G04 ================== begin FILE IDENTIFICATION RECORD ==================*
G04 Layout Name:  DAT6MTH3AD0_t6m_cm_d_brd_103112_274.brd*
G04 Film Name:    top.art*
G04 File Format:  Gerber RS274X*
G04 File Origin:  Cadence Allegro 16.3-S048*
G04 Origin Date:  Tue Nov 26 10:18:27 2013*
G04 *
G04 Layer:  VIA CLASS/TOP*
G04 Layer:  PIN/TOP*
G04 Layer:  MANUFACTURING/PHOTOPLOT_OUTLINE*
G04 Layer:  ETCH/TOP*
G04 Layer:  DRAWING FORMAT/TITLE_BLOCK*
G04 Layer:  DRAWING FORMAT/TITLE_DATA_TOP*
G04 *
G04 Offset:    (0.00 0.00)*
G04 Mirror:    No*
G04 Mode:      Positive*
G04 Rotation:  0*
G04 FullContactRelief:  No*
G04 UndefLineWidth:     6.00*
G04 ================== end FILE IDENTIFICATION RECORD ====================*
%FSLAX25Y25*MOIN*%
%IR0*IPPOS*OFA0.00000B0.00000*MIA0B0*SFA1.00000B1.00000*%
%ADD28O,.04X.135*%
%ADD109R,.02X.004*%
%ADD176R,.126X.04*%
%ADD38R,.03X.126*%
%ADD127R,.04X.109*%
%AMMACRO126*
4,1,8,-.02,.005,
.002,.005,
.002,.01,
.02,.01,
.02,-.01,
.002,-.01,
.002,-.005,
-.02,-.005,
-.02,.005,
0.0*
%
%ADD126MACRO126*%
%AMMACRO68*
4,1,28,.04488,-.04823,
.02854,-.04823,
.02854,-.06319,
.01162,-.06319,
.01162,-.04823,
-.03307,-.04823,
-.03307,-.04626,
-.04488,-.04626,
-.04488,-.03051,
-.03307,-.03051,
-.03307,-.02067,
-.04488,-.02067,
-.04488,-.00492,
-.03307,-.00492,
-.03307,.00492,
-.04488,.00492,
-.04488,.02067,
-.03307,.02067,
-.03307,.03051,
-.04488,.03051,
-.04488,.04626,
-.03307,.04626,
-.03307,.04823,
.01162,.04823,
.01162,.06319,
.02854,.06319,
.02854,.04823,
.04488,.04823,
.04488,-.04823,
0.0*
%
%ADD68MACRO68*%
%AMMACRO58*
4,1,8,.005,.02,
.005,-.002,
.01,-.002,
.01,-.02,
-.01,-.02,
-.01,-.002,
-.005,-.002,
-.005,.02,
.005,.02,
0.0*
%
%ADD58MACRO58*%
%ADD11C,.01*%
%ADD182R,.04X.007*%
%AMMACRO113*
4,1,28,-.04823,-.04488,
-.04823,-.02854,
-.06319,-.02854,
-.06319,-.01162,
-.04823,-.01162,
-.04823,.03307,
-.04626,.03307,
-.04626,.04488,
-.03051,.04488,
-.03051,.03307,
-.02067,.03307,
-.02067,.04488,
-.00492,.04488,
-.00492,.03307,
.00492,.03307,
.00492,.04488,
.02067,.04488,
.02067,.03307,
.03051,.03307,
.03051,.04488,
.04626,.04488,
.04626,.03307,
.04823,.03307,
.04823,-.01162,
.06319,-.01162,
.06319,-.02854,
.04823,-.02854,
.04823,-.04488,
-.04823,-.04488,
0.0*
%
%ADD113MACRO113*%
%ADD12R,.008X.012*%
%ADD10C,.02*%
%AMMACRO192*
21,1,.016,.0041,0.0,0.0,45.*%
%ADD192MACRO192*%
%ADD186O,.119X.063*%
%ADD181R,.007X.04*%
%ADD119R,.005X.016*%
%ADD111R,.111X.095*%
%ADD105C,.03*%
%ADD93C,.012*%
%ADD51R,.0041X.016*%
%ADD41R,.048X.13*%
%ADD37R,.03X.166*%
%ADD195O,.063X.119*%
%ADD175R,.0042X.016*%
%ADD157R,.06X.007*%
%ADD141R,.135X.072*%
%ADD118R,.016X.005*%
%AMMACRO77*
4,1,8,-.09055,-.09252,
-.0315,-.09252,
-.0315,-.08268,
.09055,-.08268,
.09055,.08268,
-.0315,.08268,
-.0315,.09252,
-.09055,.09252,
-.09055,-.09252,
0.0*
%
%ADD77MACRO77*%
%ADD65R,.016X.0041*%
%ADD33R,.095X.111*%
%ADD160R,.007X.06*%
%ADD149R,.032X.166*%
%ADD110R,.016X.0042*%
%ADD169R,.044X.007*%
%ADD159R,.035X.007*%
%ADD128C,.042*%
%ADD107C,.015*%
%ADD17C,.06*%
%ADD173C,.052*%
%ADD168R,.007X.044*%
%ADD167C,.061*%
%ADD162R,.007X.035*%
%AMMACRO151*
4,1,8,.005,.037,
.005,-.005,
.014,-.005,
.014,-.037,
-.014,-.037,
-.014,-.005,
-.005,-.005,
-.005,.037,
.005,.037,
0.0*
%
%ADD151MACRO151*%
%AMMACRO147*
4,1,8,-.037,.005,
.005,.005,
.005,.014,
.037,.014,
.037,-.014,
.005,-.014,
.005,-.005,
-.037,-.005,
-.037,.005,
0.0*
%
%ADD147MACRO147*%
%ADD91C,.016*%
%ADD72R,.036X.007*%
%ADD64R,.105X.069*%
%ADD73R,.007X.036*%
%ADD67R,.069X.105*%
%ADD63R,.15X.079*%
%ADD198R,.079X.15*%
%ADD183R,.047X.007*%
%ADD139R,.038X.007*%
%ADD26C,.045*%
%ADD180R,.007X.047*%
%ADD144R,.007X.038*%
%ADD134C,.046*%
%ADD125R,.055X.009*%
%ADD81C,.0145*%
%ADD55R,.13X.0848*%
%ADD172C,.047*%
%ADD124R,.009X.055*%
%ADD100R,.0848X.13*%
%ADD75C,.065*%
%ADD161C,.066*%
%ADD150R,.128X.069*%
%ADD117R,.032X.032*%
%ADD43C,.039*%
%ADD194C,.058*%
%ADD178R,.042X.042*%
%ADD177C,.076*%
%ADD137R,.024X.024*%
%ADD82C,.0193*%
%ADD16R,.06X.06*%
%ADD174R,.052X.052*%
%ADD166R,.061X.061*%
%ADD53C,.068*%
%ADD29C,.059*%
%ADD19C,.077*%
%AMMACRO88*
4,1,17,-.03445,.01132,
-.03445,-.01132,
.03445,-.01132,
.03445,.01132,
.01673,.01132,
.01673,.00709,
.01673,.00423,
.00886,.00423,
.00886,.00709,
.00886,.01132,
-.00886,.01132,
-.00886,.00709,
-.00886,.00423,
-.01673,.00423,
-.01673,.00709,
-.01673,.01132,
-.01675,.01132,
-.03445,.01132,
0.0*
%
%ADD88MACRO88*%
%ADD74R,.071X.071*%
%ADD30R,.045X.045*%
%ADD158R,.064X.064*%
%ADD102R,.083X.083*%
%ADD46R,.065X.065*%
%ADD165R,.066X.066*%
%ADD196R,.058X.058*%
%ADD95R,.067X.067*%
%ADD52R,.068X.068*%
%ADD31R,.077X.077*%
%ADD85R,.087X.087*%
%ADD142R,.02X.01*%
%ADD97R,.033X.01*%
%ADD80O,.0135X.01*%
%ADD76R,.02X.014*%
%ADD138R,.041X.03*%
%ADD112R,.014X.02*%
%ADD101O,.01X.0135*%
%ADD96R,.01X.033*%
%ADD133R,.02X.016*%
%ADD94O,.0135X.011*%
%ADD92O,.011X.0135*%
%ADD40R,.05X.04*%
%ADD155R,.071X.011*%
%AMMACRO116*
4,1,28,-.04488,.04823,
-.02854,.04823,
-.02854,.06319,
-.01162,.06319,
-.01162,.04823,
.03307,.04823,
.03307,.04626,
.04488,.04626,
.04488,.03051,
.03307,.03051,
.03307,.02067,
.04488,.02067,
.04488,.00492,
.03307,.00492,
.03307,-.00492,
.04488,-.00492,
.04488,-.02067,
.03307,-.02067,
.03307,-.03051,
.04488,-.03051,
.04488,-.04626,
.03307,-.04626,
.03307,-.04823,
-.01162,-.04823,
-.01162,-.06319,
-.02854,-.06319,
-.02854,-.04823,
-.04488,-.04823,
-.04488,.04823,
0.0*
%
%ADD116MACRO116*%
%AMMACRO115*
4,1,28,.04823,.04488,
.04823,.02854,
.06319,.02854,
.06319,.01162,
.04823,.01162,
.04823,-.03307,
.04626,-.03307,
.04626,-.04488,
.03051,-.04488,
.03051,-.03307,
.02067,-.03307,
.02067,-.04488,
.00492,-.04488,
.00492,-.03307,
-.00492,-.03307,
-.00492,-.04488,
-.02067,-.04488,
-.02067,-.03307,
-.03051,-.03307,
-.03051,-.04488,
-.04626,-.04488,
-.04626,-.03307,
-.04823,-.03307,
-.04823,.01162,
-.06319,.01162,
-.06319,.02854,
-.04823,.02854,
-.04823,.04488,
.04823,.04488,
0.0*
%
%ADD115MACRO115*%
%ADD83R,.036X.01*%
%ADD22R,.04X.05*%
%ADD191R,.022X.024*%
%ADD156R,.011X.071*%
%ADD84R,.01X.036*%
%ADD47R,.036X.011*%
%ADD24R,.02X.018*%
%AMMACRO164*
21,1,.016,.005,0.0,0.0,135.*%
%ADD164MACRO164*%
%ADD154R,.034X.032*%
%ADD135R,.09X.011*%
%ADD130R,.061X.014*%
%ADD123R,.071X.04*%
%ADD50R,.061X.032*%
%ADD48R,.011X.036*%
%ADD45R,.022X.017*%
%ADD23R,.018X.02*%
%ADD18C,.12*%
%ADD190R,.032X.061*%
%ADD104O,.028X.015*%
%ADD87R,.017X.022*%
%ADD27R,.022X.053*%
%ADD193C,.14*%
%ADD114R,.036X.032*%
%ADD103O,.015X.028*%
%ADD98R,.046X.013*%
%ADD25R,.014X.044*%
%ADD20R,.08X.06*%
%ADD189R,.016X.052*%
%ADD188C,.15*%
%ADD185R,.036X.024*%
%ADD71R,.011X.057*%
%AMMACRO70*
4,1,8,.02,-.005,
-.002,-.005,
-.002,-.01,
-.02,-.01,
-.02,.01,
-.002,.01,
-.002,.005,
.02,.005,
.02,-.005,
0.0*
%
%ADD70MACRO70*%
%ADD42R,.032X.036*%
%ADD35R,.032X.028*%
%ADD179R,.052X.018*%
%ADD143R,.115X.166*%
%ADD132R,.028X.024*%
%ADD120R,.059X.011*%
%ADD79R,.015X.081*%
%AMMACRO78*
4,1,8,-.005,-.02,
-.005,.002,
-.01,.002,
-.01,.02,
.01,.02,
.01,.002,
.005,.002,
.005,-.02,
-.005,-.02,
0.0*
%
%ADD78MACRO78*%
%ADD61R,.017X.052*%
%ADD60C,.142*%
%ADD39R,.028X.032*%
%ADD146R,.024X.028*%
%ADD122R,.011X.059*%
%ADD106R,.018X.052*%
%ADD69R,.054X.044*%
%ADD153C,.306*%
%ADD131R,.068X.022*%
%ADD49R,.044X.054*%
%ADD36R,.062X.046*%
%ADD152R,.059X.014*%
%ADD62C,.118*%
%ADD54R,.022X.068*%
%ADD34R,.046X.062*%
%ADD148R,.044X.056*%
%ADD86R,.046X.028*%
%ADD21R,.014X.059*%
%AMMACRO140*
4,1,8,.037,-.005,
-.005,-.005,
-.005,-.014,
-.037,-.014,
-.037,.014,
-.005,.014,
-.005,.005,
.037,.005,
.037,-.005,
0.0*
%
%ADD140MACRO140*%
%ADD66R,.182X.185*%
%ADD129R,.026X.076*%
%ADD99R,.213X.213*%
%ADD187R,.071X.095*%
%ADD170R,.048X.038*%
%ADD136C,.158*%
%ADD108R,.056X.048*%
%AMMACRO56*
4,1,17,.01132,.03445,
-.01132,.03445,
-.01132,-.03445,
.01132,-.03445,
.01132,-.01673,
.00709,-.01673,
.00423,-.01673,
.00423,-.00886,
.00709,-.00886,
.01132,-.00886,
.01132,.00886,
.00709,.00886,
.00423,.00886,
.00423,.01673,
.00709,.01673,
.01132,.01673,
.01132,.01675,
.01132,.03445,
0.0*
%
%ADD56MACRO56*%
%ADD145R,.134X.134*%
%ADD121R,.038X.048*%
%ADD90R,.099X.033*%
%ADD44R,.033X.099*%
%ADD32R,.095X.056*%
%ADD184R,.244X.244*%
%ADD89R,.099X.08*%
%ADD57R,.08X.099*%
%ADD171R,.156X.156*%
%ADD163R,.228X.228*%
%ADD197R,.079X.059*%
%ADD59R,.059X.079*%
%ADD199C,.011*%
%ADD200C,.014*%
%ADD201C,.018*%
%ADD202C,.004*%
%ADD203C,.0041*%
%ADD204C,.006*%
%ADD205C,.005*%
%ADD206C,.0042*%
%ADD207C,.007*%
%ADD208C,.008*%
%ADD209C,.009*%
%ADD210C,.0045*%
%ADD211C,.0065*%
%ADD212C,.0039*%
%ADD216C,.03004*%
%ADD218C,.03006*%
%ADD217C,.03142*%
%ADD222C,.07004*%
%ADD224C,.06204*%
%ADD219C,.02256*%
%ADD214C,.08704*%
%ADD221C,.07807*%
%ADD225C,.15004*%
%ADD223R,.07102X.07102*%
%ADD213C,.15206*%
%ADD220C,.198*%
%ADD215R,.08704X.08704*%
G75*
%LPD*%
G75*
G36*
G01X-35218Y731383D02*
G03I-640J0D01*
G37*
G36*
G01X7246Y376095D02*
X10270Y379119D01*
X50230D01*
X54480Y374869D01*
Y314318D01*
X51956Y311794D01*
G02X51603Y311647I-354J353D01*
G01X11331D01*
X7246Y315732D01*
Y376095D01*
G37*
G36*
G01X11060Y405398D02*
X54611D01*
X57500Y402509D01*
Y385903D01*
X55310Y383713D01*
X11938D01*
X9400Y386251D01*
Y403738D01*
X11060Y405398D01*
G37*
G36*
G01X29225Y13950D02*
X30298Y15023D01*
X32144D01*
X32194Y14973D01*
Y10658D01*
X31770Y10234D01*
X23163D01*
X22640Y10757D01*
Y13601D01*
X22989Y13950D01*
X29225D01*
G37*
G36*
G01X55753Y449439D02*
G02X55900Y449086I-353J-354D01*
G01Y412204D01*
G02X55400Y411704I-500J0D01*
G01X36870D01*
X35510Y413064D01*
Y450024D01*
X36586Y451100D01*
X54092D01*
X55753Y449439D01*
G37*
G36*
G01X46050Y21563D02*
G03I-640J0D01*
G37*
G36*
G01X40578Y45148D02*
X52078D01*
X52398Y44828D01*
Y25248D01*
X51188Y24038D01*
X46918D01*
X45908Y25048D01*
Y38008D01*
X42438Y41478D01*
X40088D01*
X39888Y41678D01*
Y44458D01*
X40578Y45148D01*
G37*
G36*
G01X49123Y296208D02*
X50059Y297144D01*
X58749D01*
X60221Y295672D01*
Y272206D01*
X60020Y272005D01*
X52933D01*
X49123Y275815D01*
Y296208D01*
G37*
G36*
G01X42856Y467276D02*
Y468720D01*
Y474929D01*
X49360D01*
X50556D01*
X50981Y474504D01*
Y467937D01*
X53360Y465558D01*
Y461120D01*
X53021Y460781D01*
X48020D01*
X42856Y465945D01*
Y467068D01*
Y467276D01*
G37*
G36*
G01X66248Y498556D02*
X69212D01*
X69258Y498510D01*
Y487941D01*
X69081Y487764D01*
X66005D01*
X63774Y485533D01*
Y476962D01*
Y469660D01*
X62650Y468536D01*
X52921D01*
X52171Y469286D01*
Y477199D01*
Y487988D01*
Y495090D01*
X52757Y495676D01*
X65951D01*
X66014Y495739D01*
X66092Y495817D01*
X66111Y495836D01*
Y495949D01*
X66112Y495950D01*
Y498419D01*
X66248Y498556D01*
G37*
G36*
G01X43415Y495956D02*
X50404D01*
X50665Y495695D01*
Y476730D01*
X50331Y476396D01*
X42968D01*
X42708Y476656D01*
Y495249D01*
X43415Y495956D01*
G37*
G36*
G01X54379Y511658D02*
X54720D01*
X55313Y512251D01*
X58782D01*
X58908Y512125D01*
Y509928D01*
X58470Y509490D01*
X58447D01*
X54216Y505259D01*
Y497227D01*
X53994Y497005D01*
X49121D01*
X48656Y497470D01*
Y510885D01*
X49429Y511658D01*
X53159D01*
X53244Y511626D01*
G03X54294I525J1407D01*
G01X54379Y511658D01*
G37*
G36*
G01X56704Y791162D02*
X56378Y791488D01*
Y798192D01*
X57660Y799474D01*
Y815490D01*
G02X58160Y815990I500J0D01*
G01X60060D01*
G02X60560Y815490I0J-500D01*
G01Y799517D01*
X60650Y799427D01*
X61494D01*
X61610Y799543D01*
Y815667D01*
X61920Y815977D01*
X63970D01*
G02X64470Y815477I0J-500D01*
G01Y798861D01*
X65410Y797921D01*
Y793320D01*
X65786Y792944D01*
Y788088D01*
X70030Y783845D01*
Y775088D01*
X68734Y773792D01*
X59590D01*
X51018Y782364D01*
Y793767D01*
X49832Y794953D01*
Y799588D01*
X49780Y799640D01*
Y815925D01*
X49845Y815990D01*
X52010D01*
G02X52510Y815490I0J-500D01*
G01Y799607D01*
X53976Y798142D01*
Y790492D01*
X55005Y789463D01*
X55038Y789324D01*
G03X56843Y791129I1462J343D01*
G01X56704Y791162D01*
G37*
G36*
G01X60164Y25922D02*
G03I-640J0D01*
G37*
G36*
G01X55500Y16952D02*
G03I-640J0D01*
G37*
G36*
G01X80078Y284240D02*
Y273743D01*
X78206Y271871D01*
X72189D01*
X69648Y269330D01*
Y263781D01*
X69180Y263313D01*
X60222D01*
X59486Y264049D01*
Y268261D01*
X62026Y270801D01*
Y282502D01*
X65770Y286246D01*
X71433D01*
X71537Y286196D01*
G03X73199I831J1710D01*
G01X73303Y286246D01*
X75141D01*
X79790D01*
X80078Y285958D01*
Y284240D01*
G37*
G36*
G01X69912Y291930D02*
X65335D01*
X63164Y294101D01*
Y302961D01*
X64100Y303897D01*
X77072D01*
X79077Y301892D01*
Y293199D01*
X78679Y292801D01*
X70783D01*
X69912Y291930D01*
G37*
G36*
G01X100110Y450939D02*
X99300Y450129D01*
X94379D01*
X93274Y449024D01*
Y436754D01*
X93200Y436679D01*
Y422996D01*
X93790Y422406D01*
Y415936D01*
X92810Y414956D01*
X63320D01*
G02X62820Y415456I0J500D01*
G01Y462853D01*
X63230Y463263D01*
X99610D01*
G02X100110Y462763I0J-500D01*
G01Y450939D01*
G37*
G36*
G01X67387Y466363D02*
G03I-640J0D01*
G37*
G36*
G01X64690Y465689D02*
G03I-640J0D01*
G37*
G36*
G01X61823Y465314D02*
G03I-640J0D01*
G37*
G36*
G01X59470Y508533D02*
X60716D01*
X60729Y508520D01*
Y504925D01*
X60091Y504287D01*
X59701Y503897D01*
Y497339D01*
X59385Y497023D01*
X55815D01*
X55573Y497265D01*
Y502341D01*
X55609Y502378D01*
Y504672D01*
X58781Y507844D01*
X59470Y508533D01*
G37*
G36*
G01X61877Y508532D02*
X62695D01*
X62751Y508476D01*
Y505036D01*
Y504199D01*
Y503509D01*
Y502810D01*
X62736Y502795D01*
X62588Y502647D01*
Y499595D01*
X62249Y499255D01*
X61207D01*
X60854Y499608D01*
Y503075D01*
X61757Y503978D01*
Y504670D01*
Y508412D01*
X61877Y508532D01*
G37*
G36*
G01X78498Y503410D02*
Y496799D01*
Y486815D01*
X79071Y486242D01*
X79302Y486011D01*
X84023D01*
X84450Y485584D01*
Y485032D01*
Y474782D01*
X83951Y474283D01*
X82850D01*
X76268D01*
X71247D01*
X70615Y474915D01*
Y495871D01*
Y499607D01*
X70504Y499718D01*
X70132Y500090D01*
X66804D01*
X66581Y500313D01*
Y504423D01*
X65670Y505334D01*
Y508161D01*
X65808Y508299D01*
X67742D01*
X70116D01*
X71560Y506855D01*
X73598Y504818D01*
X77090D01*
X78498Y503410D01*
G37*
G36*
G01X63829Y508531D02*
X64647D01*
X64703Y508475D01*
Y505035D01*
Y504888D01*
Y504488D01*
X64711Y504480D01*
X65177Y504014D01*
Y500908D01*
X65176Y500907D01*
Y499583D01*
X65054Y499461D01*
Y496770D01*
X65022Y496738D01*
X62928D01*
X62862Y496804D01*
Y496968D01*
Y497749D01*
Y498325D01*
X63709Y499172D01*
Y499617D01*
Y500046D01*
Y503977D01*
Y504669D01*
Y508411D01*
X63829Y508531D01*
G37*
G36*
G01X60082Y516090D02*
X66255D01*
X66435Y515910D01*
Y509989D01*
X66219Y509773D01*
X60226D01*
X60082Y509917D01*
Y516090D01*
G37*
G36*
G01X72267Y508384D02*
X71267Y509384D01*
X67636D01*
X67584Y509436D01*
Y509574D01*
Y510427D01*
X67599Y510442D01*
X73125D01*
X76231D01*
X77142Y509531D01*
Y507156D01*
Y506531D01*
X76862Y506251D01*
X74400D01*
X73755Y506896D01*
X72267Y508384D01*
G37*
G36*
G01X62634Y580554D02*
X70000Y587920D01*
X74270D01*
X75302Y586888D01*
Y582290D01*
X72768Y579756D01*
Y550748D01*
Y547064D01*
X71121Y545417D01*
X63320D01*
X62634Y546103D01*
Y555676D01*
Y580554D01*
G37*
G36*
G01X63940Y621755D02*
G03I-640J0D01*
G37*
G36*
G01X64130Y630693D02*
G03I-640J0D01*
G37*
G36*
G01X122047Y85630D02*
G02X74805I-23621J197D01*
G01X74804Y105511D01*
G02X122048I23622J1D01*
G01X122047Y85630D01*
G37*
G36*
G01X73530Y154349D02*
G03I-640J0D01*
G37*
G36*
G01X78830Y214642D02*
G03I-640J0D01*
G37*
G36*
G01X81850Y261337D02*
G03I-640J0D01*
G37*
G36*
G01X85220Y284614D02*
X84390Y283784D01*
X81759D01*
X81190Y284353D01*
Y286482D01*
X80209Y287463D01*
X76047D01*
X75390Y288120D01*
Y290705D01*
X76081Y291396D01*
X84513D01*
X85220Y290689D01*
Y284614D01*
G37*
G36*
G01X85639Y487177D02*
X79975D01*
X79563Y487589D01*
Y489016D01*
X79545Y489034D01*
Y495506D01*
X79691Y495652D01*
X87474D01*
X89303D01*
X100078D01*
X101809D01*
X103128D01*
X104052Y494728D01*
Y493409D01*
Y476892D01*
X102898Y475738D01*
X99232D01*
X86917D01*
X86298Y476357D01*
Y486518D01*
X85639Y487177D01*
G37*
G36*
G01X79854Y496663D02*
X79655Y496862D01*
Y499923D01*
X85258D01*
X86773D01*
X87312Y499384D01*
Y497209D01*
X86766Y496663D01*
X79854D01*
G37*
G36*
G01X112409Y521697D02*
X88857D01*
X85388D01*
X84820Y522265D01*
Y524245D01*
X82810Y526255D01*
X76540D01*
X75620Y527175D01*
Y545710D01*
X76520Y546610D01*
X80599D01*
X86793D01*
X87637Y545766D01*
Y532389D01*
X92310Y527716D01*
X104017D01*
X107107Y530806D01*
Y545156D01*
X108609Y546658D01*
X113441D01*
X113450Y546649D01*
X121570D01*
X122410Y545809D01*
Y526288D01*
X121618Y525496D01*
X116208D01*
X115224Y524512D01*
X112409Y521697D01*
G37*
G36*
G01X75468Y550407D02*
Y556389D01*
X75371Y556487D01*
Y579476D01*
X77576Y581681D01*
Y587030D01*
X81282Y590736D01*
X91510D01*
X93434Y588812D01*
Y585059D01*
X92630Y584255D01*
Y564634D01*
X91448Y563452D01*
X87669Y559673D01*
Y548530D01*
X86960Y547821D01*
X76142D01*
X75468Y548495D01*
Y550407D01*
G37*
G36*
G01X73770Y601599D02*
G03I-640J0D01*
G37*
G36*
G01X73820Y611184D02*
G03I-640J0D01*
G37*
G36*
G01X122047Y699803D02*
G02X74805I-23621J197D01*
G01X74804Y719684D01*
G02X122048I23622J1D01*
G01X122047Y699803D01*
G37*
G36*
G01X94487Y446978D02*
X95450Y447941D01*
X107000D01*
G02X107500Y447441I0J-500D01*
G01Y418912D01*
X103850Y415262D01*
X95360D01*
G02X94860Y415762I0J500D01*
G01Y424656D01*
X94487Y425029D01*
Y446978D01*
G37*
G36*
G01X108357Y494385D02*
X105062Y497680D01*
X101177D01*
X100630Y498227D01*
Y505820D01*
X102020Y507210D01*
X112567D01*
X114790Y504987D01*
Y503078D01*
X115338Y502530D01*
X119990D01*
X126070D01*
G02X126570Y502030I0J-500D01*
G01Y496532D01*
G02X126070Y496032I-500J0D01*
G01X123790D01*
X123631Y495874D01*
X117731D01*
X117700Y495842D01*
X115574D01*
X114117Y494385D01*
X108357D01*
G37*
G36*
G01X87366Y501997D02*
G03I-640J0D01*
G37*
G36*
G01X92928Y529026D02*
X89279Y532676D01*
Y558668D01*
X94018Y563407D01*
Y579406D01*
X94440Y579828D01*
X99742D01*
X99756Y579814D01*
X100835D01*
X101700Y578949D01*
Y570837D01*
X102802Y569734D01*
X108504D01*
X109280Y568958D01*
Y567605D01*
X110914Y565970D01*
X121737D01*
X122310Y565397D01*
Y565050D01*
Y563847D01*
Y548741D01*
X121390Y547821D01*
X107798D01*
X106076Y546099D01*
Y531551D01*
X103551Y529026D01*
X92928D01*
G37*
G36*
G01X111602Y581050D02*
X109073Y578520D01*
Y572081D01*
G02X108573Y571581I-500J0D01*
G01X103518D01*
X103128Y571971D01*
Y579771D01*
X101675Y581224D01*
X95860D01*
X95140Y581944D01*
Y594460D01*
X98030Y597350D01*
X111729D01*
X112629Y598250D01*
X134691D01*
X135005Y597937D01*
G03X136838Y597395I1415J1415D01*
G02X137296Y597259I104J-489D01*
G01X138844Y595711D01*
X153055D01*
X153121Y595692D01*
G03X153304Y595653I404J1446D01*
G03X153527Y595636I225J1485D01*
G01X157550D01*
G03X157773Y595653I-2J1502D01*
G03X157956Y595692I-221J1485D01*
G01X158022Y595711D01*
X159225D01*
X159264Y595672D01*
Y594973D01*
X158293Y594002D01*
Y591564D01*
X158282Y591554D01*
Y588412D01*
X154160Y584290D01*
Y581686D01*
X153524Y581050D01*
X111602D01*
G37*
G36*
G01X92850Y620649D02*
X106780D01*
X107331Y620098D01*
Y612943D01*
X106610Y612222D01*
X93119D01*
X91810Y613531D01*
Y619609D01*
X92850Y620649D01*
G37*
G36*
G01X93380Y650519D02*
X106732D01*
X106840Y650411D01*
Y642314D01*
X92670D01*
X92090Y642894D01*
Y649229D01*
X93380Y650519D01*
G37*
G36*
G01X107545Y399714D02*
X107037Y400222D01*
Y402074D01*
X107154Y402191D01*
X116630D01*
X117347Y402908D01*
X120564D01*
X120634Y402838D01*
Y400214D01*
G02X120134Y399714I-500J0D01*
G01X114758D01*
X114636Y399791D01*
G03X112604I-1016J-1607D01*
G01X112482Y399714D01*
X107545D01*
G37*
G36*
G01X112919Y408800D02*
X120692D01*
X120796Y408696D01*
Y404072D01*
X120783Y404059D01*
X112790D01*
X112347Y404502D01*
Y408228D01*
X112919Y408800D01*
G37*
G36*
G01X127026Y422320D02*
G03X127197Y421511I2002J1D01*
G01X127240Y421414D01*
Y419845D01*
X127860Y419225D01*
X129858D01*
X129904Y419179D01*
Y413045D01*
X128377Y411518D01*
Y399979D01*
X129788Y398568D01*
X129993D01*
X130126Y398434D01*
X134776D01*
X135930Y397280D01*
Y393532D01*
X135902Y393504D01*
X121588D01*
X119780Y395312D01*
Y397223D01*
X121839Y399282D01*
Y412161D01*
X121320Y412680D01*
X116945D01*
X116070Y413555D01*
Y424157D01*
X116522Y424609D01*
X126660D01*
X127026Y424242D01*
Y422320D01*
G37*
G36*
G01X115946Y482006D02*
X114086Y483866D01*
Y484716D01*
Y488576D01*
X116326Y490816D01*
X117485D01*
X118105Y491436D01*
Y494831D01*
X118146Y494872D01*
X121120D01*
X122246D01*
X122978D01*
X122988Y494862D01*
Y482558D01*
X122436Y482006D01*
X115946D01*
G37*
G36*
G01X111468Y566981D02*
X110628Y567821D01*
Y577441D01*
X112368Y579181D01*
X121598D01*
X122298Y578481D01*
Y567921D01*
X121358Y566981D01*
X111468D01*
G37*
G36*
G01X143919Y155569D02*
X145467Y154291D01*
G02X145649Y153906I-318J-386D01*
G01Y147291D01*
X145743Y147197D01*
Y132496D01*
Y128663D01*
X144300Y127220D01*
X129719D01*
X126760Y130179D01*
Y135211D01*
Y154285D01*
X127503Y155028D01*
X137912D01*
X138453Y155569D01*
X143919D01*
G37*
G36*
G01X127100Y250160D02*
G03I-640J0D01*
G37*
G36*
G01X127210Y256194D02*
G03I-640J0D01*
G37*
G36*
G01X130300Y279890D02*
G03I-640J0D01*
G37*
G36*
G01X130950Y269174D02*
G03I-640J0D01*
G37*
G36*
G01X123800Y287060D02*
G03I-640J0D01*
G37*
G36*
G01X130250Y287115D02*
G03I-640J0D01*
G37*
G36*
G01X130541Y399436D02*
X129507Y400470D01*
Y406763D01*
X129555Y406811D01*
X129586Y406842D01*
X136455D01*
X137866Y405431D01*
X143282D01*
X143652Y405801D01*
Y421831D01*
X143674Y421903D01*
G03Y422789I-1435J443D01*
G01X143652Y422861D01*
Y425114D01*
X140910Y427856D01*
X132998D01*
X126860D01*
X125740Y428976D01*
Y454830D01*
X126224Y455314D01*
X131601D01*
X132067Y455780D01*
X139775D01*
X140454Y455101D01*
Y443157D01*
X144444Y439167D01*
X149941D01*
X152350Y436758D01*
Y402401D01*
X149385Y399436D01*
X148160D01*
X130541D01*
G37*
G36*
G01X129442Y408925D02*
X135390D01*
X136409Y409944D01*
X139580D01*
X140089Y410453D01*
Y411772D01*
X140830Y412513D01*
X142172D01*
X142589Y412096D01*
Y406623D01*
X142494Y406528D01*
X138367D01*
X137011Y407884D01*
X129582D01*
X129442Y408024D01*
Y408925D01*
G37*
G36*
G01X121925Y470292D02*
X116975D01*
X116760Y470507D01*
Y476092D01*
Y477894D01*
X118380Y479514D01*
X122025D01*
X123185Y478354D01*
Y471552D01*
X121925Y470292D01*
G37*
G36*
G01X128705Y486131D02*
Y489525D01*
X126797Y491433D01*
Y494888D01*
X126654Y495031D01*
X124205D01*
X124005Y494831D01*
Y487031D01*
X125105Y485931D01*
X128505D01*
X128705Y486131D01*
G37*
G36*
G01X129720Y492829D02*
X131070Y491479D01*
X134410D01*
X134977Y492046D01*
Y499814D01*
X134677Y500114D01*
X129792D01*
X129416Y499738D01*
Y493133D01*
X129720Y492829D01*
G37*
G36*
G01X132212Y524276D02*
X131345D01*
X129608D01*
Y521145D01*
X128626Y520163D01*
X125941D01*
X124624Y518846D01*
Y512350D01*
X123805Y511531D01*
X120705D01*
X120304Y511130D01*
Y507228D01*
X120157Y507081D01*
Y503779D01*
X120405Y503531D01*
X121205D01*
Y503552D01*
X121226Y503531D01*
X122105D01*
X123105D01*
X124005D01*
X126405D01*
X127902D01*
X128512Y502921D01*
X135502D01*
Y508609D01*
X134713Y509398D01*
Y512804D01*
Y523241D01*
X133678Y524276D01*
X132212D01*
G37*
G36*
G01X119542Y736342D02*
X118875Y737009D01*
Y742750D01*
X119644Y743519D01*
X125589D01*
X126051Y743057D01*
Y736942D01*
G02X125551Y736442I-500J0D01*
G01X121734D01*
X121634Y736342D01*
X119542D01*
G37*
G36*
G01X133408Y724816D02*
X133826Y724399D01*
Y724076D01*
X133420Y723670D01*
X131594D01*
X131229Y724035D01*
Y731203D01*
X131461Y731435D01*
X132283D01*
G02X133177Y729989I-1J-1000D01*
G03X133340Y728024I1702J-848D01*
G02X133313Y727403I-405J-293D01*
G03X133408Y724816I1440J-1242D01*
G37*
G36*
G01X125450Y734660D02*
X127290Y736500D01*
Y739228D01*
X128015Y739953D01*
X132030D01*
X132090Y739893D01*
Y735688D01*
X130090Y733688D01*
Y724092D01*
X129418Y723420D01*
X127323D01*
X126480Y724263D01*
Y724836D01*
X126576D01*
Y725834D01*
X126578D01*
Y729134D01*
X126480D01*
Y729635D01*
X125850Y730265D01*
X122731D01*
X122430Y730566D01*
Y734160D01*
G02X122930Y734660I500J0D01*
G01X125450D01*
G37*
G36*
G01X135388Y33172D02*
X135625Y33409D01*
X144366D01*
X145525D01*
X145823Y33111D01*
Y30804D01*
X144706Y29687D01*
X144196Y29177D01*
X141581D01*
X140237D01*
X138930Y27870D01*
X138272D01*
X136231D01*
X135388Y28713D01*
Y29669D01*
Y29670D01*
Y32685D01*
Y33172D01*
G37*
G36*
G01X146948Y24872D02*
Y19636D01*
G02X146448Y19136I-500J0D01*
G01X145429D01*
X145105Y19460D01*
Y24872D01*
G02X145605Y25372I500J0D01*
G01X146448D01*
G02X146948Y24872I0J-500D01*
G37*
G36*
G01X153315Y44063D02*
X153446Y43933D01*
Y42877D01*
X153346Y42778D01*
Y41527D01*
X153362Y41512D01*
Y39866D01*
X153316Y39582D01*
Y38308D01*
X153306Y38040D01*
Y37596D01*
G02X152806Y37096I-500J0D01*
G01X146597D01*
X146455Y37238D01*
Y38197D01*
X146526Y38268D01*
Y39566D01*
X146484Y39608D01*
Y41438D01*
X146506Y41459D01*
Y42756D01*
X146455Y42806D01*
Y43850D01*
X146668Y44063D01*
X153315D01*
G37*
G36*
G01X137958Y44427D02*
X139950Y42435D01*
X140028Y42357D01*
X141184D01*
X141185Y42356D01*
X143779D01*
G03X143833Y42357I2J1351D01*
G01X144982D01*
G02X145482Y41857I0J-500D01*
G01Y40310D01*
X145420Y40247D01*
X145482Y40185D01*
Y39248D01*
G02X144982Y38748I-500J0D01*
G01X140102D01*
X139059Y37705D01*
X136817D01*
X136328Y38194D01*
Y44446D01*
X136456Y44574D01*
X137605D01*
G02X137958Y44427I-1J-500D01*
G37*
G36*
G01X144837Y309778D02*
X150752D01*
X155976D01*
X157300Y308454D01*
Y296379D01*
X156088Y295167D01*
X150357D01*
X144262D01*
X143574Y295855D01*
Y299713D01*
Y308515D01*
X144837Y309778D01*
G37*
G36*
G01X142949Y443610D02*
X142696Y443863D01*
Y451180D01*
X142870Y451355D01*
X158028D01*
X158135Y451248D01*
Y448783D01*
Y444491D01*
X157254Y443610D01*
X152168D01*
X151990D01*
G03X151101Y443831I-890J-1681D01*
G01X147820D01*
G03X147024Y443656I1J-1902D01*
G01X146924Y443610D01*
X142949D01*
G37*
G36*
G01X145927Y464332D02*
X153728D01*
X154389Y463671D01*
Y453306D01*
X153807Y452724D01*
X143014D01*
X142742Y452996D01*
Y455625D01*
X141189Y457178D01*
X136552D01*
X136086Y457644D01*
Y464166D01*
X136252Y464332D01*
X143597D01*
X145927D01*
G37*
G36*
G01X135991Y517477D02*
Y512311D01*
X136291Y512011D01*
X141051D01*
Y517477D01*
X135991D01*
G37*
G36*
G01X146945Y671206D02*
X146542Y671610D01*
Y671998D01*
X146286Y672254D01*
Y681719D01*
X147055Y682488D01*
X149049D01*
X150135Y683574D01*
Y690863D01*
X150961Y691689D01*
X153163D01*
X153325Y691851D01*
X161616D01*
X162790Y693025D01*
Y706544D01*
G02X163290Y707044I500J0D01*
G01X170389D01*
X171463Y708118D01*
Y710015D01*
X171477Y710072D01*
G03X171508Y710231I-1947J462D01*
G03X171532Y710557I-1977J309D01*
G01Y710561D01*
G02X172032Y711061I500J0D01*
G01X173330D01*
X173407Y710984D01*
Y697253D01*
X172702Y696548D01*
Y692609D01*
X171090Y690997D01*
Y686723D01*
X167063Y682696D01*
Y672872D01*
X166189Y671998D01*
X164890D01*
X163818Y670926D01*
X163310D01*
Y670418D01*
X161530Y668638D01*
Y665442D01*
X152905Y656817D01*
X139819D01*
X138600Y658036D01*
Y663987D01*
X143198Y668585D01*
G02X143905I354J-353D01*
G01X145287Y667204D01*
X148200D01*
G03Y671206I0J2001D01*
G01X146945D01*
G37*
G36*
G01X135090Y682978D02*
G03I-640J0D01*
G37*
G36*
G01X140817Y694064D02*
X140155Y694726D01*
Y696239D01*
X140173Y696305D01*
G03Y697109I-1447J402D01*
G01X140155Y697175D01*
Y712782D01*
X140128Y712809D01*
Y719127D01*
Y720212D01*
X143790Y723874D01*
X157402D01*
X158070Y724542D01*
X166615D01*
X167294Y723863D01*
Y715334D01*
X165759Y713799D01*
X159674D01*
X158600Y712725D01*
Y694713D01*
X157951Y694064D01*
X140817D01*
G37*
G36*
G01X151900Y732406D02*
X151540Y732766D01*
X143627D01*
X140669Y729808D01*
X139630D01*
X139376Y730062D01*
Y741634D01*
X139361Y741649D01*
Y743488D01*
X139013Y743836D01*
Y745924D01*
X139046Y746010D01*
G03Y747442I-1869J716D01*
G01X139013Y747528D01*
Y753287D01*
X141160Y755434D01*
X179064D01*
X180926D01*
X183050Y753310D01*
Y749496D01*
X182968Y749414D01*
Y742085D01*
X181423Y740540D01*
Y735297D01*
X181058Y734932D01*
X170372D01*
X170135Y734695D01*
Y731681D01*
X168140Y729686D01*
X152400D01*
G02X151900Y730186I0J500D01*
G01Y732406D01*
G37*
G36*
G01X174273Y15909D02*
X191875D01*
X192201D01*
X192996Y15114D01*
Y6291D01*
X192437Y5732D01*
X183350D01*
X177556D01*
X164996D01*
X164922Y5658D01*
X162316D01*
X161339Y6635D01*
Y15275D01*
X161977Y15913D01*
X164347D01*
X174269D01*
X174273Y15909D01*
G37*
G36*
G01X168209Y31813D02*
Y34898D01*
X168255Y34944D01*
X178824D01*
X179001Y34767D01*
Y31691D01*
X181232Y29460D01*
X189803D01*
X201058D01*
X203309D01*
X204417Y28352D01*
Y20698D01*
X203618Y19899D01*
X193536D01*
X190947Y17310D01*
X176409D01*
X171752D01*
X166377D01*
X162365D01*
X161730D01*
X161163Y17877D01*
Y22177D01*
X161531Y22545D01*
X169615D01*
X171025Y23955D01*
Y24885D01*
Y25290D01*
Y31467D01*
X170792Y31700D01*
X170750Y31742D01*
X168280D01*
X168209Y31813D01*
G37*
G36*
G01X151490Y25623D02*
X152014Y25099D01*
Y18165D01*
X152003Y18113D01*
G03X151962Y17718I1860J-393D01*
G01Y16868D01*
G02X151462Y16368I-500J0D01*
G01X150452D01*
G02X149952Y16868I0J500D01*
G01Y25109D01*
X150465Y25623D01*
X151490D01*
G37*
G36*
G01X154447Y43681D02*
Y45148D01*
Y46764D01*
Y47466D01*
X155660Y48679D01*
X157872Y50891D01*
Y52167D01*
X158956Y53251D01*
Y57397D01*
X159467Y57908D01*
X160380D01*
X160893D01*
X161403Y57398D01*
Y49658D01*
X157813Y46068D01*
Y44036D01*
Y44031D01*
X157268Y43486D01*
X154642D01*
X154447Y43681D01*
G37*
G36*
G01X154318Y38732D02*
Y39207D01*
X154398Y39287D01*
X158765D01*
X159735D01*
X161341D01*
X161773D01*
X161778Y39292D01*
X162086D01*
X164749Y41955D01*
X167047Y44253D01*
X167678D01*
X179808D01*
X180701Y45146D01*
Y46477D01*
Y47434D01*
Y49668D01*
X180946Y49913D01*
X188517D01*
X190326D01*
X191332Y48907D01*
Y36725D01*
X190999Y36392D01*
X188184D01*
X168255D01*
X162406D01*
X160167Y38631D01*
X159705D01*
X159674Y38662D01*
X158735D01*
X154388D01*
X154318Y38732D01*
G37*
G36*
G01X154308Y37159D02*
Y37563D01*
X154407Y37662D01*
X157902D01*
X157917Y37646D01*
X159396D01*
X159519Y37523D01*
X160819Y36223D01*
X161600Y35442D01*
X161849Y35193D01*
X165101D01*
X165217Y35077D01*
Y34507D01*
Y31867D01*
X164581Y31231D01*
X161289D01*
X160693Y31827D01*
X160375Y32145D01*
X155431Y37089D01*
X154378D01*
X154308Y37159D01*
G37*
G36*
G01X154363Y40320D02*
Y40795D01*
X154406Y40838D01*
X159362D01*
X159399Y40875D01*
X162395Y43871D01*
X163040D01*
X163433Y43478D01*
Y42476D01*
X162995Y42038D01*
X161584Y40627D01*
X161263Y40306D01*
X157974D01*
X157956Y40288D01*
X154395D01*
X154363Y40320D01*
G37*
G36*
G01X154348Y41942D02*
Y42363D01*
X154428Y42443D01*
X157709D01*
X157829Y42563D01*
X160998Y45732D01*
X162583Y47317D01*
X169802D01*
X169973D01*
X170036Y47254D01*
Y47083D01*
Y45467D01*
X169855Y45286D01*
X162350D01*
X161339Y44275D01*
X158935Y41872D01*
X158538D01*
X154418D01*
X154348Y41942D01*
G37*
G36*
G01X151278Y51049D02*
Y56527D01*
X151703Y56952D01*
X154234D01*
Y54613D01*
Y53474D01*
X151809Y51049D01*
X151278D01*
G37*
G36*
G01X162770Y129344D02*
G03I-640J0D01*
G37*
G36*
G01X158329Y321032D02*
X156813Y322548D01*
Y327163D01*
X158612Y328962D01*
X164107D01*
X165099Y327970D01*
X165107D01*
X165399Y327678D01*
Y323103D01*
X164850Y322554D01*
Y321060D01*
X164822Y321032D01*
X158329D01*
G37*
G36*
G01X151164Y382808D02*
G03I-640J0D01*
G37*
G36*
G01X162280Y403286D02*
G03I-640J0D01*
G37*
G36*
G01X171109Y650895D02*
X168046Y653958D01*
Y658284D01*
X158710D01*
G02X158210Y658784I0J500D01*
G01Y659636D01*
G02X158710Y660136I500J0D01*
G01X184230D01*
G02X184730Y659636I0J-500D01*
G01Y658784D01*
G02X184230Y658284I-500J0D01*
G01X174880D01*
Y653958D01*
X171817Y650895D01*
G02X171109I-354J353D01*
G37*
G36*
G01X168230Y30646D02*
X169992D01*
Y26528D01*
X169387Y25923D01*
X167525D01*
X164584D01*
X164358Y26149D01*
Y28785D01*
X164863Y29290D01*
X166874D01*
X168230Y30646D01*
G37*
G36*
G01X178277Y45297D02*
X171239D01*
X171057Y45478D01*
Y53120D01*
Y54949D01*
Y63700D01*
X174980Y67623D01*
X188329D01*
X190209D01*
X190401Y67431D01*
Y51595D01*
X190165Y51359D01*
X188574D01*
X180121D01*
X178830Y50068D01*
Y45850D01*
X178277Y45297D01*
G37*
G36*
G01X177850Y97657D02*
G03I-640J0D01*
G37*
G36*
G01X168591Y380551D02*
G03I-640J0D01*
G37*
G36*
G01X175930Y389582D02*
G03I-640J0D01*
G37*
G36*
G01X175140Y383383D02*
G03I-640J0D01*
G37*
G36*
G01X177213Y434559D02*
Y430686D01*
Y429773D01*
X177344Y429642D01*
X177352D01*
X180872D01*
X181059Y429455D01*
X181109Y429405D01*
Y425577D01*
X181205Y425481D01*
X181615Y425071D01*
Y421331D01*
X182394Y420552D01*
X186062D01*
X186134Y420624D01*
Y424858D01*
X186089Y424903D01*
Y426623D01*
X183887Y428825D01*
X183877Y428835D01*
Y429811D01*
Y436203D01*
X183873Y436207D01*
X177267D01*
X177213Y436153D01*
Y434559D01*
G37*
G36*
G01X179935Y437244D02*
X179979Y437288D01*
Y448978D01*
X179635Y449322D01*
X175511D01*
X175153Y448965D01*
Y442777D01*
X175253Y442677D01*
X176019D01*
X177579D01*
X177823Y442433D01*
X179084Y441172D01*
Y440565D01*
X179120Y440529D01*
Y437286D01*
X179162Y437244D01*
X179935D01*
G37*
G36*
G01X170182Y449295D02*
X173779D01*
X174030Y449044D01*
Y443490D01*
X173951Y443411D01*
X170381D01*
X169908D01*
X169691Y443628D01*
Y449234D01*
X169752Y449295D01*
X170182D01*
G37*
G36*
G01X181130Y437249D02*
X183867D01*
X183934Y437316D01*
Y439872D01*
Y440008D01*
X186231Y442305D01*
X186843Y442917D01*
Y443952D01*
Y446333D01*
Y453605D01*
X186824Y453624D01*
X185533D01*
X181130D01*
X177651D01*
X176809D01*
X176673Y453488D01*
Y450738D01*
X176792Y450619D01*
X176845Y450566D01*
X177268D01*
X180787D01*
X181130Y450223D01*
Y444666D01*
Y437249D01*
G37*
G36*
G01X169933Y562358D02*
G03I-640J0D01*
G37*
G36*
G01X165378Y620369D02*
X185504D01*
G02X186004Y619869I0J-500D01*
G01Y599962D01*
G02X185504Y599462I-500J0D01*
G01X165378D01*
G02X164878Y599962I0J500D01*
G01Y619869D01*
G02X165378Y620369I500J0D01*
G37*
G36*
G01X176053Y695174D02*
Y691750D01*
X176996Y690807D01*
X180337D01*
X181233Y689911D01*
Y687404D01*
X179872Y686043D01*
X172995D01*
Y690575D01*
X174070Y691650D01*
Y694969D01*
X174275Y695174D01*
X176053D01*
G37*
G36*
G01X194450Y6788D02*
X194036Y7202D01*
Y16668D01*
X194637Y17269D01*
X205194D01*
X205703Y16760D01*
Y6862D01*
X205629Y6788D01*
X194450D01*
G37*
G36*
G01X184810Y95213D02*
G03I-640J0D01*
G37*
G36*
G01X186700Y100103D02*
G03I-640J0D01*
G37*
G36*
G01X189484Y232789D02*
G03I-640J0D01*
G37*
G36*
G01X181142Y233307D02*
G03I-632J0D01*
G37*
G36*
G01X189887Y243016D02*
G03I-640J0D01*
G37*
G36*
G01X186778Y270787D02*
G03I-660J0D01*
G37*
G36*
G01X193277Y397362D02*
X193338Y397423D01*
X201088D01*
X201419Y397092D01*
Y389551D01*
X201179Y389311D01*
X193547D01*
X193277Y389581D01*
Y397362D01*
G37*
G36*
G01X204930Y420682D02*
X204799Y420551D01*
X191646D01*
X190752Y421445D01*
X187857D01*
X187237Y422065D01*
Y427392D01*
X184897Y429732D01*
Y434336D01*
X185019Y434458D01*
X204416D01*
X204930Y433944D01*
Y420682D01*
G37*
G36*
G01X186707Y440912D02*
X193851D01*
X194142Y440621D01*
Y436469D01*
X193164Y435491D01*
X185125D01*
X185030Y435586D01*
Y439235D01*
X186707Y440912D01*
G37*
G36*
G01X188374Y453941D02*
X198212D01*
X198844D01*
X199249Y453536D01*
X200870Y451915D01*
Y444312D01*
X199657Y443099D01*
X197789D01*
X188215D01*
Y453782D01*
X188374Y453941D01*
G37*
G36*
G01X195148Y704476D02*
G03I-640J0D01*
G37*
G36*
G01X210710Y25920D02*
X253252D01*
X254270Y24902D01*
Y7737D01*
X252630Y6097D01*
X210087D01*
X209140Y7044D01*
Y24350D01*
X210710Y25920D01*
G37*
G36*
G01X264720Y55731D02*
X261190Y52201D01*
Y40260D01*
X260370Y39440D01*
X258870D01*
X257620Y38190D01*
Y33479D01*
X253540Y29399D01*
X252138Y27997D01*
X210825D01*
X202950Y35872D01*
Y51851D01*
X205188Y54089D01*
X217328D01*
X221560Y58321D01*
X255486D01*
X255498Y58308D01*
Y58371D01*
X257070Y59943D01*
Y73463D01*
X257570Y73963D01*
X262680D01*
X265451Y76734D01*
X265830Y77113D01*
X327054D01*
X327830Y76337D01*
Y70988D01*
X326980Y70138D01*
X265847D01*
X264720Y69011D01*
Y55731D01*
G37*
G36*
G01X196640Y95568D02*
G03I-640J0D01*
G37*
G36*
G01X196650Y125188D02*
G03I-640J0D01*
G37*
G36*
G01X264305Y267347D02*
G03X264289Y268957I-1276J792D01*
G03X264218Y269057I-1259J-819D01*
G02Y270221I813J582D01*
G03X264407Y270542I-1190J917D01*
G03X263380Y272599I-1378J597D01*
G01X263243Y272632D01*
X262747Y273128D01*
X262329Y273547D01*
G03X260629Y271847I-850J-850D01*
G01X261372Y271104D01*
X261533Y270944D01*
X261565Y270803D01*
G03X261677Y270484I1464J335D01*
G03X261840Y270221I1352J656D01*
G02Y269057I-813J-582D01*
G03X261724Y268883I1189J-918D01*
G03X261571Y268501I1305J-744D01*
G01Y268500D01*
X261537Y268365D01*
X260979Y267807D01*
X260912Y267772D01*
G03X260515Y267436I568J-1074D01*
G01X260495Y267409D01*
X260472Y267386D01*
G02X259764I-354J353D01*
G01X259643Y267507D01*
G02X259611Y268887I707J707D01*
G03X259832Y269234I-888J809D01*
G03X259870Y269338I-1108J464D01*
G03X259906Y269489I-1148J354D01*
G03X259924Y269697I-1183J207D01*
G01Y270225D01*
X258748Y271401D01*
X258715Y271540D01*
G03X258481Y272062I-1462J-342D01*
G03X258400Y272167I-1229J-864D01*
G03X258330Y272244I-1146J-971D01*
G03X256251Y272316I-1077J-1046D01*
G03X256126Y272190I1002J-1119D01*
G03X255888Y270569I1127J-993D01*
G03X256064Y270279I1364J629D01*
G02Y269115I-813J-582D01*
G03X255993Y269015I1188J-919D01*
G03X256909Y266735I1260J-818D01*
G01X257049Y266702D01*
X257169Y266581D01*
X257727Y266023D01*
X257764Y265973D01*
X257781Y265951D01*
G03X257869Y265852I941J748D01*
G03X257919Y265804I857J842D01*
G03X257951Y265776I807J890D01*
G02X258128Y265394I-323J-382D01*
G02X257628Y264894I-500J0D01*
G01X257508D01*
X256720Y264105D01*
X256580Y264073D01*
G03X255928Y261477I336J-1464D01*
G02X256153Y260253I-657J-753D01*
G03X255825Y258662I1100J-1056D01*
G02X255655Y258085I-468J-176D01*
G03X255652Y258083I830J-1249D01*
G03X255598Y258040I908J-1196D01*
G03X255135Y257378I954J-1160D01*
G02X253494Y257027I-934J356D01*
G01X252117Y258404D01*
X252051Y258678D01*
X252094Y258812D01*
G03X252122Y258913I-1191J385D01*
G03X252135Y258976I-1219J284D01*
G03X252137Y258991I-1238J173D01*
G03X252154Y259197I-1234J206D01*
G01Y259745D01*
X251952Y259948D01*
X251866Y260034D01*
G02X251828Y261354I732J682D01*
G03X251839Y261366I-917J851D01*
G03X251940Y261497I-938J828D01*
G03X252154Y262197I-1038J700D01*
G01Y262745D01*
X252142Y262757D01*
X252141Y262759D01*
X252139Y262761D01*
G02X252083Y264114I707J707D01*
G03X252255Y264338I-1179J1084D01*
G03X252407Y264648I-1353J856D01*
G03X252504Y265197I-1505J549D01*
G01Y266080D01*
X252066Y266518D01*
G03X252035Y266549I-1147J-1117D01*
G01X251274Y267311D01*
X250851Y267734D01*
X249388D01*
G02X248889Y268210I0J500D01*
G03X246592Y269412I-1500J-71D01*
G01X246470Y269336D01*
X246273D01*
X245293Y268356D01*
G02X244585I-354J353D01*
G02X244497Y268943I354J353D01*
G03X244572Y269106I-1415J750D01*
G03X244656Y269396I-1489J589D01*
G03X244659Y269414I-1578J272D01*
G03X244684Y269697I-1576J282D01*
G01Y270390D01*
X244433Y270642D01*
X244231Y270844D01*
G02Y271550I354J353D01*
G01X244433Y271752D01*
X244684Y272004D01*
Y272697D01*
G03X242593Y274222I-1602J0D01*
G03X241820Y273682I490J-1525D01*
G01X241816Y273676D01*
X241813Y273672D01*
G03X241802Y273658I1253J-996D01*
G01X241780Y273629D01*
X240711Y272560D01*
G02X240167Y272451I-354J353D01*
G01X239930Y272549D01*
G02X239620Y273011I190J462D01*
G01Y274197D01*
G03X236418I-1601J0D01*
G01Y270526D01*
X237180Y269764D01*
G02Y269057I-354J-353D01*
G01X237177Y269054D01*
G03X237161Y269038I842J-858D01*
G03X237153Y269030I846J-854D01*
G03X237080Y268947I865J-834D01*
G03X236845Y268454I939J-750D01*
G01X236807Y268282D01*
X236533Y268061D01*
X235087D01*
G03X231912Y266697I-1294J-1364D01*
G01Y265792D01*
X232505Y265199D01*
G02X232564Y264562I-353J-354D01*
G01X232413Y264342D01*
X231950Y264250D01*
X231619Y264447D01*
X231555Y264549D01*
G03X230199Y265298I-1356J-853D01*
G01X228230D01*
X226730Y266798D01*
X225973D01*
G03X224511Y264544I0J-1601D01*
G03X224512Y264541I1519J505D01*
G03X224703Y264221I1461J655D01*
G02X224734Y263047I-793J-608D01*
G03X224771Y261296I1239J-850D01*
G02Y260097I-800J-599D01*
G03X224911Y258135I1202J-900D01*
G01X225640Y257406D01*
G02X225619Y256006I-724J-689D01*
G03X225498Y255872I1126J-1139D01*
G03X225413Y255757I1244J-1008D01*
G03X225334Y254110I1332J-889D01*
G01X225393Y253999D01*
Y253666D01*
X224978Y253251D01*
Y253180D01*
X224686Y252888D01*
X224440D01*
X224403Y252894D01*
G03X221430Y251059I-404J-2671D01*
G02X219792Y250643I-951J310D01*
G01X219294Y251141D01*
Y251569D01*
G03X218236Y252762I-1202J0D01*
G03X216965Y251987I-144J-1193D01*
G02X215902Y251388I-921J391D01*
G03X215830Y251399I-217J-1182D01*
G03X215690Y251407I-138J-1193D01*
G03X215488Y251391I-6J-1201D01*
G01X215447Y251384D01*
X215406D01*
G02X214906Y251884I0J500D01*
G01Y252157D01*
G03X212502I-1202J0D01*
G01Y251762D01*
G02X212002Y251262I-500J0D01*
G01X211007D01*
X210721Y251526D01*
X210705Y251721D01*
G03X210612Y252097I-1197J-97D01*
G03X210358Y252473I-1105J-472D01*
G01X209994Y252837D01*
G03X209619Y253087I-841J-856D01*
G01X209530Y253125D01*
X208548Y254107D01*
Y255289D01*
X208226Y255611D01*
Y256018D01*
X205192Y259052D01*
X205184Y259247D01*
G03X204833Y260047I-1201J-50D01*
G01X204488Y260392D01*
Y260824D01*
X204690Y261221D01*
X204765Y261285D01*
G03X204768Y261287I-660J993D01*
G01X204771Y261290D01*
X204777Y261295D01*
G03X204886Y261404I-795J904D01*
G03X205184Y262197I-903J792D01*
G01Y262817D01*
X203839Y264162D01*
X203801Y264260D01*
G03X203180Y264998I-1399J-547D01*
G02X202959Y265567I259J428D01*
G03X202863Y266659I-1441J424D01*
G03X202743Y266860I-1346J-667D01*
G02Y268017I815J579D01*
G03X203020Y268924I-1225J870D01*
G03X202973Y269261I-1501J-38D01*
G03X202885Y269509I-1454J-376D01*
G03X202598Y269930I-1366J-623D01*
G01X202597Y269931D01*
G02X202604Y270631I360J346D01*
G01X204422Y272449D01*
G02X204775Y272596I354J-353D01*
G01X206739D01*
G03X207672Y272895I1J1601D01*
G03X207865Y273058I-934J1301D01*
G03X207871Y273064I-1129J1135D01*
G01X208657Y273849D01*
X209476Y274670D01*
Y276551D01*
G02X211165Y277275I1000J0D01*
G01X211276Y277164D01*
X211325Y277116D01*
X213890D01*
X213901Y277127D01*
X214521D01*
X214532Y277116D01*
X214738D01*
X214739Y277114D01*
X214932D01*
X214942Y277104D01*
X217029D01*
X217039Y277114D01*
X217040D01*
X218393Y278468D01*
G03X218448Y278525I-1053J1071D01*
G01X218456Y278534D01*
X218543Y278622D01*
G02X219251I354J-353D01*
G01X219412Y278461D01*
G03X221536Y280585I1062J1062D01*
G01X220360Y281762D01*
X220356Y281766D01*
G03X220354Y281770I-1434J-715D01*
G01X220345Y281777D01*
X219979Y282143D01*
G03X219258Y282558I-1081J-1044D01*
G01X219070Y282693D01*
G03X219026Y282697I-167J-1595D01*
G03X218820Y283483I-1701J-26D01*
G01X218760Y283594D01*
Y283722D01*
G02X219238Y284222I501J0D01*
G01X219894D01*
X219967Y284199D01*
G03X221677Y284620I507J1624D01*
G01X224827Y287770D01*
G03X224993Y287963I-1203J1203D01*
G03X225120Y288162I-1367J1013D01*
G03X225131Y288183I-1502J800D01*
G01X225167Y288251D01*
X227906Y290991D01*
G03X227655Y293460I-1132J1132D01*
G01X227612Y293488D01*
X226447Y294654D01*
X226066Y295035D01*
Y295450D01*
X226395Y295779D01*
X226602Y295987D01*
X227906Y297291D01*
G03X227922Y297307I-1124J1140D01*
G02X228654Y297291I359J-349D01*
G03X228848Y297105I1271J1131D01*
G03X228851Y297102I1199J1196D01*
G01X228931Y297038D01*
X229028Y296849D01*
X229040Y296636D01*
X228964Y296437D01*
X228888Y296361D01*
X228862Y296335D01*
G03X228426Y295382I1062J-1062D01*
G03X228545Y294679I1498J-108D01*
G03X228862Y294211I1379J593D01*
G01X230297Y292776D01*
X230314Y292755D01*
G03X230445Y292612I1180J949D01*
G01X230475Y292582D01*
G02X230476Y291874I-353J-354D01*
G01X228322Y289720D01*
Y288973D01*
G03X231292Y288140I1602J0D01*
G01X231323Y288191D01*
X233856Y290724D01*
X233907Y290755D01*
G03X234587Y291597I-833J1368D01*
G03X234514Y292823I-1513J525D01*
G03X233831Y293534I-1440J-700D01*
G01X233766Y293569D01*
X232615Y294721D01*
X232609Y294728D01*
G03X232561Y294777I-1105J-1035D01*
G02X232457Y295347I349J358D01*
G01X232560Y295566D01*
X232631Y295632D01*
G03X233024Y296190I-1133J1215D01*
G01X233042Y296232D01*
X233043Y296234D01*
X233069Y296294D01*
X233495Y296721D01*
X233966Y297192D01*
X234136Y297361D01*
G03X234514Y298850I-1062J1062D01*
G03X234268Y299334I-1440J-427D01*
G03X234136Y299485I-1194J-911D01*
G01X234118Y299503D01*
G02Y300211I353J354D01*
G01X234299Y300392D01*
G03X234334Y300429I-1219J1188D01*
G03X234393Y300497I-1256J1149D01*
G01X234409Y300517D01*
X234429Y300537D01*
G02X235137I354J-353D01*
G01X235162Y300511D01*
G03X236516Y300100I1062J1062D01*
G03X236587Y300116I-295J1472D01*
G03X237669Y301163I-363J1457D01*
G01X237704Y301288D01*
X238083Y301668D01*
X238209Y301703D01*
G03X238573Y301861I-411J1445D01*
G03X238861Y302086I-774J1287D01*
G01X239167Y302392D01*
X239581D01*
X239727Y302245D01*
X240046Y301926D01*
G02Y301218I-353J-354D01*
G01X240027Y301199D01*
X240005Y301181D01*
X240003Y301180D01*
G03X239465Y300289I947J-1180D01*
G02X239074Y299894I-491J95D01*
G03X238855Y299832I298J-1471D01*
G03X238372Y299542I518J-1410D01*
G03X237888Y298205I1002J-1119D01*
G03X238530Y297181I1486J218D01*
G01X238569Y297154D01*
X239680Y296043D01*
X239719Y295986D01*
X239729Y295972D01*
G03X240281Y295503I1220J876D01*
G03X240578Y295393I667J1345D01*
G02X240947Y294995I-124J-485D01*
G03X243656Y294141I1577J278D01*
G01X245231Y295716D01*
G03X245299Y295788I-1129J1135D01*
G02X246049I375J-331D01*
G03X246117Y295716I1197J1063D01*
G01X247692Y294141D01*
G03X249956Y296405I1132J1132D01*
G01X248381Y297980D01*
G03X247685Y298389I-1133J-1131D01*
G03X247576Y298416I-439J-1540D01*
G03X247450Y298437I-326J-1568D01*
G01X247314Y298454D01*
X246878Y298791D01*
X246827Y298912D01*
G03X246396Y299446I-1153J-489D01*
G01X246361Y299471D01*
X245587Y300245D01*
X245553Y300376D01*
G03X245315Y300880I-1454J-378D01*
G02X245349Y302100I809J588D01*
G03X245719Y303041I-1131J988D01*
G03X245280Y304149I-1501J46D01*
G01X244143Y305286D01*
X243991Y305437D01*
X243260Y306169D01*
G02X243272Y306863I366J341D01*
G01X243291Y306882D01*
X243311Y306899D01*
G03X243561Y307171I-787J974D01*
G02X244668Y307128I521J-854D01*
G03X244853Y306928I1006J745D01*
G03X244875Y306909I829J938D01*
G03X244952Y306850I799J963D01*
G01X244987Y306825D01*
X245761Y306051D01*
X245795Y305919D01*
G03X248653Y305763I1454J378D01*
G01X248708Y305909D01*
X248964Y306086D01*
Y306159D01*
X252973Y310168D01*
X254454Y311648D01*
X255636D01*
X255930Y311354D01*
Y310641D01*
X255836Y310510D01*
G03X255608Y310031I1221J-875D01*
G01X255573Y309903D01*
X255460Y309789D01*
X255209Y309538D01*
X255107Y309500D01*
G03X254260Y308706I523J-1407D01*
G02X253852Y308413I-456J205D01*
G03X252636Y305991I155J-1594D01*
G01X252650Y305968D01*
G03X252769Y305803I1357J853D01*
G03X252965Y305603I1237J1017D01*
G01X252980Y305590D01*
X253805Y304765D01*
X254835Y303736D01*
X255439D01*
G02X255933Y303310I0J-500D01*
G03X255988Y303075I1485J224D01*
G01Y303074D01*
G02X255866Y302569I-476J-152D01*
G01X255660Y302363D01*
Y300273D01*
G03X255760Y299786I1226J-2D01*
G03X255944Y299487I1126J487D01*
G02Y298303I-807J-592D01*
G03X255760Y298004I942J-786D01*
G03X255660Y297517I1126J-485D01*
G01Y296970D01*
X255933Y296696D01*
X256892Y295737D01*
X256926Y295605D01*
G03X256985Y295426I1454J380D01*
G02X256120Y294054I-928J-373D01*
G01X255629D01*
G03X254155Y293078I0J-1601D01*
G01Y293077D01*
X254117Y292987D01*
X253259Y292129D01*
X253130Y292094D01*
G03X253549Y288946I419J-1546D01*
G01X254606D01*
X256512Y290852D01*
X258386D01*
G03X259862Y293074I0J1601D01*
G03X259844Y293116I-1480J-610D01*
G03X259273Y293787I-1458J-662D01*
G01X259175Y293852D01*
X259071Y294032D01*
G02X259068Y294528I433J251D01*
G01X259163Y294697D01*
X259254Y294762D01*
G03X259373Y294857I-876J1220D01*
G02X260586Y294891I629J-778D01*
G03X260957Y294696I878J1219D01*
G01X261095Y294647D01*
X261460Y294176D01*
X261446Y294015D01*
G03X261437Y293865I1458J-163D01*
G03X261442Y293728I1467J-15D01*
G03X261664Y293064I1462J120D01*
G01X261742Y292941D01*
Y290641D01*
X263536Y288847D01*
G03X264000Y288559I849J850D01*
G02X264322Y287951I-160J-474D01*
G03X264580Y286627I1446J-405D01*
G01X264684Y286492D01*
Y284633D01*
G03X264900Y283946I1202J0D01*
G03X264930Y283905I984J689D01*
G03X264940Y283892I957J726D01*
G03X264953Y283876I939J750D01*
G03X264965Y283862I918J775D01*
G02Y282648I-796J-607D01*
G03X264824Y282440I919J-775D01*
G03X264730Y282205I1063J-561D01*
G03X264687Y281796I1156J-328D01*
G03X265181Y280904I1199J81D01*
G01X265213Y280880D01*
X265891Y280203D01*
X265924Y280064D01*
G03X268204Y279147I1462J343D01*
G03X268304Y279218I-819J1259D01*
G02X269468I582J-813D01*
G03X269758Y279042I919J1188D01*
G03X271725Y281088I628J1365D01*
G01X271721Y281096D01*
G02X271692Y281167I447J224D01*
G01X271597Y281296D01*
G03X271433Y281484I-1210J-890D01*
G03X271356Y281554I-1048J-1076D01*
G03X271251Y281635I-969J-1148D01*
G03X270729Y281869I-864J-1228D01*
G01X270590Y281902D01*
X269564Y282928D01*
G02Y283604I369J338D01*
G01X270648Y284688D01*
X270787Y284721D01*
G03X271124Y284844I-343J1462D01*
G03X271188Y284878I-672J1343D01*
G03X271362Y284994I-744J1305D01*
G02X272526I582J-813D01*
G03X272858Y284800I918J1189D01*
G01X272948Y284762D01*
X273017Y284693D01*
G02Y283986I-354J-353D01*
G01X272851Y283820D01*
G03X272849Y283818I848J-850D01*
G01X272605Y283574D01*
X272519Y283487D01*
X272500Y283468D01*
Y281694D01*
G02X272522Y281673I-334J-372D01*
G01X272832Y281363D01*
X273520Y280676D01*
X274093D01*
G02X274513Y279905I0J-500D01*
G01X274436Y279785D01*
X274306Y279723D01*
G03X274267Y279704I638J-1359D01*
G03X273482Y278706I677J-1341D01*
G01X273449Y278567D01*
X272631Y277749D01*
X272614Y277735D01*
G03X272276Y277274I772J-921D01*
G03X272223Y276511I1110J-460D01*
G03X272258Y276399I1163J302D01*
G03X273386Y275612I1128J415D01*
G01X273892D01*
X273947Y275667D01*
X274204Y275923D01*
G02X275570Y275931I687J-726D01*
G03X275574Y275928I720J956D01*
G03X276386Y275612I812J885D01*
G01X276892D01*
X278148Y276868D01*
X278287Y276901D01*
G03X278960Y277256I-341J1463D01*
G03X279096Y277399I-1018J1105D01*
G03X279116Y277423I-1143J973D01*
G03X279254Y277629I-1175J936D01*
G01X279262Y277643D01*
X279281Y277673D01*
G02X279650Y277898I419J-273D01*
G01X279651D01*
G02X280054Y277755I50J-497D01*
G01X280272Y277538D01*
X280305Y277399D01*
G03X281430Y276278I1462J343D01*
G03X281867Y276243I337J1464D01*
G03X282066Y276270I-102J1499D01*
G02X282642Y275935I100J-490D01*
G03X283515Y275136I1142J372D01*
G03X283936Y275115I269J1171D01*
G03X284634Y275457I-151J1192D01*
G01X285557Y276380D01*
G02X287213Y275987I707J-707D01*
G03X287219Y275968I1148J352D01*
G03X287223Y275957I1130J405D01*
G03X287231Y275934I1139J383D01*
G03X287238Y275915I1131J406D01*
G03X287270Y275839I1123J428D01*
G02X286874Y275132I-454J-210D01*
G03X286361Y274948I139J-1194D01*
G03X286227Y274847I654J-1008D01*
G03X285924Y274445I787J-908D01*
G03X286164Y273089I1090J-506D01*
G01X286714Y272539D01*
G02Y271831I-353J-354D01*
G01X286204Y271321D01*
X286198Y271316D01*
G03X286145Y271262I827J-865D01*
G03X285927Y270940I869J-823D01*
G03X286574Y269326I1087J-501D01*
G02X287192Y268231I-368J-930D01*
G03X287188Y268207I1183J-209D01*
G03X287176Y267996I1189J-173D01*
G03X287177Y267973I1201J41D01*
G03X287192Y267835I1200J61D01*
G01X287199Y267794D01*
Y267752D01*
G02X286699Y267252I-500J0D01*
G01X286426D01*
G03Y264850I0J-1201D01*
G01X286999D01*
G02X287352Y264703I-1J-500D01*
G01X287558Y264498D01*
G02X287615Y263860I-354J-353D01*
G03X287434Y263453I988J-683D01*
G03X287415Y263353I1170J-274D01*
G03X288603Y261974I1188J-178D01*
G01X288814D01*
X290834Y259954D01*
X292052D01*
X292326Y259680D01*
Y248301D01*
X293602Y247025D01*
Y240892D01*
X291368Y238658D01*
X284472D01*
X281632Y241498D01*
Y248914D01*
X280926Y249620D01*
Y251722D01*
X280478Y252170D01*
X280453Y252334D01*
G03X280081Y253039I-1188J-176D01*
G03X279831Y253217I-816J-882D01*
G03X279464Y253342I-566J-1060D01*
G01X279428Y253348D01*
X279252Y253374D01*
X278298D01*
X278102Y253463D01*
X278031Y253543D01*
G03X275777I-1127J-993D01*
G01X275706Y253463D01*
X275510Y253374D01*
X270824D01*
X270600Y253497D01*
X270531Y253606D01*
G03X267995I-1268J-806D01*
G01X267926Y253497D01*
X267702Y253374D01*
X267231D01*
Y253309D01*
G03X265696Y252311I-343J-1152D01*
G01X265674Y252142D01*
X265377Y251845D01*
X264793D01*
X264771Y251867D01*
X264765Y251861D01*
X263790D01*
G02X263290Y252361I0J500D01*
G01Y254081D01*
X264242Y255033D01*
X264337Y255071D01*
G03X265118Y255793I-563J1393D01*
G03X265255Y256216I-1345J669D01*
G03X265105Y257160I-1481J249D01*
G03X265104Y257162I-1344J-671D01*
G01X265047Y257271D01*
Y262174D01*
X264777Y262444D01*
X264752Y262604D01*
G03X264383Y263377I-1484J-234D01*
G03X263315Y263871I-1114J-1007D01*
G03X262729Y263772I-48J-1501D01*
G03X262247Y263472I538J-1402D01*
G02X260974Y263385I-689J725D01*
G03X260947Y263405I-907J-1197D01*
G03X260480Y263631I-878J-1219D01*
G03X260397Y263653I-426J-1440D01*
G01X260274Y263681D01*
X259877Y264026D01*
X259829Y264155D01*
G03X259823Y264168I-1089J-495D01*
G03X259598Y264514I-1101J-470D01*
G02X259601Y265876I733J679D01*
G03X259640Y265920I-880J819D01*
G01X259704Y265996D01*
X259873Y266083D01*
G02X260329I228J-446D01*
G01X260473Y266009D01*
X260539Y265928D01*
G03X261479Y265482I940J768D01*
G01X262090D01*
X263255Y266648D01*
X263391Y266681D01*
G03X263536Y266725I-363J1458D01*
G03X264305Y267347I-507J1414D01*
G37*
G36*
G01X213742Y305173D02*
X215738Y307168D01*
X215776Y307206D01*
Y307873D01*
G03X212984Y308945I-1602J0D01*
G01X212974Y308934D01*
X212964Y308923D01*
G02X212256I-354J354D01*
G01X211705Y309474D01*
X211024D01*
G03X210872Y309467I-2J-1601D01*
G03X210800Y309459I141J-1595D01*
G03X210748Y309451I217J-1587D01*
G01X210706Y309444D01*
X209979D01*
G02X209625Y310297I0J500D01*
G01X209630Y310302D01*
X209635Y310307D01*
X210687Y311360D01*
G03X208211Y313836I-1238J1238D01*
G01X206636Y312261D01*
G03X206568Y312190I1230J-1246D01*
G02X205845Y312166I-373J333D01*
G03X205816Y312195I-1146J-1117D01*
G03X205807Y312203I-1068J-1192D01*
G03X205796Y312213I-1083J-1180D01*
G01X205786Y312222D01*
X205706Y312302D01*
G02Y313009I354J353D01*
G01X206252Y313555D01*
Y313973D01*
X206468Y314245D01*
X206639Y314285D01*
G03X207165Y316975I-340J1463D01*
G01X207130Y317000D01*
X205292Y318838D01*
X201685D01*
X201230Y319293D01*
Y319678D01*
G02X201708Y320178I501J0D01*
G01X202691D01*
X203649Y321136D01*
X205265D01*
X205335Y321115D01*
G03X206255I460J1534D01*
G01X206358Y321146D01*
X206359Y321147D01*
X206444Y321185D01*
G03X207058Y321664I-649J1464D01*
G01X207072Y321683D01*
X207098Y321717D01*
X208397Y323017D01*
G03X208833Y323823I-1132J1133D01*
G03X209253Y324349I-934J1176D01*
G01X209290Y324425D01*
X210901Y326036D01*
X211055Y326064D01*
G03X211362Y326169I-199J1084D01*
G01X211470Y326224D01*
X213004D01*
X213111Y326169D01*
G03X214119I504J980D01*
G01X214296Y326260D01*
X217380Y329344D01*
X220820D01*
X220979Y329185D01*
X222349D01*
X222690Y328844D01*
Y321458D01*
X223457Y320691D01*
X224166D01*
X224397Y320460D01*
Y317526D01*
X224386Y317514D01*
Y317306D01*
X223678Y316598D01*
Y316259D01*
X223657Y316189D01*
G03X224024Y314659I1509J-447D01*
G03X224052Y314630I1166J1098D01*
G01X224053Y314629D01*
X224086Y314596D01*
X224142Y314512D01*
G02X224078Y313883I-418J-275D01*
G01X222421Y312226D01*
G03X221970Y311421I1203J-1203D01*
G03X222122Y310223I1654J-399D01*
G03X222281Y309978I1501J800D01*
G02X222322Y308806I-789J-614D01*
G03X222200Y308607I1301J-934D01*
G01X222164Y308537D01*
X221385Y307757D01*
X221316Y307722D01*
G03X220917Y307430I735J-1423D01*
G01X220905Y307419D01*
X220903Y307417D01*
X220896Y307410D01*
G02X220203Y307396I-354J354D01*
G01X220181Y307417D01*
X220165Y307435D01*
G03X219277Y307957I-1266J-1137D01*
G03X219136Y307983I-379J-1659D01*
G03X217696Y307501I-237J-1685D01*
G01X216121Y305926D01*
G03X215639Y304486I1203J-1203D01*
G03X215665Y304345I1685J238D01*
G03X216187Y303457I1659J378D01*
G01X216205Y303441D01*
X216226Y303419D01*
G02X216212Y302726I-368J-339D01*
G01X216189Y302703D01*
X216177Y302690D01*
G03X215724Y301639I1147J-1117D01*
G03X215723Y301614I1599J-76D01*
G03X215996Y300677I1601J-42D01*
G03X216197Y300435I1327J897D01*
G01X216264Y300369D01*
X216353Y300170D01*
G02X216252Y299616I-457J-203D01*
G01X216244Y299608D01*
X216192Y299555D01*
G03X216264Y297223I1132J-1132D01*
G02Y296473I-331J-375D01*
G03X216192Y296405I1063J-1197D01*
G01X214617Y294830D01*
G03X214172Y293976I1132J-1133D01*
G02X213803Y293578I-493J87D01*
G03X213229Y293290I371J-1455D01*
G02X211969I-630J776D01*
G03X209962Y293185I-945J-1167D01*
G01X209873Y293096D01*
X209834Y293056D01*
X209803Y293025D01*
G02X209095I-354J354D01*
G01X209064Y293056D01*
X209025Y293096D01*
X208936Y293185D01*
G03X208890Y293229I-1061J-1063D01*
G03X208863Y293253I-1011J-1110D01*
G02X208845Y293979I335J372D01*
G01X208866Y294000D01*
X208885Y294019D01*
X209006Y294141D01*
G03X209177Y296204I-1132J1132D01*
G03X208997Y296415I-1304J-930D01*
G02X208815Y297597I701J713D01*
G03X208938Y297763I-941J826D01*
G01X208969Y297813D01*
X209076Y297920D01*
Y298068D01*
X209090Y298126D01*
G03X208742Y299325I-1216J297D01*
G02X208969Y300404I930J368D01*
G03X209246Y300747I-1096J1168D01*
G03X209474Y301516I-1372J825D01*
G03X209463Y301774I-1600J61D01*
G02X210411Y302900I992J127D01*
G01X211361D01*
X211556D01*
X212638Y303982D01*
Y304177D01*
Y304271D01*
G02X213012Y304755I500J0D01*
G01X213013D01*
G03X213016Y304756I-505J1519D01*
G03X213742Y305173I-407J1549D01*
G37*
G36*
G01X212631Y280156D02*
X212584D01*
X211678Y281062D01*
X211609D01*
X210909Y281762D01*
X210874Y281830D01*
G03X210773Y281999I-1423J-736D01*
G03X209921Y282628I-1324J-901D01*
G01X209803Y282664D01*
X209441Y283027D01*
X209405Y283145D01*
G03X208947Y283862I-1530J-473D01*
G01X208871Y283930D01*
X208819Y284041D01*
G02X208919Y284607I453J212D01*
G01X208938Y284626D01*
X208947Y284634D01*
G03X209004Y284689I-1083J1179D01*
G01X209006Y284691D01*
X209099Y284783D01*
G02X209787Y284798I352J-355D01*
G01X209812Y284776D01*
X209829Y284756D01*
G03X212152Y284687I1194J1067D01*
G01X212156Y284691D01*
X212175Y284709D01*
X212322Y284856D01*
X212735D01*
X213048Y284543D01*
X213464Y284126D01*
X214150Y283440D01*
X214478D01*
G02X214831Y282586I0J-500D01*
G01X214546Y282301D01*
G03X214108Y281548I1203J-1203D01*
G03X214089Y281471I1642J-446D01*
G01X214061Y281349D01*
X213773Y281015D01*
X213650Y280970D01*
G03X213086Y280611I525J-1447D01*
G01X212631Y280156D01*
G37*
G36*
G01X210321Y289252D02*
X210373Y289359D01*
X210447Y289425D01*
G03X210510Y289485I-1004J1117D01*
G01X210511Y289486D01*
X212086Y291061D01*
X212087Y291062D01*
G03X212147Y291125I-1057J1067D01*
G01X212213Y291199D01*
X212380Y291281D01*
G02X212818I219J-450D01*
G01X212985Y291199D01*
X213051Y291125D01*
G03X213111Y291062I1117J1004D01*
G01X213112Y291061D01*
X214687Y289486D01*
G03X214733Y289442I1061J1063D01*
G03X214756Y289421I1024J1098D01*
G01X214768Y289411D01*
X214779Y289400D01*
G02Y288693I-354J-353D01*
G01X214757Y288671D01*
X214738Y288652D01*
X214617Y288530D01*
G03X214603Y288516I1125J-1139D01*
G01X214601Y288514D01*
X214598Y288512D01*
G02X213891I-353J354D01*
G01X213802Y288601D01*
G03X211329Y288530I-1203J-1203D01*
G02X210597Y288514I-373J333D01*
G03X210535Y288575I-1154J-1110D01*
G03X210456Y288644I-1092J-1171D01*
G02X210321Y289252I314J389D01*
G37*
G36*
G01X211637Y304907D02*
Y304592D01*
X210946Y303901D01*
X207811D01*
X207431Y304280D01*
G03X206793Y304671I-1132J-1132D01*
G01X206678Y304709D01*
X206285Y305102D01*
X206247Y305217D01*
G03X206009Y305679I-1524J-493D01*
G02X205946Y306164I401J299D01*
G01X206052Y306427D01*
G02X206516Y306740I464J-187D01*
G01X206711D01*
G03X207606Y306263I1162J1102D01*
G01X207764Y306236D01*
X208003Y305997D01*
X210653D01*
X211478Y305173D01*
G03X211487Y305163I1193J1064D01*
G01X211559Y305092D01*
X211637Y304907D01*
G37*
G36*
G01X201130Y463368D02*
X204397D01*
X206438Y465409D01*
X211953D01*
X212275Y465087D01*
Y460502D01*
G02X211775Y460002I-500J0D01*
G01X205985D01*
X205202Y460785D01*
X201311D01*
X200710Y461386D01*
Y462948D01*
X201130Y463368D01*
G37*
G36*
G01X209409Y478253D02*
X203409D01*
X202709Y477553D01*
Y468853D01*
X202309Y468453D01*
X201164Y467308D01*
X196310D01*
X195641Y466639D01*
Y464922D01*
X195867Y464696D01*
X195924Y464753D01*
X200909D01*
X203509D01*
X205609Y466853D01*
X212009D01*
X212509Y467353D01*
Y471953D01*
X210009Y474453D01*
Y477653D01*
X209409Y478253D01*
G37*
G36*
G01X210463Y539962D02*
G03I-577J0D01*
G37*
G36*
G01X202086Y539853D02*
G03I-577J0D01*
G37*
G36*
G01X200286Y551653D02*
G03I-577J0D01*
G37*
G36*
G01X208686Y551053D02*
G03I-577J0D01*
G37*
G36*
G01X208116Y608936D02*
G03I-640J0D01*
G37*
G36*
G01X207650Y602472D02*
G03I-640J0D01*
G37*
G36*
G01X203090Y663633D02*
G03I-640J0D01*
G37*
G36*
G01X221145Y59322D02*
X221111Y59288D01*
X220459Y59940D01*
X220412D01*
X219370Y60982D01*
Y67652D01*
G02X219870Y68152I500J0D01*
G01X254897D01*
X255680Y67369D01*
Y59969D01*
X255033Y59322D01*
X221145D01*
G37*
G36*
G01X212688Y234333D02*
G03I-660J0D01*
G37*
G36*
G01X221933Y291458D02*
X222172Y291698D01*
X222859Y292385D01*
X222898Y292423D01*
G02X223900Y292671I707J-707D01*
G01X224277Y292294D01*
G02X224346Y291960I-426J-262D01*
G01X222902Y290515D01*
X222834Y290480D01*
G03X222421Y290176I791J-1507D01*
G01X219669Y287424D01*
X219135D01*
G02X218657Y287924I22J500D01*
G01Y288057D01*
X218723Y288173D01*
G03X218900Y289311I-1399J800D01*
G02X219846Y290522I978J211D01*
G01X220474D01*
G03X221897Y291389I0J1601D01*
G01X221933Y291458D01*
G37*
G36*
G01X237045Y304534D02*
X236776Y304266D01*
G03X236546Y304000I1023J-1117D01*
G01X236441Y303895D01*
X236027Y303894D01*
X235711Y304210D01*
G03X233672Y304288I-1062J-1062D01*
G03X233255Y303706I977J-1140D01*
G01X233210Y303593D01*
X232823Y303261D01*
X232701Y303233D01*
G03X232343Y303109I374J-1660D01*
G03X231871Y302776I731J-1536D01*
G01X228721Y299626D01*
G03X228654Y299555I1203J-1203D01*
G02X227922Y299539I-373J333D01*
G03X225642Y299555I-1148J-1116D01*
G01X222492Y296405D01*
G03X222228Y296058I1130J-1134D01*
G03X222200Y296006I1396J-785D01*
G01X222164Y295937D01*
X220949Y294722D01*
X220098Y293871D01*
G02X219745Y293724I-354J353D01*
G01X219145D01*
G02X218645Y294224I0J500D01*
G01Y294358D01*
X218712Y294474D01*
G03X218384Y296473I-1388J799D01*
G02X218323Y297158I331J375D01*
G03X218464Y297283I-997J1267D01*
G01X218626Y297445D01*
G02X219334I354J-353D01*
G01X219338Y297441D01*
X219349Y297429D01*
G03X220001Y296998I1125J994D01*
G03X221536Y297361I473J1425D01*
G01X224686Y300511D01*
G03X222562Y302635I-1062J1062D01*
G01X220742Y300815D01*
X220330D01*
X220210Y300935D01*
G03X219952Y301217I-1309J-939D01*
G01X219870Y301399D01*
G02X219972Y301957I456J205D01*
G01X220031Y302016D01*
G03X220459Y302788I-1132J1132D01*
G02X220834Y303163I487J-112D01*
G03X221606Y303591I-360J1560D01*
G01X223181Y305166D01*
G03X223237Y305224I-1124J1141D01*
G03X223249Y305237I-1171J1093D01*
G01X223258Y305247D01*
X223267Y305256D01*
G02X223975Y305257I354J-353D01*
G01X224203Y305029D01*
X225642Y303591D01*
G03X227906Y305855I1132J1132D01*
G01X224756Y309005D01*
G03X224740Y309021I-1140J-1124D01*
G02X224756Y309753I349J359D01*
G03X224827Y309820I-1132J1270D01*
G01X227977Y312970D01*
G03X227913Y315437I-1203J1203D01*
G01X227894Y315454D01*
X227870Y315480D01*
G02X227878Y316162I370J337D01*
G01X227889Y316173D01*
X227906Y316191D01*
G03X228275Y316766I-1132J1132D01*
G03X228340Y316986I-1499J563D01*
G01X228374Y317145D01*
X228861Y317579D01*
X230987D01*
X231474Y317145D01*
X231508Y316986D01*
G03X231604Y316688I1565J340D01*
G03X231958Y316175I1470J636D01*
G02X231942Y315443I-349J-359D01*
G03X231871Y315376I1132J-1270D01*
G01X228721Y312226D01*
G03X228223Y311016I1203J-1203D01*
G03X228581Y309978I1701J6D01*
G02X228621Y308804I-789J-615D01*
G03X228460Y308522I1303J-931D01*
G03X228322Y307873I1464J-650D01*
G01Y306977D01*
X228591Y306708D01*
X229815Y305485D01*
G03X229838Y305461I1167J1095D01*
G01X229842Y305458D01*
X230284Y305016D01*
X232481D01*
X234110Y306645D01*
X234516Y307050D01*
X234929D01*
X235016Y306963D01*
G03X235155Y306804I1205J913D01*
G01X236682Y305276D01*
G03X236943Y305049I1118J1021D01*
G01X237044Y304948D01*
X237045Y304534D01*
G37*
G36*
G01X233754Y414220D02*
X219632D01*
X218256D01*
X217199D01*
X216351Y415068D01*
Y441672D01*
Y444335D01*
X216941Y444925D01*
X233942D01*
X234037Y444830D01*
X235100D01*
X235714Y444216D01*
Y414694D01*
X235240Y414220D01*
X233754D01*
G37*
G36*
G01X227255Y461936D02*
X227359Y461885D01*
G03X227691Y461757I883J1796D01*
G01X227816Y461721D01*
X228461Y461076D01*
Y460181D01*
X228058Y459777D01*
X215364D01*
X214746Y460396D01*
Y464371D01*
X215892Y465517D01*
X220224D01*
X221952Y463789D01*
Y463550D01*
G03X225023Y461859I2001J0D01*
G01X225145Y461936D01*
X227255D01*
G37*
G36*
G01X215709Y474453D02*
X212609D01*
X212009Y475053D01*
Y479953D01*
X212709Y480653D01*
X216009D01*
X216209Y480453D01*
Y474953D01*
X215709Y474453D01*
G37*
G36*
G01X215203Y516492D02*
G03I-577J0D01*
G37*
G36*
G01X219519Y593091D02*
G03I-640J0D01*
G37*
G36*
G01X212400Y610915D02*
G03I-640J0D01*
G37*
G36*
G01X219936Y604811D02*
G03I-640J0D01*
G37*
G36*
G01X212502Y617709D02*
G03I-640J0D01*
G37*
G36*
G01X240140Y100925D02*
G03I-640J0D01*
G37*
G36*
G01X238984Y307221D02*
G03X238861Y307360I-1184J-924D01*
G01X237286Y308935D01*
G03X237217Y308999I-1055J-1068D01*
G01X237205Y309010D01*
X237194Y309021D01*
G02Y309728I354J353D01*
G01X239854Y312388D01*
G02X240561I353J-354D01*
G01X240668Y312281D01*
G02Y311574I-353J-353D01*
G01X239746Y310651D01*
G03X239884Y308121I1203J-1203D01*
G02X239909Y307363I-313J-390D01*
G03X239764Y307210I1015J-1107D01*
G02X238984Y307221I-386J318D01*
G37*
G36*
G01X236921Y441512D02*
X248240D01*
X248928Y440824D01*
Y414643D01*
X248663Y414378D01*
X237610D01*
X236921Y415067D01*
Y441512D01*
G37*
G36*
G01X232150Y469160D02*
Y475337D01*
G02X232650Y475837I500J0D01*
G01X233796D01*
G02X234296Y475337I0J-500D01*
G01Y469160D01*
G02X233796Y468660I-500J0D01*
G01X232650D01*
G02X232150Y469160I0J500D01*
G37*
G36*
G01X237112Y468774D02*
X236698Y469188D01*
Y475451D01*
G02X237198Y475951I500J0D01*
G01X238308D01*
G02X238808Y475451I0J-500D01*
G01Y469274D01*
G02X238308Y468774I-500J0D01*
G01X237112D01*
G37*
G36*
G01X241210Y469248D02*
Y475425D01*
G02X241710Y475925I500J0D01*
G01X242780D01*
G02X243280Y475425I0J-500D01*
G01Y469177D01*
X242851Y468748D01*
X241710D01*
G02X241210Y469248I0J500D01*
G37*
G36*
G01X305080Y506135D02*
X304899Y506316D01*
Y506283D01*
X296908D01*
X295258Y507933D01*
X292845D01*
G03X290949I-948J-612D01*
G01X289695D01*
G03X287799I-948J-612D01*
G01X286778D01*
X285926Y508785D01*
G02X286049Y509437I283J284D01*
G03X284564Y510922I-451J1034D01*
G02X283912Y510799I-368J160D01*
G01X282776Y511935D01*
G02X282899Y512586I284J284D01*
G03X282111Y514696I-451J1034D01*
G01X282082Y514687D01*
X280623D01*
G03X280429Y514891I-1326J-1067D01*
G01Y516770D01*
G03X278167I-1131J0D01*
G01Y514891D01*
G03X278095Y514823I1132J-1271D01*
G01X277694Y514423D01*
X272224D01*
X271551Y515096D01*
G03X268542Y515453I-1701J-1476D01*
G01X266509D01*
X266409Y515353D01*
X266274Y515319D01*
G03X266177Y515292I421J-1701D01*
G03X265870Y515162I526J-1671D01*
G03X264948Y513620I828J-1542D01*
G01Y512887D01*
X265475Y512360D01*
X265621Y512215D01*
X265624Y511805D01*
X265480Y511657D01*
G03X265317Y511462I1220J-1186D01*
G02X264910Y511253I-407J291D01*
G01X264515D01*
X264372Y511382D01*
G03X262728I-822J-911D01*
G01X262585Y511253D01*
X261366D01*
X261223Y511382D01*
G03X261086Y511489I-822J-911D01*
G01X261046Y511516D01*
X259012Y513550D01*
X258999Y513738D01*
G03X258036Y515186I-1748J-118D01*
G03X256133Y514968I-785J-1566D01*
G01X255994Y514853D01*
X255359D01*
X255220Y514968D01*
G03X253825Y515350I-1119J-1348D01*
G03X252810Y514804I276J-1730D01*
G01X252803Y514796D01*
X251286Y513278D01*
G03X250836Y512507I1238J-1239D01*
G03X250776Y512154I1687J-468D01*
G01X250767Y512023D01*
X250504Y511621D01*
X250387Y511560D01*
G03X250293Y511506I564J-1090D01*
G03X250057Y511311I658J-1036D01*
G01X249985Y511235D01*
X249796Y511153D01*
X249061D01*
X248704Y511308D01*
X248641Y511367D01*
G03X246963I-839J-896D01*
G01X246900Y511308D01*
X246543Y511153D01*
X245912D01*
X245555Y511308D01*
X245492Y511367D01*
G03X243814I-839J-896D01*
G01X243751Y511308D01*
X243394Y511153D01*
X243009D01*
X241709Y512453D01*
Y516553D01*
X242909Y517753D01*
Y518846D01*
X243255Y519192D01*
Y519919D01*
G03X243104Y520630I-1752J-1D01*
G01X243061Y520727D01*
Y522148D01*
X243254Y522342D01*
Y523069D01*
G03X242063Y524729I-1752J0D01*
G01X241952Y524766D01*
X239977Y526741D01*
X239939Y526839D01*
G03X239573Y527406I-1584J-621D01*
G02X239431Y527755I358J349D01*
G01Y528064D01*
G02X239717Y528661I994J-109D01*
G01X241853Y530797D01*
X241978Y530832D01*
G03X243189Y532043I-475J1686D01*
G01X243224Y532168D01*
X243709Y532653D01*
Y547453D01*
X246334Y550078D01*
X246693Y550112D01*
X246842Y550010D01*
G03X247802Y549713I961J1405D01*
G01X248510D01*
X249021Y550224D01*
G02X249728I353J-354D01*
G01X249873Y550079D01*
X250238Y549713D01*
X250549D01*
X250810Y549452D01*
X250847Y549331D01*
G03X251286Y548597I1677J505D01*
G01X253368Y546515D01*
X254102D01*
G03X255166Y546874I2J1752D01*
G03X255264Y546955I-1066J1390D01*
G01X255328Y547012D01*
X255512Y547087D01*
G02X256054Y546977I188J-463D01*
G01X256517Y546515D01*
X257251D01*
G03X258942Y547808I0J1752D01*
G03X259000Y548165I-1691J458D01*
G01X259011Y548355D01*
X260369Y549713D01*
X261108D01*
X261477Y550082D01*
X261623Y550229D01*
G02X262142Y550347I353J-354D01*
G01X262252Y550308D01*
X262334Y550225D01*
G03X263550Y549713I1217J1190D01*
G01X264257D01*
X264727Y550183D01*
G02X265434I353J-353D01*
G02X265440Y549483I-354J-353D01*
G03X266700Y546515I1260J-1217D01*
G01X267427D01*
X267919Y547006D01*
X267921Y547008D01*
X268070Y547156D01*
X268479Y547157D01*
X268626Y547014D01*
G03X269850Y546515I1224J1252D01*
G01X269851D01*
G03X271089Y547028I0J1750D01*
G01X271315Y547253D01*
X272309D01*
X274609Y544953D01*
Y542809D01*
X274562Y542708D01*
G03Y541226I1587J-741D01*
G01X274609Y541125D01*
Y539659D01*
X274562Y539558D01*
G03Y538076I1587J-741D01*
G01X274609Y537975D01*
Y536509D01*
X274562Y536408D01*
G03Y534926I1587J-741D01*
G01X274609Y534825D01*
Y533360D01*
X274562Y533259D01*
G03Y531777I1587J-741D01*
G01X274609Y531676D01*
Y530210D01*
X274562Y530109D01*
G03Y528627I1587J-741D01*
G01X274609Y528526D01*
Y527862D01*
G03X276149Y523967I1540J-1643D01*
G01X277085D01*
X278206Y525088D01*
X291897D01*
G03X292852Y525613I0J1131D01*
G01X293740D01*
X296480Y528353D01*
Y537698D01*
X299928Y541146D01*
X310860D01*
X310948Y541058D01*
X315431D01*
X317588Y543215D01*
Y547926D01*
X318988Y549326D01*
Y557329D01*
X319628Y557969D01*
X320629D01*
X321180Y557418D01*
Y552125D01*
X321287Y552018D01*
X323472D01*
X323488Y552003D01*
X326988D01*
X327888D01*
X328788D01*
X328806Y551985D01*
X328824Y552003D01*
X329888D01*
X330917D01*
Y546732D01*
X329795Y545610D01*
Y539690D01*
X329408Y539303D01*
X327688D01*
X326488Y538103D01*
Y536003D01*
X326088Y535603D01*
X324188D01*
X322310Y533725D01*
Y533698D01*
X319624Y531012D01*
X317436D01*
X315768Y529344D01*
Y525716D01*
X315900Y525584D01*
Y515845D01*
X306190Y506135D01*
X305080D01*
G37*
G36*
G01X245295Y584456D02*
G03X245021Y582271I1521J-1300D01*
G01X245092Y582126D01*
X245040Y581810D01*
X244430Y581200D01*
X236364D01*
X235982Y581582D01*
Y589648D01*
X237273Y590939D01*
X244841D01*
X245457Y590323D01*
Y588657D01*
X245414D01*
Y588597D01*
X245295Y588456D01*
G03Y585856I1521J-1300D01*
G02X245414Y585531I-381J-324D01*
G01Y584781D01*
G02X245295Y584456I-500J-1D01*
G37*
G36*
G01X253985Y626546D02*
X254674Y625858D01*
Y601339D01*
X254529D01*
X253952Y600762D01*
Y600686D01*
X242633D01*
X241945Y601374D01*
Y624866D01*
X243625Y626546D01*
X253985D01*
G37*
G36*
G01X238553Y635074D02*
X238673Y635194D01*
X242297D01*
X242467Y635024D01*
X243552D01*
X243579Y635021D01*
G03X243907I164J1493D01*
G01X243934Y635024D01*
X254699D01*
X256013Y633710D01*
X259701D01*
X259872Y633539D01*
Y632183D01*
X258249Y630560D01*
X248837D01*
X247793Y631604D01*
X245093D01*
X244553Y631064D01*
X243677Y630188D01*
X237890D01*
X236490Y631588D01*
Y634954D01*
X236610Y635074D01*
X238553D01*
G37*
G36*
G01X244020Y646053D02*
X244201Y646234D01*
X251003D01*
X258563D01*
X259777Y645020D01*
Y643651D01*
Y635110D01*
X259566Y634899D01*
X259483D01*
X256483D01*
X256028Y635354D01*
X255785D01*
X255114Y636026D01*
X242882D01*
X242712Y636196D01*
X242711D01*
X242245Y636662D01*
Y638138D01*
X242304Y638197D01*
X243057D01*
X244020Y639160D01*
Y646053D01*
G37*
G36*
G01X244370Y103057D02*
G03I-640J0D01*
G37*
G36*
G01X247226Y313746D02*
G02X247599Y314055I466J-182D01*
G03X248484Y314524I-319J1671D01*
G01X249052Y315091D01*
Y315144D01*
X250159Y316252D01*
X250579D01*
G02X250911Y316125I-1J-500D01*
G03X253303Y316430I1063J1198D01*
G01X253331Y316471D01*
X253476Y316615D01*
Y316762D01*
X253500Y316836D01*
G03X253547Y317021I-1526J486D01*
G03X253576Y317323I-1572J303D01*
G01Y317536D01*
G02X254764Y318518I1000J0D01*
G03X256507Y319271I360J1561D01*
G03X256574Y319399I-1384J806D01*
G02X257206Y319654I453J-212D01*
G03X257585Y319559I576J1494D01*
G03X257829Y319548I194J1590D01*
G03X257954Y319557I-52J1601D01*
G03X258143Y319589I-172J1592D01*
G01X258169Y319595D01*
X258219Y319602D01*
G02X258645Y319461I73J-495D01*
G01X259548Y318558D01*
X262325D01*
X263542Y319775D01*
X264386D01*
G03X264540Y319785I-1J1202D01*
G03X265169Y320066I-155J1192D01*
G01X265310Y320187D01*
X266462D01*
X266603Y320066D01*
G03X268169I783J911D01*
G01X268310Y320187D01*
X268845D01*
G02X269200Y320040I1J-500D01*
G01X269324Y319915D01*
G03X271523Y319996I1062J1062D01*
G01X271535Y320010D01*
X271712Y320187D01*
X272462D01*
X272603Y320066D01*
G03X274169I783J911D01*
G01X274310Y320187D01*
X275462D01*
X275603Y320066D01*
G03X276232Y319785I784J911D01*
G03X276386Y319775I155J1192D01*
G01X278315D01*
X278446Y319680D01*
G03X279386Y319375I940J1296D01*
G01X281357D01*
X282124Y320142D01*
X282452D01*
G03X284640Y320189I1069J1193D01*
G01X284705Y320253D01*
X285095Y320424D01*
X285271Y320371D01*
G03X285346Y320350I442J1435D01*
G03X285351Y320349I297J1472D01*
G03X285380Y320342I367J1456D01*
G03X286236Y320405I322J1467D01*
G01X286322Y320437D01*
X286949D01*
X287150Y320343D01*
X287222Y320257D01*
G03X288298Y319717I1155J959D01*
G01X288299D01*
X288614Y319698D01*
X291544D01*
X291560Y319714D01*
X291938D01*
X292064Y319840D01*
X292660Y320437D01*
X294098D01*
X294237Y320321D01*
G03X296163I963J1152D01*
G01X296302Y320437D01*
X298469D01*
X298520Y320385D01*
X307034D01*
G02X307387Y320238I-1J-500D01*
G01X307924Y319701D01*
Y318349D01*
X309137Y317136D01*
X331028D01*
G02X331528Y316636I0J-500D01*
G01Y313614D01*
X331305Y313391D01*
X331146Y313233D01*
Y312631D01*
X329867Y311352D01*
X310448D01*
X308202Y313598D01*
X301546D01*
X301074Y314070D01*
X299599D01*
X299234Y313706D01*
X292410D01*
X291933Y314083D01*
X291886Y314225D01*
G03X290366Y315321I-1520J-506D01*
G01X287467D01*
X286638Y316149D01*
X283751D01*
G03X283544Y316140I-34J-1601D01*
G03X283483Y316133I152J-1594D01*
G03X283399Y316118I239J-1584D01*
G02X282312Y316643I-197J980D01*
G03X279284Y315913I-1426J-730D01*
G01Y313850D01*
X278254Y312819D01*
G03X277888Y312253I1131J-1133D01*
G03X277884Y312243I1484J-600D01*
G03X277784Y311687I1501J-557D01*
G01Y311608D01*
G02X277417Y311126I-500J0D01*
G03X277034Y310960I400J-1448D01*
G03X276907Y310874I777J-1285D01*
G02X275744Y310881I-577J817D01*
G03X275193Y311145I-911J-1194D01*
G01X275039Y311183D01*
X274620Y311668D01*
Y312820D01*
X273488Y313952D01*
Y315913D01*
G03X270284I-1602J0D01*
G01Y313157D01*
G03X270721Y312058I1602J1D01*
G02X270801Y310782I-727J-686D01*
G02X270204Y310616I-404J295D01*
G01X270022Y310692D01*
X269958Y310751D01*
G03X269695Y310944I-1015J-1107D01*
G03X269530Y311026I-750J-1302D01*
G03X268026Y310832I-586J-1383D01*
G02X266862I-582J813D01*
G03X264847Y310669I-918J-1189D01*
G02X263970Y310873I-236J972D01*
G03X263811Y310990I-1027J-1229D01*
G01X263766Y311019D01*
X263728Y311057D01*
G02Y311764I354J353D01*
G01X263818Y311854D01*
X263847Y311876D01*
G03X263865Y311890I-974J1271D01*
G03X263867Y311891I-715J1432D01*
G03X263954Y311963I-977J1269D01*
G03X264488Y313157I-1068J1194D01*
G01Y315913D01*
G03X261284I-1602J0D01*
G01Y313850D01*
X260254Y312819D01*
G03X259803Y311930I1132J-1133D01*
G03X259788Y311797I1582J-246D01*
G03X259785Y311731I1598J-106D01*
G02X259285Y311244I-500J13D01*
G01X259273D01*
X258758Y310730D01*
X258345D01*
X258198Y310876D01*
G03X257345Y311320I-1132J-1133D01*
G01X257165Y311352D01*
X256932Y311630D01*
Y311769D01*
X256050Y312650D01*
X254039D01*
X248740Y307352D01*
X248354Y307333D01*
X248205Y307456D01*
G03X247627Y307752I-957J-1157D01*
G01X247496Y307786D01*
X246721Y308561D01*
X246696Y308596D01*
G03X246660Y308645I-1027J-717D01*
G03X246599Y308717I-985J-773D01*
G02X246615Y309407I370J337D01*
G01X247426Y310218D01*
Y311023D01*
G03X247050Y312107I-1752J0D01*
G02X247005Y313282I786J618D01*
G03X247170Y313600I-1330J892D01*
G01Y313601D01*
X247226Y313746D01*
G37*
G36*
G01X249098Y330067D02*
G02X249578Y330197I353J-354D01*
G03X249805Y330155I386J1451D01*
G03X249959Y330147I155J1494D01*
G01X251258D01*
X251818Y329587D01*
Y329448D01*
G03X251729Y327963I897J-799D01*
G01X251818Y327834D01*
Y326464D01*
X251729Y326335D01*
G03Y324963I986J-686D01*
G01X251818Y324834D01*
Y324219D01*
X251653Y323853D01*
X251587Y323787D01*
G03X251121Y322804I1128J-1137D01*
G01X251104Y322626D01*
X249978Y321500D01*
Y319522D01*
X249710Y319254D01*
X248632D01*
X248622Y319244D01*
X247056D01*
X246818Y319482D01*
Y322987D01*
X246823Y322992D01*
Y325692D01*
X247305Y326182D01*
X247477Y326204D01*
G03X248237Y326528I-186J1490D01*
G03X248736Y328099I-947J1166D01*
G01X248718Y328165D01*
Y329687D01*
X249098Y330067D01*
G37*
G36*
G01X245348Y392871D02*
X246020Y393543D01*
X246924D01*
G02X247424Y393043I0J-500D01*
G01Y391129D01*
X247695Y390858D01*
X248434D01*
X248594Y391018D01*
Y393043D01*
G02X249094Y393543I500J0D01*
G01X249449D01*
G02X249949Y393043I0J-500D01*
G01Y391486D01*
X250232Y391203D01*
X250996D01*
X251144Y391351D01*
Y393043D01*
G02X251644Y393543I500J0D01*
G01X252376D01*
X252745Y393174D01*
Y387063D01*
X252229Y386547D01*
X251369D01*
X251288Y386575D01*
G03X250034I-627J-1795D01*
G01X249953Y386547D01*
X248434D01*
X248114Y386227D01*
Y384922D01*
X247380Y384188D01*
X246076D01*
X246044Y384157D01*
X244172D01*
X243458Y384871D01*
Y385962D01*
G02X243682Y386379I500J0D01*
G01X243807Y386462D01*
X244032D01*
Y386679D01*
G03X244227Y386930I-1399J1288D01*
G01X244256Y386975D01*
X244813Y387532D01*
Y388403D01*
X245842Y389431D01*
Y390885D01*
G03X245335Y392177I-1902J-1D01*
G02X245348Y392871I366J340D01*
G37*
G36*
G01X243893Y395611D02*
X242751Y396753D01*
Y406390D01*
G02X243251Y406890I500J0D01*
G01X257102D01*
X257163Y406829D01*
Y396125D01*
X256649Y395611D01*
X243893D01*
G37*
G36*
G01X254710Y468744D02*
Y475408D01*
G02X255210Y475908I500J0D01*
G01X256030D01*
X256384Y475553D01*
Y468744D01*
G02X255884Y468244I-500J0D01*
G01X255210D01*
G02X254710Y468744I0J500D01*
G37*
G36*
G01X255995Y627647D02*
X257633Y629285D01*
X260146D01*
X262045Y631184D01*
Y644412D01*
X278884D01*
X281289Y642007D01*
Y632845D01*
Y593794D01*
X279103Y591608D01*
X257465D01*
X255995Y593078D01*
Y627647D01*
G37*
G36*
G01X272641Y26954D02*
Y23081D01*
Y22168D01*
X272772Y22037D01*
X272780D01*
X276300D01*
X276487Y21850D01*
X276537Y21800D01*
Y17972D01*
X276633Y17876D01*
X277043Y17466D01*
Y13726D01*
X277822Y12947D01*
X281490D01*
X281562Y13019D01*
Y17253D01*
X281517Y17298D01*
Y19018D01*
X279315Y21220D01*
X279305Y21230D01*
Y22206D01*
Y28598D01*
X279301Y28602D01*
X272695D01*
X272641Y28548D01*
Y26954D01*
G37*
G36*
G01X265610Y41690D02*
X269207D01*
X269458Y41439D01*
Y35885D01*
X269379Y35806D01*
X265809D01*
X265336D01*
X265119Y36023D01*
Y41629D01*
X265180Y41690D01*
X265610D01*
G37*
G36*
G01X275363Y29639D02*
X275407Y29683D01*
Y41373D01*
X275063Y41717D01*
X270939D01*
X270581Y41360D01*
Y35172D01*
X270681Y35072D01*
X271447D01*
X273007D01*
X273251Y34828D01*
X274512Y33567D01*
Y32960D01*
X274548Y32924D01*
Y29681D01*
X274590Y29639D01*
X275363D01*
G37*
G36*
G01X276558Y29644D02*
X279295D01*
X279362Y29711D01*
Y32267D01*
Y32403D01*
X281659Y34700D01*
X282271Y35312D01*
Y36347D01*
Y38728D01*
Y46000D01*
Y54408D01*
X281870Y54809D01*
X274096D01*
X273560Y54273D01*
X273180Y53893D01*
Y47641D01*
Y46726D01*
X275140Y44766D01*
X276558Y43348D01*
Y42618D01*
Y37061D01*
Y29644D01*
G37*
G36*
G01X266765Y62211D02*
X266270Y62706D01*
Y69018D01*
X266388Y69136D01*
X327330D01*
G02X327830Y68636I0J-500D01*
G01Y62231D01*
X327810Y62211D01*
X266765D01*
G37*
G36*
G01X266470Y102566D02*
G03I-640J0D01*
G37*
G36*
G01X264850Y96914D02*
G03I-640J0D01*
G37*
G36*
G01X264874Y295150D02*
G02X263699Y295083I-634J774D01*
G03X263297Y295263I-794J-1234D01*
G02X262940Y295836I135J482D01*
G03X261806Y297573I-1477J275D01*
G01X261667Y297606D01*
X260798Y298475D01*
G02Y299182I354J353D01*
G01X262162Y300545D01*
X262293Y300579D01*
G03X263297Y301446I-379J1453D01*
G02X263943Y301714I460J-196D01*
G03X264097Y301662I557J1395D01*
G02X264807Y300496I-269J-963D01*
G03X265020Y299591I1079J-224D01*
G02X264985Y298311I-786J-619D01*
G03X264684Y297517I900J-795D01*
G01Y296980D01*
X264996Y296669D01*
G02X264903Y295173I-707J-707D01*
G03X264874Y295150I919J-1188D01*
G37*
G36*
G01X268108Y285549D02*
G03X267969Y285409I780J-914D01*
G02X267587Y285233I-381J324D01*
G01X267380D01*
X267088Y285525D01*
Y286820D01*
X267133Y286919D01*
G03X267268Y287626I-1365J627D01*
G02X267867Y288596I999J53D01*
G03X268236Y288847I-480J1102D01*
G01X268999Y289611D01*
X269162Y289635D01*
G03X270129Y291949I-219J1451D01*
G02X270110Y293099I809J589D01*
G03X269252Y295394I-1243J843D01*
G02X268883Y295919I129J483D01*
G03X268888Y296008I-1497J129D01*
G02X269231Y296470I500J-13D01*
G03X269752Y298199I-345J1047D01*
G02X269787Y299479I786J619D01*
G03X270088Y300273I-900J795D01*
G01Y301257D01*
X270192Y301467D01*
X270286Y301538D01*
G03X269505Y304233I-906J1198D01*
G02X268588Y305229I83J996D01*
G01Y305337D01*
G03X268587Y305376I-1202J-11D01*
G02X269586Y306409I999J33D01*
G01X271186D01*
G02X272185Y305376I0J-1000D01*
G03X272536Y304487I1201J-40D01*
G01X272822Y304202D01*
X272891Y303941D01*
X272855Y303811D01*
G03X273539Y302120I1448J-398D01*
G02X273913Y300790I-509J-861D01*
G03X274054Y299551I973J-517D01*
G02Y298239I-755J-656D01*
G03X273789Y297411I832J-723D01*
G02X273373Y296869I-498J-49D01*
G03X272484Y294402I245J-1482D01*
G02X272517Y293131I-755J-656D01*
G03X272736Y291563I869J-678D01*
G01X272768Y291540D01*
X272795Y291512D01*
G02Y290805I-353J-353D01*
G01X272536Y290547D01*
G03X272994Y288561I850J-850D01*
G02X272984Y287613I-164J-472D01*
G03X272544Y287385I462J-1429D01*
G02X271344I-600J800D01*
G03X268982Y286526I-900J-1202D01*
G01X268949Y286387D01*
X268124Y285562D01*
X268108Y285549D01*
G37*
G36*
G01X262473Y303428D02*
G03X261835Y303533I-557J-1395D01*
G02X261312Y303974I-26J499D01*
G03X260206Y305251I-1492J-174D01*
G01X260077Y305286D01*
X259807Y305555D01*
G02X260161Y306409I353J354D01*
G01X262186D01*
G02X263185Y305376I0J-1000D01*
G03X263184Y305337I1201J-50D01*
G01Y304820D01*
X263300Y304705D01*
Y304022D01*
X263224Y303900D01*
G03X263119Y303696I1279J-787D01*
G02X262473Y303428I-460J196D01*
G37*
G36*
G01X296088Y340150D02*
X295150Y339212D01*
X294501D01*
X294420Y339130D01*
G02X294065Y338983I-354J353D01*
G01X293822D01*
X293734Y338895D01*
X293727D01*
X291533Y336701D01*
X287433D01*
X287420Y336689D01*
X287283Y336552D01*
X286895Y336163D01*
X286220Y335489D01*
X285603D01*
G03X285194Y335417I1J-1202D01*
G01X285111Y335387D01*
X282818D01*
X280518Y337687D01*
X280117D01*
X279986Y337818D01*
X279432D01*
G03X279116Y337788I-45J-1201D01*
G03X278734Y337626I271J-1170D01*
G03X278244Y336990I652J-1009D01*
G01X278207Y336876D01*
X277118Y335787D01*
X275518D01*
X272920Y338385D01*
Y339489D01*
X272956Y339525D01*
G03X273336Y339765I-603J1376D01*
G01X273477Y339887D01*
X273747D01*
X276141Y342281D01*
Y342381D01*
X276382Y342527D01*
G03Y345095I-780J1284D01*
G01X276269Y345163D01*
X276141Y345391D01*
Y346144D01*
G02X276288Y346499I500J1D01*
G01X276488Y346698D01*
Y349506D01*
Y353046D01*
X277229Y353787D01*
X293752D01*
X295873Y351666D01*
X295881Y351657D01*
G03X295970Y351568I1035J946D01*
G01X295979Y351560D01*
X296235Y351304D01*
Y340503D01*
G02X296088Y340150I-500J1D01*
G37*
G36*
G01X265339Y425163D02*
Y435729D01*
X266560Y436950D01*
X277101D01*
X281650D01*
X283112Y435488D01*
Y417748D01*
X281582Y416218D01*
X273300D01*
X270545D01*
X268860Y417903D01*
Y420658D01*
Y421642D01*
X267891Y422611D01*
X265339Y425163D01*
G37*
G36*
G01X279277Y439119D02*
X275055D01*
X271393D01*
X271368Y439094D01*
X271174D01*
X269881D01*
X269808Y439167D01*
Y448270D01*
X270906Y449368D01*
X272102D01*
X272230Y449496D01*
X279807D01*
X279842Y449462D01*
X282959D01*
X294991D01*
X296330Y448123D01*
Y441962D01*
X293487Y439119D01*
X281974D01*
X279277D01*
G37*
G36*
G01X259992Y468819D02*
Y475483D01*
G02X260492Y475983I500J0D01*
G01X261126D01*
G02X261626Y475483I0J-500D01*
G01Y468748D01*
X261197Y468319D01*
X260492D01*
G02X259992Y468819I0J500D01*
G37*
G36*
G01X282820Y10253D02*
G03I-640J0D01*
G37*
G36*
G01X280447Y26853D02*
X299844D01*
X300358Y26339D01*
Y13738D01*
Y13077D01*
X300227Y12946D01*
X282956D01*
X282665Y13237D01*
Y13607D01*
Y19787D01*
X280476Y21976D01*
X280325Y22127D01*
Y22883D01*
Y23920D01*
X280339Y23934D01*
X280325Y23948D01*
Y24869D01*
Y25861D01*
X280369Y25905D01*
X280325Y25949D01*
Y26731D01*
X280447Y26853D01*
G37*
G36*
G01X282135Y33307D02*
X289279D01*
X289570Y33016D01*
Y28864D01*
X288592Y27886D01*
X280553D01*
X280458Y27981D01*
Y31630D01*
X282135Y33307D01*
G37*
G36*
G01X296653Y35494D02*
X293217D01*
X283643D01*
Y46177D01*
Y54486D01*
X284325Y55168D01*
X297855D01*
X297859Y55164D01*
X300080Y52943D01*
Y37405D01*
X298169Y35494D01*
X296653D01*
G37*
G36*
G01X279650Y104889D02*
G03I-640J0D01*
G37*
G36*
G01X287350Y95717D02*
G03I-640J0D01*
G37*
G36*
G01X283756Y290220D02*
G03X284113Y290114I516J1085D01*
G02X284547Y289619I-66J-496D01*
G01X284546Y285839D01*
X284637Y285749D01*
X284670Y285610D01*
G03X285169Y284800I1462J342D01*
G02X285312Y284229I-321J-384D01*
G03X285315Y283321I1114J-450D01*
G02X284941Y282106I-925J-380D01*
G03X284503Y280620I662J-1003D01*
G02X284398Y280066I-458J-200D01*
G01X283940Y279607D01*
Y278842D01*
G02X283440Y278342I-500J0D01*
G01X283313D01*
X283091Y278462D01*
X283022Y278568D01*
G03X282557Y279020I-1255J-826D01*
G02X282320Y279445I263J425D01*
G01Y282143D01*
X281736Y282727D01*
G03X281591Y282850I-848J-852D01*
G02Y283660I293J405D01*
G03X282088Y284633I-704J973D01*
G01Y287358D01*
X282520Y287790D01*
Y289186D01*
G02X282719Y289586I500J1D01*
G03X283111Y290023I-900J1202D01*
G02X283756Y290220I430J-255D01*
G37*
G36*
G01X281076Y302556D02*
G03X279665Y304768I-1322J713D01*
G02X279282Y304914I-29J499D01*
G01X278641Y305555D01*
G02X278994Y306409I353J354D01*
G01X282787D01*
X283061Y306189D01*
X283099Y306017D01*
G03X283169Y305801I1173J261D01*
G02X282828Y304588I-918J-396D01*
G03X283199Y302450I693J-981D01*
G01X283325Y302414D01*
X283924Y301815D01*
Y300048D01*
X284495Y299478D01*
X284565Y299225D01*
X284534Y299097D01*
G03X284502Y298873I1069J-267D01*
G02X283604Y297916I-999J38D01*
G03X284305Y295889I112J-1096D01*
G02X285675Y295593I534J-845D01*
G03X285746Y295498I917J611D01*
G01X285869Y295348D01*
X285851Y294964D01*
X284826Y293940D01*
Y293559D01*
X283422Y292155D01*
G03X283362Y292089I858J-841D01*
G02X282692Y292009I-379J326D01*
G03X280356Y291130I-874J-1222D01*
G01X280323Y290991D01*
X280116Y290785D01*
Y288786D01*
X279701Y288370D01*
X279442Y288301D01*
X279312Y288336D01*
G03X279261Y288349I-396J-1448D01*
G01X279122Y288382D01*
X277570Y289934D01*
X277534Y290052D01*
G03X277287Y290491I-1147J-356D01*
G02X277252Y291771I751J661D01*
G03X276387Y293555I-866J682D01*
G02X275888Y294055I1J500D01*
G01Y294817D01*
X275113Y295591D01*
X275080Y295730D01*
G03X275037Y295878I-1462J-344D01*
G02X275315Y296502I473J163D01*
G03X275672Y296745I-429J1015D01*
G02X277100I714J-701D01*
G03X278752Y298199I786J772D01*
G02X278787Y299479I786J619D01*
G03X278984Y299785I-900J796D01*
G02X279892Y299798I457J-203D01*
G03X281447Y301221I994J475D01*
G02X281076Y302556I509J861D01*
G37*
G36*
G01X284972Y472834D02*
G03I-640J0D01*
G37*
G36*
G01X302499Y588257D02*
X292661D01*
X287722D01*
X286615Y589364D01*
Y598194D01*
X287520Y599099D01*
X293084D01*
X302658D01*
Y588416D01*
X302499Y588257D01*
G37*
G36*
G01X305854Y607740D02*
X286457D01*
X285943Y608254D01*
Y620780D01*
X286417Y621254D01*
X303160D01*
X303636Y620778D01*
Y614806D01*
X305825Y612617D01*
X305976Y612466D01*
Y607862D01*
X305854Y607740D01*
G37*
G36*
G01X295440Y100593D02*
G03I-640J0D01*
G37*
G36*
G01X296130Y97209D02*
G03I-640J0D01*
G37*
G36*
G01X303010Y95215D02*
G03I-640J0D01*
G37*
G36*
G01X300750Y250987D02*
G03I-632J0D01*
G37*
G36*
G01X300602Y375609D02*
X305932D01*
X306381Y375160D01*
Y371351D01*
X306226Y371196D01*
X300339D01*
X300316Y371219D01*
Y375323D01*
X300602Y375609D01*
G37*
G36*
G01X297288Y385628D02*
X298148Y386488D01*
X304164D01*
X304558Y386094D01*
Y384590D01*
X303340Y383372D01*
X303233D01*
X302875Y383014D01*
Y379469D01*
X302445Y379039D01*
X297432D01*
X297288Y379183D01*
Y385628D01*
G37*
G36*
G01X297575Y400203D02*
X301692D01*
X301872Y400023D01*
Y387777D01*
X301693Y387598D01*
X297897D01*
X297002Y388493D01*
Y399630D01*
X297575Y400203D01*
G37*
G36*
G01X308584Y388135D02*
X304219D01*
X303544Y388810D01*
Y397522D01*
X303473Y397593D01*
Y400674D01*
X306203Y403404D01*
X329202D01*
X330569Y402037D01*
Y390269D01*
X329485Y389185D01*
X317385D01*
X316732Y389838D01*
X310613D01*
X310540Y389764D01*
X310213D01*
X308584Y388135D01*
G37*
G36*
G01X291967Y466811D02*
G03I-640J0D01*
G37*
G36*
G01X304030Y599281D02*
X306939Y602190D01*
Y604882D01*
X307006Y604949D01*
X310866D01*
X310899Y604915D01*
X310938Y604954D01*
X311711D01*
X311753Y604912D01*
Y601669D01*
X311789Y601633D01*
Y601026D01*
X313294Y599521D01*
Y595633D01*
X314271Y594656D01*
Y590075D01*
X313631Y589435D01*
X312771Y588574D01*
X304049D01*
X304030Y588593D01*
Y599281D01*
G37*
G36*
G01X304166Y601286D02*
X297022D01*
X296731Y601577D01*
Y605729D01*
X297709Y606707D01*
X305748D01*
X305843Y606612D01*
Y602963D01*
X304166Y601286D01*
G37*
G36*
G01X313660Y607639D02*
Y611512D01*
Y612425D01*
X313529Y612556D01*
X313521D01*
X310001D01*
X309814Y612743D01*
X309764Y612793D01*
Y616621D01*
X309668Y616717D01*
X309258Y617127D01*
Y620867D01*
X308479Y621646D01*
X304811D01*
X304739Y621574D01*
Y617340D01*
X304784Y617295D01*
Y615575D01*
X306986Y613373D01*
X306996Y613363D01*
Y612387D01*
Y605995D01*
X307000Y605991D01*
X313606D01*
X313660Y606045D01*
Y607639D01*
G37*
G36*
G01X314578Y34458D02*
X330224D01*
X330806Y33876D01*
Y7739D01*
X329682Y6615D01*
X315560D01*
X314184D01*
X313127D01*
X312279Y7463D01*
Y34067D01*
X312670Y34458D01*
X314578D01*
G37*
G36*
G01X315470Y92851D02*
G03I-640J0D01*
G37*
G36*
G01X312052Y250230D02*
G03I-632J0D01*
G37*
G36*
G01X316042Y258656D02*
G03I-632J0D01*
G37*
G36*
G01X341290Y288980D02*
X338157Y292113D01*
X328930D01*
X327139Y293904D01*
X325942D01*
Y294016D01*
X322940D01*
Y293904D01*
X322026D01*
X321876Y294054D01*
X321376D01*
X318872D01*
X318722Y293904D01*
X315534D01*
G02X315034Y294404I0J500D01*
G01Y296826D01*
X315395Y297187D01*
X318497D01*
X319292Y297982D01*
X331376D01*
G03Y301784I0J1901D01*
G01X319940D01*
Y301805D01*
X319291Y302454D01*
X315250D01*
X315034Y302670D01*
Y309805D01*
X315185Y309956D01*
X329011D01*
X330254Y308713D01*
X334858D01*
X335886Y307685D01*
Y296894D01*
X336437Y296343D01*
X343744D01*
X346138Y293950D01*
X360422D01*
X361614Y295142D01*
Y306347D01*
X361304Y306658D01*
Y306837D01*
X356965Y311176D01*
X351583D01*
X350980Y310573D01*
Y309748D01*
Y307736D01*
X350440Y307196D01*
X346600D01*
G02X346122Y307673I21J500D01*
G01Y308425D01*
X344878Y309669D01*
Y311508D01*
X344932Y311562D01*
Y314231D01*
G02X345432Y314709I500J-23D01*
G01X351893D01*
X352384Y315200D01*
X352857D01*
X352920Y315264D01*
X357801D01*
X358655Y314410D01*
X364674D01*
X364916Y314653D01*
X375566D01*
X377890Y312329D01*
Y306610D01*
X377160Y305880D01*
Y293323D01*
X372817Y288980D01*
X341290D01*
G37*
G36*
G01X309552Y318138D02*
X308926Y318764D01*
Y320116D01*
X307970Y321072D01*
Y322227D01*
X310389Y324646D01*
X310816D01*
X310938Y324569D01*
G03X312542I802J1270D01*
G01X312664Y324646D01*
X313610D01*
X314565Y323691D01*
X331064D01*
G02X331564Y323191I0J-500D01*
G01Y318638D01*
G02X331064Y318138I-500J0D01*
G01X309552D01*
G37*
G36*
G01X325404Y384628D02*
X328191Y381840D01*
Y379036D01*
X326339Y377184D01*
Y373861D01*
X326314Y373836D01*
Y362482D01*
X326081Y362249D01*
X317232D01*
X316802Y362679D01*
Y363717D01*
X316862Y363777D01*
Y367656D01*
G03X316814Y368090I-2002J-2D01*
G01X316802Y368143D01*
Y378379D01*
X317049Y378661D01*
X317235Y378687D01*
G03X317667Y378798I-254J1884D01*
G03X318031Y378986I-685J1774D01*
G01X318157Y379070D01*
X318382D01*
Y379275D01*
X318486Y379410D01*
G03Y381732I-1506J1161D01*
G01X318382Y381867D01*
Y382072D01*
X318375D01*
G02X318021Y382219I0J500D01*
G01X317660Y382581D01*
Y385312D01*
X317343Y385628D01*
X317290Y385681D01*
G02X317297Y386381I361J346D01*
G01X318059Y387143D01*
X321600D01*
G02X321768Y387114I0J-501D01*
G01X323553D01*
X323634Y387143D01*
X324464D01*
X324661Y386946D01*
Y385370D01*
X325320Y384710D01*
Y384628D01*
X325404D01*
G37*
G36*
G01X310488Y570631D02*
Y544275D01*
X311063Y543700D01*
X314908D01*
X315388Y544180D01*
Y544603D01*
Y548368D01*
X317788Y550768D01*
Y558803D01*
X316288Y560303D01*
Y566703D01*
X318488Y568903D01*
X323788D01*
X324288Y569403D01*
Y574903D01*
X322888Y576303D01*
X316160D01*
X310488Y570631D01*
G37*
G36*
G01X325153Y566703D02*
X319188D01*
X317841D01*
X317456Y566318D01*
Y561354D01*
X318207Y560603D01*
X318388D01*
X324388D01*
X326745D01*
X326946Y560804D01*
Y564910D01*
X325153Y566703D01*
G37*
G36*
G01X331849Y33907D02*
X340306D01*
X342246Y31967D01*
Y7743D01*
X341276Y6773D01*
X332538D01*
X331849Y7462D01*
Y33907D01*
G37*
G36*
G01X328590Y101057D02*
G03I-640J0D01*
G37*
G36*
G01X323640Y94337D02*
G03I-640J0D01*
G37*
G36*
G01X337257Y297403D02*
X336896Y297764D01*
Y308731D01*
X337324Y309159D01*
G02X337702Y309305I354J-354D01*
G03X338712Y309632I72J1500D01*
G01X338849Y309741D01*
X343390D01*
X345121Y308010D01*
Y298124D01*
X344400Y297403D01*
X337257D01*
G37*
G36*
G01X343931Y311977D02*
X343318Y311364D01*
X339344D01*
X339118Y311490D01*
X339049Y311600D01*
G03X337302Y312231I-1275J-795D01*
G03X336517Y312334I-581J-1385D01*
G02X336029Y313194I512J859D01*
G01Y323169D01*
G02X336176Y323522I500J-1D01*
G01X336646Y323992D01*
X340181D01*
X340302Y324005D01*
X340426Y324018D01*
G03X340629Y324049I-200J1992D01*
G01X340679Y324060D01*
X342921D01*
X342989Y323992D01*
X342990D01*
X343784Y323198D01*
G02X343931Y322845I-353J-354D01*
G01Y311977D01*
G37*
G36*
G01X329032Y362707D02*
Y363864D01*
X329057Y363889D01*
X329078D01*
Y377045D01*
X329562Y377529D01*
X336608D01*
X338071Y376066D01*
Y363306D01*
X336931Y362166D01*
X329032D01*
Y362707D01*
G37*
G36*
G01X338572Y546620D02*
X336572Y548620D01*
Y552564D01*
X336095Y553041D01*
X322680D01*
X322648Y553073D01*
X322470D01*
X322182Y553362D01*
Y557833D01*
X322100Y557914D01*
Y559465D01*
X322236Y559602D01*
X325180D01*
X325313Y559469D01*
X332969D01*
X333150Y559650D01*
X333351D01*
X333390Y559689D01*
X334545D01*
X334560Y559674D01*
X335810D01*
X336669Y560533D01*
X336740D01*
Y563064D01*
X337450Y563774D01*
X350268D01*
X350720Y563322D01*
Y549360D01*
X347980Y546620D01*
X338572D01*
G37*
G36*
G01X331930Y551928D02*
Y546402D01*
Y545823D01*
X331924Y545818D01*
Y545807D01*
X331114Y544997D01*
Y544169D01*
Y540335D01*
X331348Y540101D01*
X332980D01*
X333131Y540252D01*
Y542123D01*
X333798Y542790D01*
Y544669D01*
Y545035D01*
X332926Y545907D01*
Y547765D01*
Y548208D01*
Y551907D01*
X332833Y552000D01*
X332002D01*
X331930Y551928D01*
G37*
G36*
G01X332936Y560651D02*
X332988Y560703D01*
Y564903D01*
X333990Y565905D01*
Y574201D01*
X333288Y574903D01*
X327188D01*
X326888Y574603D01*
Y573103D01*
Y567003D01*
X327888Y566003D01*
X327930Y565961D01*
X327971Y565920D01*
Y560720D01*
X328040Y560651D01*
X332936D01*
G37*
G36*
G01X346458Y597636D02*
X340500D01*
X336342Y601794D01*
Y607898D01*
X336137Y608103D01*
Y623924D01*
X336983Y624770D01*
X345769D01*
X346458Y624081D01*
Y597636D01*
G37*
G36*
G01X345410Y101718D02*
G03I-640J0D01*
G37*
G36*
G01X352433Y105404D02*
G03I-640J0D01*
G37*
G36*
G01X352410Y305739D02*
G03X355210Y305576I1431J455D01*
G03X353325Y307605I-1369J619D01*
G02X351982Y308544I-343J939D01*
G01Y310158D01*
X351998Y310174D01*
X356550D01*
X360302Y306422D01*
Y297255D01*
X358470Y295423D01*
X346160D01*
X345707Y295876D01*
Y297294D01*
X346122Y297709D01*
Y305506D01*
X346810Y306194D01*
X350867D01*
G02X352410Y305739I603J-798D01*
G37*
G36*
G01X351179Y327012D02*
X350451Y327740D01*
X349690D01*
G02X349190Y328240I0J500D01*
G01Y335216D01*
G02X349690Y335716I500J0D01*
G01X361900D01*
G02X362400Y335216I0J-500D01*
G01Y327512D01*
G02X361900Y327012I-500J0D01*
G01X351179D01*
G37*
G36*
G01X359070Y315412D02*
X358216Y316266D01*
X352501D01*
X352438Y316202D01*
X350320D01*
X350314Y316196D01*
X345530D01*
G02X345030Y316696I0J500D01*
G01Y323374D01*
X345394Y323738D01*
X348064D01*
X349529Y322272D01*
X362374D01*
X362575Y322072D01*
X362771D01*
X363071Y321772D01*
X363567D01*
X365550Y319788D01*
Y316703D01*
X364259Y315412D01*
X359070D01*
G37*
G36*
G01X339149Y327366D02*
X338190Y328325D01*
Y334396D01*
X339060Y335266D01*
X347140D01*
X347730Y334676D01*
Y327978D01*
X347492Y327740D01*
X344720D01*
G03X343667Y327441I-1J-2001D01*
G01X343546Y327366D01*
X339149D01*
G37*
G36*
G01X363729Y597085D02*
X348083D01*
X347501Y597667D01*
Y623804D01*
X348625Y624928D01*
X362747D01*
X364123D01*
X365180D01*
X366028Y624080D01*
Y597476D01*
X365637Y597085D01*
X363729D01*
G37*
G36*
G01X362940Y98674D02*
G03I-640J0D01*
G37*
G36*
G01X364839Y526853D02*
X364310Y527382D01*
Y532783D01*
X365028Y533501D01*
X382919D01*
X383542Y532878D01*
X383894Y532526D01*
X384356Y532064D01*
X391396D01*
X392251Y531209D01*
Y527679D01*
Y519802D01*
X384278D01*
X383787Y520293D01*
Y523755D01*
X380689Y526853D01*
X364839D01*
G37*
G36*
G01X370620Y547262D02*
Y542270D01*
X370545Y542195D01*
X364317D01*
X364237Y542275D01*
Y547130D01*
X364635Y547528D01*
X370354D01*
X370620Y547262D01*
G37*
G36*
G01X369565Y541103D02*
X371884Y538784D01*
Y538654D01*
Y534630D01*
X371817Y534563D01*
X360750D01*
X359009Y536304D01*
Y540891D01*
X359221Y541103D01*
X369565D01*
G37*
G36*
G01X372642Y539443D02*
X371054Y541030D01*
Y541288D01*
X371622Y541855D01*
Y547677D01*
X370769Y548529D01*
X370506D01*
X368447Y550588D01*
Y552217D01*
G02X368947Y552717I500J0D01*
G01X373338D01*
G02X373838Y552217I0J-500D01*
G01Y543725D01*
X373780Y543668D01*
Y539833D01*
X373838Y539776D01*
Y539453D01*
G02Y539443I-500J-5D01*
G01X372642D01*
G37*
G36*
G01X372050Y35349D02*
X372210Y35509D01*
X375609D01*
X375860Y35258D01*
Y21693D01*
X375010Y20843D01*
Y16895D01*
X374538Y16423D01*
X370400D01*
X369550Y17273D01*
Y21348D01*
X372050Y23848D01*
Y35349D01*
G37*
G36*
G01X373260Y98355D02*
G03I-640J0D01*
G37*
G36*
G01X384730Y98743D02*
G03I-640J0D01*
G37*
G36*
G01X379800Y102923D02*
G03I-640J0D01*
G37*
G36*
G01X369920Y415600D02*
G03I-640J0D01*
G37*
G36*
G01X375200Y412421D02*
G03I-640J0D01*
G37*
G36*
G01X376790Y430405D02*
G03I-640J0D01*
G37*
G36*
G01X374490Y496585D02*
G03I-640J0D01*
G37*
G36*
G01X371130Y510592D02*
X371885Y511347D01*
X380349D01*
X380764Y510932D01*
Y505603D01*
X380122Y504961D01*
X372339D01*
X371130Y506170D01*
Y510592D01*
G37*
G36*
G01X384524Y518301D02*
Y517196D01*
G02X384003Y516697I-500J1D01*
G03X383924Y516699I-88J-1900D01*
G01X380786D01*
G03X380338Y516645I2J-1902D01*
G02X379102Y517617I-236J972D01*
G01Y519562D01*
X379140Y519600D01*
X383064D01*
X383863Y518801D01*
X384024D01*
G02X384524Y518301I0J-500D01*
G37*
G36*
G01X371828Y512441D02*
X371621Y512648D01*
Y519836D01*
X372887Y521102D01*
Y521504D01*
X372914Y521530D01*
Y524166D01*
G03X372894Y524412I-1502J2D01*
G01X372887Y524452D01*
Y525352D01*
G02X373387Y525852I500J0D01*
G01X377770D01*
X377778Y525843D01*
Y521533D01*
X377784Y521527D01*
Y520186D01*
X377855Y520116D01*
Y512856D01*
X377440Y512441D01*
X371828D01*
G37*
G36*
G01X383729Y546270D02*
Y550059D01*
Y551241D01*
X381682Y553288D01*
Y555329D01*
X382428Y556075D01*
X384380D01*
X389155D01*
X389946Y555284D01*
Y554586D01*
Y546221D01*
X383778D01*
X383729Y546270D01*
G37*
G36*
G01X381924Y550466D02*
Y546097D01*
Y545557D01*
X381754Y545387D01*
X380979D01*
X378173D01*
X375502D01*
X374896Y545993D01*
Y552822D01*
G02X375396Y553322I500J0D01*
G01X379068D01*
X381924Y550466D01*
G37*
G36*
G01X383344Y534659D02*
X378902D01*
X375311D01*
X375232Y534739D01*
X375241Y534748D01*
Y540559D01*
Y541190D01*
X374782Y541649D01*
Y543253D01*
X375481Y543952D01*
X375500D01*
X375770Y544222D01*
X389849D01*
X390190Y543881D01*
Y540588D01*
X392155Y538623D01*
Y535003D01*
X390560Y533408D01*
X386316D01*
X385065Y534659D01*
X383344D01*
G37*
G36*
G01X395092Y588393D02*
X385254D01*
X382005D01*
X380746Y589652D01*
Y598129D01*
X381852Y599235D01*
X385677D01*
X395251D01*
Y588552D01*
X395092Y588393D01*
G37*
G36*
G01X398447Y607876D02*
X388573D01*
X388125Y607428D01*
Y604817D01*
X387577Y604269D01*
X381304D01*
X378010D01*
X376380Y605899D01*
Y621122D01*
X377041Y621783D01*
X381771D01*
X395938D01*
X396229Y621492D01*
Y621122D01*
Y614942D01*
X398418Y612753D01*
X398569Y612602D01*
Y607998D01*
X398447Y607876D01*
G37*
G36*
G01X387866Y35146D02*
X388260Y35540D01*
X391600D01*
X393850Y33290D01*
Y16384D01*
X393017Y15551D01*
X388491D01*
X387866Y16176D01*
Y35146D01*
G37*
G36*
G01X399460Y95823D02*
G03I-640J0D01*
G37*
G36*
G01X399790Y131773D02*
G03I-640J0D01*
G37*
G36*
G01X392520Y131692D02*
G03I-640J0D01*
G37*
G36*
G01X400490Y249696D02*
G03I-640J0D01*
G37*
G36*
G01X392640Y258265D02*
G03I-640J0D01*
G37*
G36*
G01X399930Y257245D02*
G03I-640J0D01*
G37*
G36*
G01X393290Y272539D02*
G03I-640J0D01*
G37*
G36*
G01X396710Y283930D02*
G03I-640J0D01*
G37*
G36*
G01X413386Y357465D02*
G02I0J19700D01*
G37*
G36*
G01X404920Y463441D02*
X404960Y463401D01*
Y450560D01*
X408040Y447480D01*
X412177D01*
X412650Y447007D01*
Y410408D01*
X411110Y408868D01*
X399170D01*
X397050Y410988D01*
Y462318D01*
X398173Y463441D01*
X404920D01*
G37*
G36*
G01X389747Y492097D02*
G03I-640J0D01*
G37*
G36*
G01X402336Y605085D02*
X399599D01*
X399532Y605018D01*
Y602462D01*
Y602326D01*
X397235Y600029D01*
X396623Y599417D01*
Y598382D01*
Y596001D01*
Y588729D01*
Y586328D01*
X397195Y585756D01*
X401813D01*
X402317Y586260D01*
Y589760D01*
Y592111D01*
X402336D01*
Y597668D01*
Y605085D01*
G37*
G36*
G01X406253Y607775D02*
Y611648D01*
Y612561D01*
X406122Y612692D01*
X406114D01*
X402594D01*
X402407Y612879D01*
X402357Y612929D01*
Y616757D01*
X402261Y616853D01*
X401851Y617263D01*
Y621003D01*
X401072Y621782D01*
X397404D01*
X397332Y621710D01*
Y617476D01*
X397377Y617431D01*
Y615711D01*
X399579Y613509D01*
X399589Y613499D01*
Y612523D01*
Y606131D01*
X399593Y606127D01*
X406199D01*
X406253Y606181D01*
Y607775D01*
G37*
G36*
G01X396759Y601422D02*
X389615D01*
X389324Y601713D01*
Y605865D01*
X390302Y606843D01*
X398341D01*
X398436Y606748D01*
Y603099D01*
X396759Y601422D01*
G37*
G36*
G01X400907Y684029D02*
G03I-640J0D01*
G37*
G36*
G01X408437Y65813D02*
X406073Y68177D01*
Y81648D01*
X406119Y81747D01*
G03X406280Y82480I-1591J734D01*
G01Y88702D01*
G03X406119Y89435I-1752J-1D01*
G01X406073Y89534D01*
Y93060D01*
X406133Y93171D01*
G03X406226Y93378I-1320J717D01*
G02X406848Y93686I471J-169D01*
G03X407210Y93618I456J1431D01*
G02X407618Y92880I-31J-499D01*
G03X409495Y93678I1442J-785D01*
G02X408778Y94832I265J964D01*
G03X407646Y96579I-1475J285D01*
G01X407507Y96612D01*
X406904Y97215D01*
Y109766D01*
X407380Y110242D01*
Y118616D01*
X407834Y119070D01*
G02X408187Y119217I354J-353D01*
G01X430318D01*
G02X430818Y118717I0J-500D01*
G01Y116165D01*
X432462Y114520D01*
X453683D01*
G02X454183Y114020I0J-500D01*
G01Y101151D01*
X454678Y100656D01*
Y97992D01*
X453896Y97210D01*
X453396D01*
X451979Y98628D01*
G03X449851Y98623I-1062J-1062D01*
G01X449850D01*
Y98622D01*
G02X449142I-354J353D01*
G01X447764Y100000D01*
Y103582D01*
X443562D01*
Y100316D01*
G02X443062Y99816I-500J0D01*
G01X438082D01*
X435520Y97254D01*
Y97103D01*
X424970Y86553D01*
Y69044D01*
X421739Y65813D01*
X408437D01*
G37*
G36*
G01X409700Y92095D02*
G03I-640J0D01*
G37*
G36*
G01X402310Y93807D02*
G03I-640J0D01*
G37*
G36*
G01X440383Y156487D02*
Y135987D01*
X438683Y134287D01*
X412133D01*
X411643Y134777D01*
Y155277D01*
X411648Y155282D01*
Y161392D01*
X413883Y163627D01*
X438693D01*
X440383Y161937D01*
Y156487D01*
G37*
G36*
G01X419622Y256578D02*
X417460Y258740D01*
X417440D01*
X417224Y258956D01*
X407917D01*
X407904Y258969D01*
Y259910D01*
X407972Y259978D01*
X417817D01*
X418080Y260240D01*
X419811D01*
X419946Y260138D01*
G03X421913Y260262I912J1193D01*
G02X422264Y260406I351J-356D01*
G01X429380D01*
G02X429880Y259906I0J-500D01*
G01Y257308D01*
X429150Y256578D01*
X419622D01*
G37*
G36*
G01X401590Y293145D02*
G03I-640J0D01*
G37*
G36*
G01X417150Y408642D02*
X415380Y410412D01*
Y447301D01*
X413724Y448957D01*
X408880D01*
X408110Y449727D01*
Y463025D01*
X408880Y463795D01*
X413371D01*
X417982Y459184D01*
X426746D01*
G02X427246Y458684I0J-500D01*
G01Y457692D01*
X427424D01*
G02X427754Y457568I0J-500D01*
G03X429740I993J1126D01*
G02X430070Y457692I330J-376D01*
G01X430248D01*
Y458684D01*
G02X430748Y459184I500J0D01*
G01X447690D01*
X448809Y458065D01*
Y412189D01*
X445262Y408642D01*
X417150D01*
G37*
G36*
G01X409423Y485019D02*
Y486779D01*
X409513Y486869D01*
X419571D01*
X419680Y486760D01*
Y483939D01*
X419643Y483902D01*
X414622D01*
X414108Y484416D01*
X409978D01*
G03X409718Y484562I-920J-1334D01*
G02X409423Y485019I205J456D01*
G37*
G36*
G01X419072Y488852D02*
X407248D01*
X403343D01*
X402834D01*
X402512Y489174D01*
Y500910D01*
X402875Y501273D01*
X403523Y501921D01*
X407186D01*
X419196D01*
X419632Y501485D01*
Y489412D01*
X419072Y488852D01*
G37*
G36*
G01X412370Y504171D02*
X412218Y504323D01*
Y508187D01*
X413088Y509057D01*
X416670D01*
G02X417170Y508557I0J-500D01*
G01Y508440D01*
X418333Y507277D01*
Y504531D01*
X417973Y504171D01*
X412370D01*
G37*
G36*
G01X412523Y518407D02*
X417387D01*
X417861Y517933D01*
Y516581D01*
X417556Y516276D01*
X413228D01*
X412978Y516026D01*
Y515246D01*
Y513371D01*
X412713Y513106D01*
X403000D01*
X402811Y513295D01*
Y515718D01*
Y517290D01*
X403946Y518425D01*
X405518D01*
X412505D01*
X412523Y518407D01*
G37*
G36*
G01X422887Y511235D02*
X414915D01*
X414726Y511424D01*
Y514755D01*
X415161Y515191D01*
X418151D01*
X421275Y518315D01*
X423518D01*
X423734Y518099D01*
Y517009D01*
Y516174D01*
X423264Y515704D01*
Y511612D01*
X422887Y511235D01*
G37*
G36*
G01X408069Y525894D02*
X414946D01*
X414970Y525870D01*
Y525364D01*
X414914Y525308D01*
X411235D01*
X411179Y525252D01*
Y524296D01*
X411203Y524272D01*
X414430D01*
X414654Y524048D01*
Y522094D01*
X413048Y520488D01*
X408505D01*
X407851Y521142D01*
Y523102D01*
Y525676D01*
X408069Y525894D01*
G37*
G36*
G01X408442Y560346D02*
X416905D01*
X417216Y560035D01*
Y553595D01*
X416717Y553096D01*
X414726D01*
X413668Y552038D01*
Y548056D01*
X413201Y547589D01*
X407134D01*
X406668Y548055D01*
Y550086D01*
X407881Y551299D01*
Y552910D01*
Y556409D01*
X407490Y556800D01*
Y560235D01*
X407601Y560346D01*
X408442D01*
G37*
G36*
G01X413284Y593039D02*
X409687D01*
X409436Y593290D01*
Y598844D01*
X409515Y598923D01*
X413085D01*
X413558D01*
X413775Y598706D01*
Y593100D01*
X413714Y593039D01*
X413284D01*
G37*
G36*
G01X403531Y605090D02*
X403487Y605046D01*
Y593356D01*
X403532Y593311D01*
Y590504D01*
X403995Y590041D01*
X407981D01*
X408313Y590373D01*
Y593369D01*
Y599557D01*
X408213Y599657D01*
X407447D01*
X405887D01*
X405643Y599901D01*
X404382Y601162D01*
Y601769D01*
X404346Y601805D01*
Y605048D01*
X404304Y605090D01*
X403531D01*
G37*
G36*
G01X416474Y693272D02*
G03I-640J0D01*
G37*
G36*
G01X423350Y244300D02*
G03I-640J0D01*
G37*
G36*
G01X422910Y250679D02*
G03I-640J0D01*
G37*
G36*
G01X424709Y503722D02*
Y510914D01*
X427473Y513678D01*
X427529D01*
Y516289D01*
X428021Y516781D01*
X428968D01*
X429214Y516535D01*
Y513526D01*
Y513332D01*
X429148D01*
Y510328D01*
X429204D01*
Y503722D01*
X429200Y503718D01*
Y502132D01*
Y501272D01*
X429323Y501149D01*
X429754D01*
X432540D01*
X432612Y501077D01*
Y484167D01*
X434836Y481943D01*
X434862D01*
X435918Y480887D01*
X439126Y477679D01*
Y474249D01*
X438138Y473261D01*
X435566D01*
X431550D01*
X431295Y473516D01*
Y475453D01*
Y475771D01*
X430977Y476089D01*
X426467D01*
X426414Y476036D01*
Y475638D01*
Y473153D01*
X426228Y472967D01*
X422777D01*
X422257D01*
X421245Y473979D01*
Y501039D01*
X421409Y501203D01*
X423649D01*
X424709Y502263D01*
Y503722D01*
G37*
G36*
G01X430206Y510937D02*
Y511329D01*
X430150D01*
Y512331D01*
X430216D01*
Y516950D01*
X429980Y517186D01*
Y517957D01*
X430031Y518009D01*
Y522211D01*
X430353Y522533D01*
X431129D01*
X432226Y521436D01*
Y514280D01*
X432196Y514250D01*
Y510937D01*
G02X431696Y510437I-500J0D01*
G01X430706D01*
G02X430206Y510937I0J500D01*
G37*
G36*
G01X432318Y509002D02*
X433197Y509881D01*
X433631Y510315D01*
Y518195D01*
Y521579D01*
X431551Y523659D01*
Y524158D01*
X431592Y524199D01*
X435055D01*
X437135Y522119D01*
Y513727D01*
X437214Y513648D01*
Y509738D01*
Y506892D01*
X436535Y506213D01*
X431269D01*
X430474D01*
X430292Y506395D01*
Y508274D01*
X431020Y509002D01*
X432318D01*
G37*
G36*
G01X424266Y513569D02*
Y515289D01*
X424736Y515759D01*
Y516570D01*
X426423Y518258D01*
G02X427276Y517904I353J-354D01*
G01Y517453D01*
X426528Y516704D01*
Y514449D01*
X425148Y513069D01*
X424766D01*
G02X424266Y513569I0J500D01*
G37*
G36*
G01X416323Y537922D02*
X416420Y538019D01*
X429859D01*
X429941Y537937D01*
Y524255D01*
X429844Y524158D01*
X416580D01*
X416323Y524415D01*
Y537922D01*
G37*
G36*
G01X418614Y663446D02*
G03I-640J0D01*
G37*
G36*
G01X444970Y72829D02*
X450920D01*
X451800Y71949D01*
Y70907D01*
X451782Y70890D01*
Y67758D01*
X451418Y67394D01*
X445190D01*
X444480Y68104D01*
Y72339D01*
X444970Y72829D01*
G37*
G36*
G01X450760Y83446D02*
X450845Y83361D01*
Y78977D01*
X448489Y76621D01*
Y74783D01*
X447736Y74030D01*
X444852D01*
X444575Y74307D01*
Y82790D01*
X445231Y83446D01*
X450760D01*
G37*
G36*
G01X465337Y80604D02*
X461461Y84480D01*
X461402D01*
X458186D01*
X447579D01*
X447546Y84448D01*
X444816D01*
X443574Y83205D01*
Y83106D01*
X442687Y82220D01*
X436687D01*
X435460Y83447D01*
Y93108D01*
X436556Y94204D01*
X447020D01*
X447418Y93806D01*
Y91440D01*
X447730Y91128D01*
X463881D01*
X464410Y90599D01*
Y88797D01*
X465011Y88196D01*
X470827D01*
X471640Y87383D01*
Y81544D01*
X470700Y80604D01*
X465337D01*
G37*
G36*
G01X432877Y115522D02*
X431819Y116580D01*
Y124968D01*
Y125583D01*
X434068Y127832D01*
X460670D01*
X462854Y125648D01*
X463307Y125195D01*
Y115900D01*
X462929Y115522D01*
X432877D01*
G37*
G36*
G01X444465Y152638D02*
X444171Y152932D01*
Y172764D01*
G02X444671Y173264I500J0D01*
G01X449529D01*
X449845Y173580D01*
X450474Y174208D01*
Y179138D01*
G02X450974Y179638I500J0D01*
G01X458382D01*
G02X458882Y179138I0J-500D01*
G01Y174093D01*
X459585Y173390D01*
X464671D01*
G02X465171Y172890I0J-500D01*
G01Y161451D01*
X464162Y160442D01*
X459220D01*
Y153838D01*
X464671D01*
G02X465171Y153338I0J-500D01*
G01Y153138D01*
G02X464671Y152638I-500J0D01*
G01X444465D01*
G37*
G36*
G01X443635Y186584D02*
X448183D01*
X448470Y186297D01*
Y180961D01*
X449472Y179959D01*
Y174623D01*
X449114Y174265D01*
X444782D01*
X442955Y176092D01*
Y185904D01*
X443635Y186584D01*
G37*
G36*
G01X448562Y265286D02*
G03I-640J0D01*
G37*
G36*
G01X441866Y258066D02*
G02X441513Y258213I1J500D01*
G01X441019Y258707D01*
X440935D01*
Y259793D01*
X441511Y260369D01*
X442269D01*
X442436Y260536D01*
X443345D01*
X446346Y263536D01*
X450681D01*
X451211Y263006D01*
Y256369D01*
X450786Y255944D01*
X446118D01*
X443996Y258066D01*
X441866D01*
G37*
G36*
G01X457627Y405442D02*
X458634Y404436D01*
X463535D01*
G02X464485Y403125I0J-1000D01*
G03X464837Y401611I1428J-466D01*
G02X464830Y400905I-358J-349D01*
G03X467349Y399506I1053J-1071D01*
G02X467924Y399889I488J-109D01*
G03X469544Y400548I287J1616D01*
G02X471064Y400672I813J-583D01*
G01X489338Y382398D01*
X518220D01*
X532490Y368128D01*
Y342892D01*
G02X531612Y341900I-1000J0D01*
G03X530578Y339529I183J-1491D01*
G02X530432Y338196I-811J-586D01*
G03X530315Y338081I993J-1127D01*
G02X528786Y338134I-742J670D01*
G03X528719Y338213I-1178J-931D01*
G02X528653Y339470I743J669D01*
G03X526322Y339348I-1215J883D01*
G02X526388Y338091I-743J-669D01*
G03X528718Y336201I1214J-884D01*
G02X530247Y336148I742J-670D01*
G03X531466Y335572I1183J926D01*
G02X532490Y334573I24J-1000D01*
G01Y309188D01*
X529210Y305908D01*
X466512D01*
Y311958D01*
X465515Y312955D01*
X464105D01*
X463108Y311958D01*
Y306115D01*
X462901Y305908D01*
X459899D01*
X444990Y320817D01*
Y392420D01*
X436960Y400450D01*
Y404942D01*
G02X437460Y405442I500J0D01*
G01X457627D01*
G37*
G36*
G01X437741Y487878D02*
Y485121D01*
G02X437241Y484621I-500J0D01*
G01X435014D01*
X434769Y484866D01*
Y500863D01*
X435377Y501470D01*
X437607D01*
X437946Y501809D01*
X443495D01*
X455194D01*
X464321D01*
X468660D01*
X468730Y501739D01*
Y489550D01*
X468081Y488901D01*
X465243D01*
X465242Y488900D01*
X455194D01*
X452542D01*
X452257Y488615D01*
X449645D01*
X438478D01*
X437741Y487878D01*
G37*
G36*
G01X448744Y484420D02*
X448207Y483883D01*
X439577D01*
X439539Y483921D01*
Y486268D01*
X439880Y486609D01*
X448410D01*
X448744Y486275D01*
Y484420D01*
G37*
G36*
G01X435434Y539067D02*
X433868Y540633D01*
X433818D01*
X433373Y541078D01*
Y543591D01*
X433434Y543651D01*
Y546226D01*
X435872Y548665D01*
Y548949D01*
X436153Y549229D01*
Y550163D01*
G02X436653Y550663I500J0D01*
G01X439539D01*
X439618Y550584D01*
Y546832D01*
X438498Y545712D01*
X436910D01*
X436388Y545191D01*
X436356D01*
Y545159D01*
X436282Y545084D01*
Y540763D01*
X436728Y540317D01*
Y539524D01*
X436271Y539067D01*
X435434D01*
G37*
G36*
G01X437697Y538449D02*
Y539077D01*
X437730Y539109D01*
Y540732D01*
X437697Y540764D01*
Y540912D01*
X437284Y541325D01*
Y544379D01*
X437338Y544434D01*
X443637D01*
X443735Y544336D01*
Y542170D01*
X440076Y538511D01*
X439184D01*
X438623Y537949D01*
X438197D01*
G02X437697Y538449I0J500D01*
G37*
G36*
G01X434512Y645119D02*
G03I-640J0D01*
G37*
G36*
G01X445043Y665963D02*
G03I-640J0D01*
G37*
G36*
G01X458186Y83479D02*
X459156D01*
X460987D01*
X462718Y81748D01*
Y76538D01*
Y73730D01*
X462423Y73435D01*
X457287D01*
X456825Y73897D01*
Y75172D01*
X457686Y76033D01*
Y76280D01*
Y82979D01*
G02X458186Y83479I500J0D01*
G37*
G36*
G01X457786Y97416D02*
X458059Y97689D01*
X460166D01*
X460450Y97973D01*
Y99542D01*
X460659Y99750D01*
Y103737D01*
X460731Y103809D01*
X463835D01*
X464497Y103147D01*
Y101111D01*
X465323Y100285D01*
Y93157D01*
X464340Y92174D01*
X457975D01*
X457786Y92363D01*
Y97416D01*
G37*
G36*
G01X455726Y112745D02*
X456162Y113181D01*
X464378D01*
X464643Y112916D01*
Y105227D01*
X464227Y104811D01*
X460014D01*
X459657Y104454D01*
Y100165D01*
X458958Y99466D01*
X456325D01*
G02X455825Y99966I0J500D01*
G01Y112018D01*
X455726Y112117D01*
Y112745D01*
G37*
G36*
G01X458618Y189319D02*
Y185128D01*
Y182563D01*
X458368Y182313D01*
X450498D01*
X449631Y183180D01*
Y187520D01*
Y188779D01*
X450364Y189512D01*
X458425D01*
X458618Y189319D01*
G37*
G36*
G01X460000Y174392D02*
X459884Y174508D01*
Y188509D01*
X460271Y188896D01*
X464436D01*
X464976Y188356D01*
Y175163D01*
X464205Y174392D01*
X460000D01*
G37*
G36*
G01X449952Y276221D02*
G03I-640J0D01*
G37*
G36*
G01X454442Y292405D02*
G03I-640J0D01*
G37*
G36*
G01X476003Y453096D02*
X476370Y452729D01*
Y407907D01*
X475368Y406905D01*
X459620D01*
X458656Y407869D01*
Y452596D01*
G02X459156Y453096I500J0D01*
G01X476003D01*
G37*
G36*
G01X449755Y487183D02*
X449859Y487287D01*
X468513D01*
X469090Y486710D01*
Y474931D01*
X468441Y474282D01*
X450275D01*
X449755Y474802D01*
Y487183D01*
G37*
G36*
G01X468894Y516115D02*
Y508978D01*
Y505743D01*
X468312Y505161D01*
X460860D01*
X459262Y506759D01*
Y508448D01*
Y515068D01*
X461423Y517229D01*
X467780D01*
X468894Y516115D01*
G37*
G36*
G01X459290Y666543D02*
G03I-640J0D01*
G37*
G36*
G01X469806Y681378D02*
G03X468086Y680505I-339J-1463D01*
G01X468027Y680367D01*
X467776Y680201D01*
X456359D01*
G02X456006Y680348I1J500D01*
G01X455539Y680815D01*
X450554D01*
X448482Y682887D01*
Y689799D01*
G02X448982Y690299I500J0D01*
G01X475445D01*
X476090Y689654D01*
Y685679D01*
X476013Y685495D01*
X475972Y685454D01*
X474173D01*
X473110Y684390D01*
X470998Y682279D01*
G02X469806Y681378I-997J80D01*
G37*
G36*
G01X466325Y92197D02*
Y101400D01*
X465727Y101998D01*
Y103328D01*
X466139Y103740D01*
X469456D01*
X469574Y103622D01*
Y102621D01*
Y90776D01*
Y90180D01*
X468687Y89293D01*
X465858D01*
X465558Y89593D01*
Y91430D01*
X466325Y92197D01*
G37*
G36*
G01X468850Y401505D02*
G03I-640J0D01*
G37*
G36*
G01X474770Y553659D02*
G03I-640J0D01*
G37*
G36*
G01X474930Y563565D02*
G03I-640J0D01*
G37*
G36*
G01X479545Y659426D02*
G03I-640J0D01*
G37*
G36*
G01X479993Y668666D02*
G03I-640J0D01*
G37*
G36*
G01X466689Y675327D02*
G03I-640J0D01*
G37*
G36*
G01X472299Y678689D02*
X472003Y678985D01*
Y681867D01*
X474588Y684452D01*
X479810D01*
G02X480164Y684305I0J-500D01*
G03X482290I1063J1061D01*
G02X482644Y684452I354J-353D01*
G01X486334D01*
X486778Y684008D01*
Y680428D01*
X486745Y680342D01*
G03X486614Y679669I1870J-713D01*
G02X485614Y678689I-1000J20D01*
G01X472299D01*
G37*
G36*
G01X484980Y124022D02*
Y125447D01*
X486000Y126468D01*
X486144D01*
Y126612D01*
X486410Y126877D01*
Y136158D01*
X486500Y136248D01*
X497374D01*
X498100Y135522D01*
Y131889D01*
X497053Y130842D01*
X494550D01*
X493424Y129716D01*
Y124680D01*
G02X492924Y124180I-500J0D01*
G01X489747D01*
X487638Y122071D01*
G02X486931I-353J354D01*
G01X484980Y124022D01*
G37*
G36*
G01X495780Y385762D02*
G03I-640J0D01*
G37*
G36*
G01X480690Y419556D02*
G03I-640J0D01*
G37*
G36*
G01X487310Y426196D02*
G03I-640J0D01*
G37*
G36*
G01X480215Y467597D02*
G03I-640J0D01*
G37*
G36*
G01X480394Y462988D02*
G03I-640J0D01*
G37*
G36*
G01X484325Y473522D02*
G03I-640J0D01*
G37*
G36*
G01X484281Y479628D02*
G03I-640J0D01*
G37*
G36*
G01X487280Y543687D02*
G03I-640J0D01*
G37*
G36*
G01X487360Y563730D02*
G03I-640J0D01*
G37*
G36*
G01X482020Y553210D02*
G03I-640J0D01*
G37*
G36*
G01X482050Y573563D02*
G03I-640J0D01*
G37*
G36*
G01X486530Y590563D02*
G03I-640J0D01*
G37*
G36*
G01X490020Y590839D02*
G03I-640J0D01*
G37*
G36*
G01X495789Y220199D02*
X500630D01*
X501343Y219486D01*
Y217037D01*
X500898Y216592D01*
X496252D01*
X495230Y217614D01*
Y219640D01*
X495789Y220199D01*
G37*
G36*
G01X505537Y390481D02*
G03I-640J0D01*
G37*
G36*
G01X496085Y413830D02*
Y430647D01*
X497805Y432367D01*
X505200D01*
X505673Y431894D01*
Y429488D01*
X502214Y426029D01*
X501307D01*
X500276Y424998D01*
Y419688D01*
X500740Y419224D01*
X503721D01*
X503769Y419215D01*
G03X505241I736J3729D01*
G01X505289Y419224D01*
X508125D01*
X510185Y421284D01*
Y423248D01*
X512598Y425661D01*
X520023D01*
X521433Y424251D01*
Y414817D01*
X521461Y414789D01*
X519346Y412674D01*
X497241D01*
X496085Y413830D01*
G37*
G36*
G01X506380Y495880D02*
G03I-640J0D01*
G37*
G36*
G01X532513Y539727D02*
G02X532045Y540052I0J500D01*
G03X529884Y540824I-1407J-527D01*
G02X529260Y540924I-251J433D01*
G03X527164Y541068I-1122J-999D01*
G02X526465Y541118I-324J381D01*
G03X523952Y540703I-1127J-993D01*
G01X523914Y540612D01*
X523602Y540300D01*
Y540227D01*
G02X523102Y539727I-500J0D01*
G01X521422D01*
G02X520429Y540606I0J1000D01*
G03X520232Y541188I-1491J-180D01*
G02X520357Y541837I431J254D01*
G03X518144Y542262I-919J1188D01*
G02X518019Y541613I-431J-254D01*
G03X517447Y540606I919J-1188D01*
G02X516454Y539727I-993J121D01*
G01X515340D01*
G02X514840Y540227I0J500D01*
G01Y540855D01*
X514875Y540944D01*
G03Y542054I-1395J555D01*
G01X514840Y542143D01*
Y542633D01*
X514080Y543393D01*
X507436D01*
G02X507007Y543635I-1J500D01*
G01Y543637D01*
G03X505756Y544367I-1289J-772D01*
G02X504804Y545150I24J1000D01*
G03X504136Y546097I-1466J-325D01*
G01X504088Y546127D01*
X503338Y546878D01*
Y547772D01*
X504088Y548523D01*
X504136Y548553D01*
G03X503713Y551279I-798J1272D01*
G02X503338Y551764I125J484D01*
G01Y553125D01*
X501575Y554888D01*
G02X501437Y555332I354J353D01*
G01X501452Y555414D01*
X501463Y555450D01*
X501465Y555455D01*
G03X501287Y556759I-1427J469D01*
G03X500617Y557311I-1249J-834D01*
G01X500525Y557349D01*
X500340Y557535D01*
X499926Y557949D01*
X499880D01*
X499588Y558241D01*
Y561023D01*
G02X500088Y561523I500J0D01*
G01X500107D01*
G03X500358Y561539I30J1502D01*
G01X500395Y561544D01*
X500569D01*
X500625Y561601D01*
X500718Y561640D01*
G03X501535Y562474I-580J1385D01*
G03X501297Y563981I-1397J552D01*
G02X501360Y565324I771J637D01*
G03X501527Y567343I-1022J1101D01*
G02Y568507I813J582D01*
G03X500464Y570922I-1189J918D01*
G02X499588Y571914I124J992D01*
G01Y572428D01*
G02X500509Y573425I1000J0D01*
G03Y576425I-71J1500D01*
G02X499588Y577422I79J997D01*
G01Y583534D01*
X500355Y584301D01*
X500446Y584339D01*
G03X501264Y586280I-578J1386D01*
G02X501532Y587399I929J369D01*
G03X501955Y589024I-994J1126D01*
G01X501948Y589044D01*
G02X501968Y589426I471J167D01*
G01X502045Y589586D01*
Y591125D01*
G02X502545Y591625I500J0D01*
G01X509860D01*
G02X510856Y590720I0J-1000D01*
G03X511139Y589942I1498J105D01*
G03X513321Y589675I1215J883D01*
G02X514543Y589725I643J-765D01*
G03X516143Y589637I870J1225D01*
G03X516803Y590380I-730J1313D01*
G01X516810Y590397D01*
X516811Y590400D01*
X516856Y590508D01*
Y590528D01*
X516871Y590588D01*
G03X516905Y590773I-1458J364D01*
G02X517894Y591625I989J-148D01*
G01X524676D01*
G02X525176Y591125I0J-500D01*
G01Y590876D01*
X526214Y589838D01*
X526252Y589747D01*
G03X529127Y590519I1386J579D01*
G02X530122Y591625I995J106D01*
G01X530976D01*
G02X531476Y591125I0J-500D01*
G01Y590476D01*
X531527Y590424D01*
X531539Y590235D01*
Y590234D01*
G03X531836Y589424I1499J90D01*
G03X534540Y590288I1202J900D01*
G03X534428Y590893I-1502J35D01*
G01X534427Y590895D01*
X534390Y590987D01*
Y591125D01*
G02X534890Y591625I500J0D01*
G01X538850D01*
G02X539350Y591125I0J-500D01*
G01Y590825D01*
X539312Y590733D01*
G03X542090I1389J-571D01*
G01X542052Y590825D01*
Y591125D01*
G02X542552Y591625I500J0D01*
G01X545148D01*
G02X545648Y591125I0J-500D01*
G01Y590825D01*
X545611Y590733D01*
X545610Y590732D01*
G03X548390I1390J-569D01*
G01X548389Y590733D01*
X548352Y590825D01*
Y591125D01*
G02X548852Y591625I500J0D01*
G01X549938D01*
X551091Y590472D01*
G02X550605Y588790I-707J-707D01*
G03X549439Y587225I333J-1465D01*
G03X550360Y585939I1499J100D01*
G01X550451Y585901D01*
X551185Y585166D01*
X551960D01*
G02X552438Y584667I-21J-499D01*
G01Y574219D01*
G02X551373Y573221I-1000J0D01*
G03X550189Y570650I-135J-1496D01*
G02X550311Y569392I-710J-704D01*
G03X550263Y567731I1227J-867D01*
G03X551478Y567024I1275J794D01*
G02X552438Y566025I-40J-999D01*
G01Y563173D01*
G02X551938Y562673I-500J0D01*
G01X551841D01*
X551784Y562686D01*
G03X551092I-346J-1461D01*
G01X551035Y562673D01*
X550974D01*
X550947Y562645D01*
G03X551438Y559723I491J-1420D01*
G02X552438Y558723I0J-1000D01*
G01Y553723D01*
G02X551960Y553224I-499J0D01*
G01X551550D01*
X550851Y552524D01*
X550760Y552486D01*
G03X550373Y549949I578J-1386D01*
G02X550307Y548384I-654J-756D01*
G03X551732Y545759I854J-1236D01*
G01X551824Y545796D01*
X551960D01*
G02X552438Y545297I-21J-499D01*
G01Y539931D01*
G02X551974Y539432I-500J0D01*
G01X551937D01*
G02X551582Y539580I0J500D01*
G01X551436Y539727D01*
X547076D01*
G02X546592Y540102I0J500D01*
G03X543752Y540303I-1454J-377D01*
G01X543714Y540212D01*
X543469Y539967D01*
G02X542762I-354J354D01*
G01X542684Y540045D01*
X542646Y540148D01*
G03X539852Y540203I-1408J-523D01*
G01X539814Y540112D01*
X539429Y539727D01*
X536647D01*
X536062Y540312D01*
X536024Y540403D01*
G03X533167Y540127I-1386J-578D01*
G02X532677Y539727I-490J100D01*
G01X532513D01*
G37*
G36*
G01X500656Y653942D02*
X500285Y654313D01*
Y661170D01*
X500392Y661277D01*
X502554D01*
X503322Y660508D01*
X513695D01*
X513934Y660269D01*
Y659566D01*
X513777Y659409D01*
X510928D01*
G03X510724Y659396I-7J-1501D01*
G01X510691Y659391D01*
X510303D01*
X510191Y659279D01*
X507725D01*
X506872Y658426D01*
Y657740D01*
X503074Y653942D01*
X500656D01*
G37*
G36*
G01X512045Y453478D02*
Y453479D01*
Y473352D01*
G02X512545Y473852I500J0D01*
G01X534280D01*
G02X534780Y473352I0J-500D01*
G01Y451873D01*
G02X534280Y451373I-500J0D01*
G01X517462D01*
X512868D01*
X512045Y452196D01*
Y453478D01*
G37*
G36*
G01X520130Y496645D02*
G03I-640J0D01*
G37*
G36*
G01X526338Y496724D02*
G03I-640J0D01*
G37*
G36*
G01X512160Y496255D02*
G03I-640J0D01*
G37*
G36*
G01X522890Y513692D02*
G03I-640J0D01*
G37*
G36*
G01X512200Y513792D02*
G03I-640J0D01*
G37*
G36*
G01X524578Y528725D02*
G03I-640J0D01*
G37*
G36*
G01X540938Y76549D02*
Y99778D01*
X541199Y100039D01*
X545193D01*
X546060Y100906D01*
X548320D01*
X549179Y100047D01*
Y95535D01*
X550059Y94655D01*
X551659D01*
X551704Y94610D01*
X563187D01*
X563210Y94587D01*
X564880Y96257D01*
Y100372D01*
G02X565380Y100872I500J0D01*
G01X567501D01*
X567560Y100813D01*
Y78439D01*
X564878Y75757D01*
X541730D01*
X540938Y76549D01*
G37*
G36*
G01X537348Y255423D02*
Y250233D01*
X537338Y250223D01*
Y249803D01*
X536538Y249003D01*
X533038D01*
X533028Y249013D01*
X532648D01*
X530838Y250823D01*
Y258823D01*
Y259923D01*
X531838Y260923D01*
X537338D01*
X539338D01*
X539838Y260423D01*
Y257913D01*
X537738Y255813D01*
X537348Y255423D01*
G37*
G36*
G01X540538Y269723D02*
Y262923D01*
X540313Y262698D01*
X539738Y262123D01*
X534238D01*
X533688Y262673D01*
Y272423D01*
X534838Y273573D01*
X540138D01*
X540538Y273173D01*
Y269723D01*
G37*
G36*
G01X530550Y419478D02*
G03I-640J0D01*
G37*
G36*
G01X540059Y491107D02*
G03I-640J0D01*
G37*
G36*
G01X533574Y491384D02*
G03I-640J0D01*
G37*
G36*
G01X558638Y121923D02*
Y113123D01*
X560638Y111123D01*
X569138D01*
X570138Y110123D01*
Y106123D01*
X569413Y105398D01*
X568901D01*
X567450Y103947D01*
Y102418D01*
X567278Y102246D01*
X564277D01*
X563099Y103424D01*
X558820D01*
X557583Y102187D01*
X555196D01*
X554797Y102586D01*
Y106561D01*
Y111782D01*
X556638Y113623D01*
X557638Y114623D01*
Y121923D01*
X558638D01*
G37*
G36*
G01X548615Y228365D02*
X546773Y230208D01*
X544480D01*
G02X543980Y230708I0J500D01*
G01Y232717D01*
X545054Y233792D01*
X545185D01*
X545759Y234366D01*
X553440D01*
X558338Y229468D01*
Y219913D01*
X557968Y219543D01*
X553988D01*
X551418Y222113D01*
Y225293D01*
X551240Y225471D01*
Y225741D01*
X548615Y228365D01*
G37*
G36*
G01X551038Y259523D02*
Y246323D01*
X550438Y245723D01*
X548238D01*
X547538Y246423D01*
X544138Y249823D01*
Y255423D01*
X541898Y257663D01*
Y261163D01*
Y262373D01*
Y267083D01*
Y270483D01*
Y271423D01*
X542648Y272173D01*
X550388D01*
X550538Y272023D01*
X551038Y271523D01*
Y270323D01*
Y269423D01*
Y259523D01*
G37*
G36*
G01X556347Y389146D02*
G03I-640J0D01*
G37*
G36*
G01X544021Y448428D02*
G03I-640J0D01*
G37*
G36*
G01X557288Y468826D02*
X544262D01*
X543002Y470086D01*
Y476398D01*
X543415Y476811D01*
X557574D01*
X558488Y475897D01*
Y470026D01*
X557288Y468826D01*
G37*
G36*
G01X551940Y485189D02*
X552765Y486014D01*
X564504D01*
X565389Y485129D01*
Y478817D01*
X565212Y478640D01*
X553237D01*
X553235Y478642D01*
X552396D01*
X551940Y479098D01*
Y479937D01*
Y485189D01*
G37*
G36*
G01X548640Y509493D02*
G03I-640J0D01*
G37*
G36*
G01X548520Y515743D02*
G03I-640J0D01*
G37*
G36*
G01X556754Y628703D02*
X566816D01*
X567497Y628022D01*
Y624927D01*
X564970Y622400D01*
X555250D01*
X554820Y622830D01*
Y626769D01*
X556754Y628703D01*
G37*
G36*
G01X546549Y633931D02*
X553353D01*
X553746Y633538D01*
Y629920D01*
X553030Y629204D01*
X546405D01*
Y633787D01*
X546549Y633931D01*
G37*
G36*
G01X568482Y203099D02*
X573182D01*
X574382Y201899D01*
Y193699D01*
X573482Y192799D01*
X568982D01*
X567982Y193799D01*
Y202599D01*
X568482Y203099D01*
G37*
G36*
G01X573829Y203868D02*
X573597Y204101D01*
X569596D01*
X569594Y204103D01*
X568920D01*
X568462Y204560D01*
G02X568315Y204914I353J354D01*
G01Y216021D01*
X569117Y216823D01*
X604433D01*
G02X605433Y215795I0J-1000D01*
G03X607005Y212346I4300J-123D01*
G02X607188Y211959I-317J-387D01*
G01Y202088D01*
X606600Y201500D01*
X595891D01*
X593670Y203721D01*
X574183D01*
G02X573829Y203868I0J500D01*
G37*
G36*
G01X560038Y230883D02*
X561948Y232793D01*
X565998D01*
X568508Y230283D01*
Y230264D01*
X569410Y229362D01*
X574818D01*
X576270Y227910D01*
Y221279D01*
X574124Y219133D01*
X567158D01*
X561548D01*
X561038Y219643D01*
Y226823D01*
X560038Y227823D01*
Y230883D01*
G37*
G36*
G01X563616Y261113D02*
X578776D01*
X579148Y260741D01*
Y245906D01*
X578996Y245754D01*
X564022D01*
X563616Y246160D01*
Y261113D01*
G37*
G36*
G01X567960Y415088D02*
G03I-640J0D01*
G37*
G36*
G01X562250Y503885D02*
G03I-640J0D01*
G37*
G36*
G01X561600Y510151D02*
G03I-640J0D01*
G37*
G36*
G01X572470Y509411D02*
G03I-640J0D01*
G37*
G36*
G01X628330Y99232D02*
Y82753D01*
X625900Y80323D01*
X583968D01*
X581038Y83253D01*
Y92653D01*
X581113Y92728D01*
Y102838D01*
X585358Y107083D01*
X597200D01*
X602231Y102052D01*
X625510D01*
X628330Y99232D01*
G37*
G36*
G01X577392Y189909D02*
X576340Y190961D01*
Y202219D01*
G02X576840Y202719I500J0D01*
G01X592744D01*
X593492Y201972D01*
Y190909D01*
X592492Y189909D01*
X577392D01*
G37*
G36*
G01X586628Y268018D02*
G02X586886Y268456I500J0D01*
G03X588304Y270863I-1334J2407D01*
G01Y273897D01*
X588300Y273912D01*
G02X588428Y274403I481J137D01*
G01X590348Y276323D01*
X591538D01*
X592028Y275833D01*
Y274733D01*
X591158Y273863D01*
Y272978D01*
X590574Y272395D01*
Y267412D01*
X590396Y267233D01*
X586818D01*
X586628Y267423D01*
Y268018D01*
G37*
G36*
G01X586224Y308881D02*
G03I-640J0D01*
G37*
G36*
G01X584499Y321204D02*
G03I-762J0D01*
G37*
G36*
G01X576190Y463784D02*
G03I-640J0D01*
G37*
G36*
G01X576290Y469996D02*
G03I-640J0D01*
G37*
G36*
G01X580240Y508878D02*
G03I-640J0D01*
G37*
G36*
G01X589676Y548825D02*
G03I-640J0D01*
G37*
G36*
G01X592963Y308988D02*
G03I-762J0D01*
G37*
G36*
G01X592739Y319360D02*
G03I-762J0D01*
G37*
G36*
G01X591538Y597158D02*
G03I-640J0D01*
G37*
G36*
G01X591437Y608057D02*
G03I-640J0D01*
G37*
G36*
G01X591663Y600384D02*
G03I-640J0D01*
G37*
G36*
G01X606002Y609413D02*
G03I-640J0D01*
G37*
G36*
G01X591241Y618696D02*
G03I-640J0D01*
G37*
G36*
G01X602228Y664798D02*
G03I-640J0D01*
G37*
G36*
G01X607820Y332593D02*
X610804Y335577D01*
G02X612220Y335575I707J-707D01*
G03X615642Y336986I1420J1411D01*
G01Y337348D01*
G02X616142Y337848I500J0D01*
G01X643664D01*
X645860Y340044D01*
X658019D01*
X660450Y337613D01*
Y332827D01*
X657235Y329612D01*
X643580D01*
X641640Y327672D01*
Y315387D01*
X641210Y314957D01*
X640535Y314282D01*
X639051D01*
X639006Y314238D01*
X639005D01*
X638084Y313316D01*
Y313314D01*
X638035Y313265D01*
Y305029D01*
X638080Y304984D01*
Y304166D01*
X638026Y304112D01*
X634134D01*
X633752D01*
X633731Y304133D01*
X632853D01*
X632850Y304130D01*
X630046D01*
X628837Y302921D01*
X625878D01*
X625396Y303403D01*
Y303726D01*
X610876D01*
X607820Y306782D01*
Y332593D01*
G37*
G36*
G01X606386Y387837D02*
G03I-640J0D01*
G37*
G36*
G01X609509Y396959D02*
G03I-640J0D01*
G37*
G36*
G01X606213Y393920D02*
G03I-640J0D01*
G37*
G36*
G01X609461Y403445D02*
G03I-640J0D01*
G37*
G36*
G01X609808Y554851D02*
G03I-640J0D01*
G37*
G36*
G01X607717Y566915D02*
G03I-640J0D01*
G37*
G36*
G01X611884Y709830D02*
G03I-640J0D01*
G37*
G36*
G01X617733Y709167D02*
G03I-640J0D01*
G37*
G36*
G01X624996Y176106D02*
G03I-640J0D01*
G37*
G36*
G01X625584Y189825D02*
G03I-640J0D01*
G37*
G36*
G01X633121Y192797D02*
G03I-640J0D01*
G37*
G36*
G01X633123Y202093D02*
G03I-640J0D01*
G37*
G36*
G01X636421Y287382D02*
X636260Y287543D01*
Y297525D01*
X637596Y298861D01*
X638969D01*
X639085Y298977D01*
Y312901D01*
X639420Y313236D01*
X641034D01*
X642860Y315062D01*
Y326486D01*
X643884Y327510D01*
X644212Y327838D01*
X666141D01*
X673830Y320149D01*
Y301260D01*
X672237Y299667D01*
X664351D01*
X663076Y300942D01*
Y309125D01*
X662519Y309682D01*
X657820D01*
X657294Y310208D01*
G02X657147Y310561I353J354D01*
G01Y316725D01*
X656548Y317324D01*
X651676D01*
X650702Y316350D01*
Y314776D01*
Y312066D01*
X648830Y310194D01*
X646410D01*
X645755Y309539D01*
Y298498D01*
X646556Y297697D01*
Y292816D01*
X646630Y292742D01*
Y287382D01*
X636421D01*
G37*
G36*
G01X634303Y411009D02*
G03I-640J0D01*
G37*
G36*
G01X635400Y555064D02*
X635020Y555444D01*
Y559220D01*
X637583Y561783D01*
G02X638291I354J-353D01*
G01X640760Y559314D01*
Y555598D01*
X640226Y555064D01*
X635400D01*
G37*
G36*
G01X644371Y613434D02*
X644578Y613227D01*
Y592451D01*
X644206Y592079D01*
X623760D01*
X623429Y592410D01*
Y613227D01*
X623636Y613434D01*
X644371D01*
G37*
G36*
G01X621894Y713788D02*
G03I-640J0D01*
G37*
G36*
G01X651366Y306937D02*
X652566Y308137D01*
X652669Y308175D01*
G03X653303Y308554I-692J1878D01*
G02X653634Y308680I332J-374D01*
G01X657474D01*
X657484Y308670D01*
X660096D01*
X661081Y307685D01*
Y301922D01*
Y301183D01*
Y296207D01*
X660910Y296036D01*
X657940D01*
X652941Y301035D01*
X652522Y301454D01*
X651797Y302179D01*
X646816D01*
X646779Y302216D01*
Y302995D01*
X646798Y303014D01*
Y305981D01*
Y306703D01*
X647032Y306937D01*
X650718D01*
X651366D01*
G37*
G36*
G01X652908Y370080D02*
X652566Y370422D01*
Y371593D01*
X648637Y375522D01*
Y378680D01*
X648968Y379011D01*
X657755D01*
X658130Y378636D01*
Y377601D01*
X658108Y377529D01*
G03Y376643I1435J-443D01*
G01X658130Y376571D01*
Y373473D01*
X654737Y370080D01*
X652908D01*
G37*
G36*
G01X667990Y385431D02*
X667891Y385476D01*
G03X665524Y385737I-1579J-3458D01*
G03X663158Y385476I-787J-3719D01*
G01X663059Y385431D01*
X646994D01*
X646338Y386087D01*
Y409120D01*
X646748Y409530D01*
X670111D01*
X670479Y409162D01*
Y385636D01*
X670274Y385431D01*
X667990D01*
G37*
G36*
G01X642120Y430289D02*
G03I-640J0D01*
G37*
G36*
G01X650719D02*
G03I-640J0D01*
G37*
G36*
G01X653556Y617061D02*
X650175D01*
X650097Y617139D01*
Y620099D01*
X658133Y628135D01*
X668124D01*
X668520Y627739D01*
Y621126D01*
X667538Y620144D01*
X661464D01*
X658866Y617546D01*
X654041D01*
X653556Y617061D01*
G37*
G36*
G01X712599Y85630D02*
G02X665355I-23622J0D01*
G01Y105315D01*
G02X712599I23622J0D01*
G01Y85630D01*
G37*
G36*
G01X659409Y143630D02*
G03I-640J0D01*
G37*
G36*
G01X659407Y151013D02*
G03I-640J0D01*
G37*
G36*
G01X659599Y165625D02*
G03I-640J0D01*
G37*
G36*
G01X659612Y158337D02*
G03I-640J0D01*
G37*
G36*
G01X672120Y187640D02*
X672112Y187632D01*
X673010Y186734D01*
Y184368D01*
X670841Y182199D01*
X659680D01*
X657450Y184429D01*
Y218597D01*
X658490Y219637D01*
X670421D01*
X672120Y217938D01*
Y187640D01*
G37*
G36*
G01X659222Y222614D02*
G03I-640J0D01*
G37*
G36*
G01X659241Y229770D02*
G03I-640J0D01*
G37*
G36*
G01X661800Y235485D02*
G03I-640J0D01*
G37*
G36*
G01X661830Y246085D02*
G03I-640J0D01*
G37*
G36*
G01X663572Y354223D02*
X662988Y354808D01*
Y358227D01*
X666063Y361303D01*
G02X666770I353J-354D01*
G01X669846Y358227D01*
Y354554D01*
X669514Y354223D01*
X663572D01*
G37*
G36*
G01X656661Y427864D02*
G03I-640J0D01*
G37*
G36*
G01X666406Y427868D02*
G03I-640J0D01*
G37*
G36*
G01X712599Y699803D02*
G02X665355I-23622J0D01*
G01Y719488D01*
G02X712599I23622J0D01*
G01Y699803D01*
G37*
G36*
G01X699470Y195532D02*
Y185630D01*
X698446Y184606D01*
X674971D01*
X674210Y185367D01*
Y195852D01*
X674730Y196372D01*
X698630D01*
X699470Y195532D01*
G37*
G36*
G01X677992Y198146D02*
X675590Y200548D01*
Y217892D01*
X677603Y219905D01*
X682203D01*
X699400Y237102D01*
X726640D01*
X728030Y235712D01*
Y230736D01*
X726500Y229206D01*
X714645D01*
G03X708505I-3070J-6845D01*
G01X702728D01*
X695960Y222438D01*
Y209753D01*
X699364Y206349D01*
Y198701D01*
X698957Y198293D01*
G02X698603Y198146I-354J353D01*
G01X677992D01*
G37*
G36*
G01X681971Y623179D02*
X681780Y623370D01*
Y636348D01*
X682320Y636888D01*
X688809D01*
X690020Y635677D01*
Y623679D01*
G02X689520Y623179I-500J0D01*
G01X681971D01*
G37*
G36*
G01X681950Y666671D02*
G03I-640J0D01*
G37*
G36*
G01X672040Y666151D02*
G03I-640J0D01*
G37*
G36*
G01X684910Y797307D02*
Y788960D01*
X686640Y787230D01*
Y784620D01*
X686482Y784462D01*
X682990D01*
X681230Y786222D01*
Y797649D01*
X681388Y797807D01*
X684410D01*
G02X684910Y797307I0J-500D01*
G37*
G36*
G01X756310Y120371D02*
X754580Y118641D01*
X711127D01*
X696280Y133488D01*
Y154738D01*
G02X696427Y155091I500J-1D01*
G01X699330Y157994D01*
X753811D01*
X756310Y155495D01*
Y120371D01*
G37*
G36*
G01X690504Y392130D02*
G03I-640J0D01*
G37*
G36*
G01X687761Y407004D02*
G03I-640J0D01*
G37*
G36*
G01X690504Y398141D02*
G03I-640J0D01*
G37*
G36*
G01X687371Y413349D02*
G03I-640J0D01*
G37*
G36*
G01X691170Y557156D02*
X689694Y558632D01*
Y588825D01*
X695677Y594808D01*
X698610D01*
X699527Y593891D01*
Y558718D01*
X697965Y557156D01*
X691170D01*
G37*
G36*
G01X693360Y670540D02*
G03I-640J0D01*
G37*
G36*
G01X699470Y670652D02*
G03I-640J0D01*
G37*
G36*
G01X705130Y552667D02*
X700280Y557517D01*
Y558055D01*
X700528Y558303D01*
Y593616D01*
X701700Y594787D01*
X706934D01*
X708620Y593101D01*
Y575040D01*
X712601Y571059D01*
X720770D01*
X721700Y570129D01*
Y567555D01*
X721922Y567333D01*
X733149D01*
X735810Y564672D01*
Y553928D01*
X734549Y552667D01*
X705130D01*
G37*
G36*
G01X714664Y572060D02*
X711510Y575215D01*
Y586421D01*
X711600Y586511D01*
X732592D01*
X733660Y585443D01*
Y579865D01*
X732650Y578855D01*
X722696D01*
X721210Y577369D01*
Y572408D01*
X720862Y572060D01*
X714664D01*
G37*
G36*
G01X726224Y595609D02*
X726890Y594943D01*
Y590926D01*
X725496Y589532D01*
X714590D01*
X714589Y589531D01*
X711130D01*
X710040Y590621D01*
Y595186D01*
X710463Y595609D01*
X726224D01*
G37*
G36*
G01X721284Y624074D02*
G02X720784Y623574I-500J0D01*
G01X711642D01*
G02X711142Y624074I0J500D01*
G01Y635977D01*
X711702Y636537D01*
X721122D01*
X721372Y636287D01*
Y629702D01*
X721284D01*
Y624074D01*
G37*
G36*
G01X704210Y673036D02*
G03I-640J0D01*
G37*
G36*
G01X708300Y673204D02*
G03I-640J0D01*
G37*
G36*
G01X714550Y681330D02*
G03I-640J0D01*
G37*
G36*
G01X710125Y733400D02*
X708312Y735213D01*
Y740481D01*
G02X708459Y740835I500J0D01*
G01X708825Y741200D01*
X730500D01*
X731400Y740300D01*
Y739735D01*
G02X730040Y738801I-1000J-1D01*
G03Y735999I-540J-1401D01*
G02X731400Y735065I360J-933D01*
G01Y734600D01*
X730200Y733400D01*
X710125D01*
G37*
G36*
G01X709025Y742300D02*
X707725Y743600D01*
Y748100D01*
X709316Y749691D01*
G02X709669Y749838I354J-353D01*
G01X729362D01*
X729736Y749464D01*
G02X729217Y747775I-707J-707D01*
G03X730040Y744899I282J-1475D01*
G02X731400Y743965I360J-933D01*
G01Y743300D01*
X730400Y742300D01*
X709025D01*
G37*
G36*
G01X741630Y102545D02*
X739897Y100812D01*
X725254D01*
X723830Y102236D01*
Y115735D01*
X725150Y117055D01*
X740106D01*
X741630Y115531D01*
Y102545D01*
G37*
G36*
G01X760080Y558383D02*
X760038Y558340D01*
Y549069D01*
X759020Y548051D01*
X738154D01*
X737260Y548945D01*
Y564924D01*
X733127Y569057D01*
X723091D01*
X722963Y569185D01*
Y576494D01*
X724243Y577774D01*
X734158D01*
X735357Y578973D01*
Y585925D01*
X729550Y591732D01*
Y593714D01*
X730800Y594964D01*
X744106D01*
X744168Y594902D01*
X760091D01*
X761050Y593943D01*
Y574401D01*
X760080Y573431D01*
Y558383D01*
G37*
G36*
G01X719150Y681526D02*
G03I-640J0D01*
G37*
G36*
G01X727900Y703100D02*
Y685600D01*
X727950Y685550D01*
Y681950D01*
X728500Y681400D01*
X735100D01*
X736300Y682600D01*
Y685500D01*
Y703300D01*
X735400Y704200D01*
X729000D01*
X727900Y703100D01*
G37*
G36*
G01X720800Y681500D02*
X726300D01*
X726600Y681800D01*
Y685400D01*
Y703500D01*
X725900Y704200D01*
X724300D01*
X721200D01*
X719900Y702900D01*
Y699800D01*
Y682400D01*
X720800Y681500D01*
G37*
G36*
G01X729317Y728160D02*
G03X731400Y727023I1483J240D01*
G02X732800Y726107I400J-916D01*
G01Y707600D01*
X731500Y706300D01*
X726700D01*
X726475Y706525D01*
Y708825D01*
X726500Y708850D01*
Y728700D01*
X726800Y729000D01*
X728330D01*
G02X729317Y728160I0J-1000D01*
G37*
G36*
G01X725300Y710000D02*
Y726800D01*
Y728600D01*
X724900Y729000D01*
X717200D01*
X716900Y728700D01*
Y726500D01*
Y710200D01*
X717650Y709450D01*
X717700D01*
X721150Y706000D01*
X724400D01*
X725300Y706900D01*
Y710000D01*
G37*
G36*
G01X718790Y763015D02*
G03I-640J0D01*
G37*
G36*
G01X721740Y762903D02*
G03I-640J0D01*
G37*
G36*
G01X728210Y775278D02*
G03I-640J0D01*
G37*
G36*
G01X731630Y775334D02*
G03I-640J0D01*
G37*
G36*
G01X751810Y117461D02*
X752840Y116431D01*
Y99245D01*
X751840Y98245D01*
X744034D01*
X743270Y99009D01*
Y116601D01*
X744130Y117461D01*
X751810D01*
G37*
G36*
G01X752820Y444630D02*
X752223Y444032D01*
X744723D01*
X743623Y445132D01*
Y456832D01*
Y458344D01*
X744411Y459132D01*
X745923D01*
X750923D01*
X752820Y457235D01*
Y444630D01*
G37*
G36*
G01X754900Y652063D02*
X754041Y651204D01*
X744334D01*
X744110Y651428D01*
Y660766D01*
X744703Y661359D01*
X754640D01*
X754900Y661099D01*
Y652063D01*
G37*
G36*
G01X764542Y102566D02*
X763630Y101654D01*
X755528D01*
X755137Y102044D01*
G02X754990Y102398I353J354D01*
G01Y108158D01*
X755582Y108750D01*
X763535D01*
X764542Y107743D01*
Y102566D01*
G37*
G36*
G01X761890Y548084D02*
X761040Y548934D01*
Y557932D01*
X761082Y557975D01*
Y561738D01*
X761400Y562056D01*
Y573330D01*
X762440Y574370D01*
Y594439D01*
X763390Y595389D01*
X783210D01*
X783650Y594949D01*
Y549205D01*
X782529Y548084D01*
X761890D01*
G37*
%LPC*%
G75*
G36*
G01X107523Y99696D02*
G03X108251Y98188I1927J0D01*
G02X88601I-9825J-12361D01*
G03X89329Y99696I-1199J1508D01*
G01Y105512D01*
G02X107523I9097J0D01*
G01Y99696D01*
G37*
G36*
G01Y713869D02*
G03X108251Y712361I1927J0D01*
G02X88601I-9825J-12361D01*
G03X89329Y713869I-1199J1508D01*
G01Y719685D01*
G02X107523I9097J0D01*
G01Y713869D01*
G37*
G36*
G01X256994Y54702D02*
G02X258609Y55103I506J1415D01*
G02X256994Y54702I-506J-1415D01*
G37*
G36*
G01X255384Y284633D02*
Y287178D01*
X256385Y288179D01*
G02X258509I1062J-1062D01*
G01X261388Y285300D01*
Y284633D01*
G02X258986Y283431I-1502J0D01*
G03X257786I-600J-800D01*
G02X255384Y284633I-900J1202D01*
G37*
G36*
G01X225989Y282741D02*
X225921Y282706D01*
X224756Y281541D01*
G02X222492Y283805I-1132J1132D01*
G01X223657Y284970D01*
X223692Y285038D01*
G02X223996Y285451I1507J-791D01*
G01X225571Y287026D01*
G02X227977Y284620I1203J-1203D01*
G01X226402Y283045D01*
G02X225989Y282741I-1204J1203D01*
G37*
G36*
G01X238997Y282263D02*
X240136Y281124D01*
X241861D01*
X242967Y282230D01*
G02X245231I1132J-1132D01*
G01X246337Y281124D01*
X248302D01*
X248940Y281762D01*
X248975Y281831D01*
G02X251531Y282230I1424J-733D01*
G01X251771Y281990D01*
G03X252478I353J354D01*
G01X253172Y282684D01*
G02X255296I1062J-1062D01*
G01X256422Y281558D01*
Y278991D01*
X256232Y278801D01*
Y276767D01*
G02X254730Y275266I-1502J1D01*
G01X250958D01*
X248302Y277922D01*
X245674D01*
G02X244542Y278391I0J1601D01*
G01X244452Y278481D01*
G03X243746I-353J-354D01*
G01X243656Y278391D01*
G02X242524Y277922I-1132J1132D01*
G01X239374D01*
G02X238176Y278460I-1J1601D01*
G01X238166Y278472D01*
X238155Y278483D01*
G03X237448I-354J-354D01*
G01X237356Y278391D01*
G02X235092I-1132J1132D01*
G01X235002Y278481D01*
G03X234296I-353J-354D01*
G01X234206Y278391D01*
G02X231942Y280655I-1132J1132D01*
G01X233517Y282230D01*
G02X235781I1132J-1132D01*
G01X235871Y282141D01*
G03X236577I353J354D01*
G01X237169Y282732D01*
X237865D01*
G02X238997Y282263I0J-1601D01*
G37*
G36*
G01X217191Y255941D02*
G03X216039Y256422I-877J-480D01*
G02X215674Y256370I-368J1275D01*
G01X214559D01*
G02X213715Y256674I1J1327D01*
G03X212499Y256718I-637J-771D01*
G02X210721Y257176I-696J979D01*
G01X210684Y257252D01*
X210101Y257835D01*
X209962Y257868D01*
G02X209094Y260218I343J1462D01*
G03Y261401I-807J592D01*
G02X211767Y262632I1211J888D01*
G01X211800Y262493D01*
X213004Y261289D01*
Y260697D01*
G02X212718Y259918I-1201J-1D01*
G03X212772Y258562I761J-649D01*
G01X212811Y258523D01*
G03X213518I353J354D01*
G01X213533Y258538D01*
X213546Y258554D01*
G02X214559Y259024I1013J-857D01*
G01X214798D01*
G03X215226Y259265I0J500D01*
G02X215377Y259473I1286J-775D01*
G03X215215Y260932I-756J655D01*
G02X214640Y261826I894J1207D01*
G01X214609Y261971D01*
X213839Y262741D01*
X213816Y262759D01*
G02X213678Y264507I743J938D01*
G03X213649Y265890I-736J676D01*
G01X213362Y266176D01*
Y266697D01*
G02X213683Y267512I1197J-1D01*
G03X213681Y268876I-732J681D01*
G02X213586Y268992I880J818D01*
G03X212776I-405J-293D01*
G02X212508Y268724I-973J705D01*
G01X212476Y268701D01*
X211798Y268023D01*
X211765Y267884D01*
G02X209101Y269127I-1462J342D01*
G03Y270327I-800J600D01*
G02X209960Y272689I1202J900D01*
G01X210099Y272722D01*
X211628Y274252D01*
X211653Y274414D01*
G02X213359Y272701I1485J-227D01*
G03X212954Y272351I73J-494D01*
G02X212508Y271724I-1151J346D01*
G01X212476Y271701D01*
X212300Y271525D01*
G03Y270817I353J-354D01*
G01X212346Y270771D01*
X212403Y270738D01*
G02X212555Y270634I-600J-1041D01*
G03X213807I626J780D01*
G02X213934Y270723I752J-937D01*
G01X213985Y270754D01*
X214622Y271391D01*
X214657Y271522D01*
G02X217521Y271651I1452J-383D01*
G01X217559Y271546D01*
X217637Y271468D01*
G03X218345I354J353D01*
G01X218494Y271617D01*
X218531Y271698D01*
G02X220824Y271197I1092J-501D01*
G01Y270549D01*
X217661Y267386D01*
X217036D01*
X216920Y267318D01*
G02X216889Y267300I-752J1260D01*
G03X216874Y266432I240J-438D01*
G02X217311Y264239I-765J-1293D01*
G03Y263039I800J-600D01*
G02X217244Y261156I-1202J-900D01*
G03X217406Y259697I756J-655D01*
G02X217573Y259553I-895J-1206D01*
G03X218280I353J354D01*
G01X218773Y260047D01*
G02X220473Y258347I850J-850D01*
G01X219864Y257738D01*
X219809Y257431D01*
X219874Y257289D01*
G02X217191Y255941I-1366J-625D01*
G37*
G36*
G01X275115Y256760D02*
G02X273192Y257429I-752J937D01*
G01X273160Y257569D01*
X272260Y258469D01*
X272121Y258502D01*
G02X273926Y260307I343J1462D01*
G01X273959Y260168D01*
X275566Y258561D01*
G03X276274I354J353D01*
G01X276306Y258593D01*
X276332Y258632D01*
G03X276240Y259878I-825J566D01*
G02X276269Y261547I879J819D01*
G01X278134Y263412D01*
Y263882D01*
X278059Y264004D01*
G02X279293Y266296I1277J791D01*
G03X279751Y266632I-14J500D01*
G02X280036Y267087I1135J-394D01*
G01X280223Y267274D01*
G03Y267982I-353J354D01*
G01X280198Y268007D01*
X280169Y268029D01*
G02X280067Y268114I717J964D01*
G03X278705I-681J-732D01*
G02X277067I-819J879D01*
G03X275705I-681J-732D01*
G02X275361Y267890I-818J880D01*
G03X274863Y266523I396J-919D01*
G02X274983Y266192I-1342J-674D01*
G01X275016Y266053D01*
X275564Y265505D01*
Y263697D01*
G02X273162I-1201J0D01*
G01Y264186D01*
X273007Y264430D01*
X272876Y264492D01*
G02X273601Y267349I644J1357D01*
G03X273997Y268185I26J499D01*
G02X273823Y268433I889J809D01*
G01X273788Y268500D01*
X273240Y269048D01*
X273101Y269081D01*
G02X274344Y271745I342J1462D01*
G03X275544I600J800D01*
G02X277344I900J-1202D01*
G03X278544I600J800D01*
G02X280350Y271741I900J-1202D01*
G03X281495Y271698I603J797D01*
G02X283586Y269644I814J-1262D01*
G01X283510Y269522D01*
Y267162D01*
X281736Y265387D01*
G02X281640Y265302I-843J856D01*
G03X282007Y264416I314J-389D01*
G02X283628Y263265I159J-1494D01*
G01X283661Y263126D01*
X284918Y261870D01*
Y261364D01*
G02X284446Y260410I-1202J1D01*
G01X284420Y260390D01*
X284396Y260366D01*
G03Y259659I354J-353D01*
G01X284630Y259425D01*
G02X282938Y257733I-846J-846D01*
G01X282607Y258064D01*
X282420D01*
X281749Y258735D01*
X281609Y258767D01*
G02X281375Y258841I334J1464D01*
G03X280123Y258403I-379J-925D01*
G02X279154Y257673I-1311J733D01*
G01X279015Y257640D01*
X277871Y256496D01*
X277119D01*
G02X276367Y256760I-1J1201D01*
G03X275115I-626J-780D01*
G37*
G36*
G01X228617Y269946D02*
G03X227558Y271100I-988J156D01*
G02X227443Y271096I-113J1597D01*
G01X224225D01*
X223225Y272096D01*
G02Y274360I1132J1132D01*
G01X225673Y276809D01*
G03X225635Y278259I-707J707D01*
G02X225571Y280726I1139J1264D01*
G01X231871Y287026D01*
G02X234394Y286896I1203J-1203D01*
G03X235143Y286865I388J315D01*
G02X235162Y286885I1098J-1024D01*
G01X235321Y287044D01*
G03Y287752I-353J354D01*
G01X235162Y287911D01*
G02X237286Y290035I1062J1062D01*
G01X238463Y288857D01*
X238532Y288822D01*
G02X238931Y288530I-735J-1423D01*
G01X239023Y288438D01*
G03X239730I354J354D01*
G01X239741Y288449D01*
X239751Y288461D01*
G02X239817Y288530I1190J-1072D01*
G01X239906Y288619D01*
G03Y289326I-354J353D01*
G01X236877Y292355D01*
X236841Y292380D01*
G02X236628Y292560I923J1308D01*
G01X234622Y294565D01*
Y295273D01*
G02X237536Y296192I1602J0D01*
G01X237561Y296156D01*
X238423Y295294D01*
X238468D01*
X242197Y291565D01*
G03X242905I354J353D01*
G01X244320Y292980D01*
X244347Y293020D01*
G02X247276Y292123I1327J-897D01*
G01Y291406D01*
X245169Y289299D01*
G03Y288592I354J-353D01*
G01X246291Y287471D01*
G03X246644Y287324I354J353D01*
G01X247995D01*
G03X248348Y287471I-1J500D01*
G01X249337Y288460D01*
G02X251461I1062J-1062D01*
G01X253036Y286885D01*
G02X250912Y284761I-1062J-1062D01*
G01X250753Y284920D01*
G03X250045I-354J-353D01*
G01X249886Y284761D01*
G02X248824Y284322I-1061J1062D01*
G01X246236D01*
X246162Y284298D01*
G02X244542Y284691I-488J1525D01*
G01X244452Y284781D01*
G03X243746I-353J-354D01*
G01X243656Y284691D01*
G02X241554Y284548I-1133J1132D01*
G03X240344I-605J-796D01*
G02X238242Y284691I-969J1275D01*
G01X238082Y284851D01*
G03X237375Y284850I-353J-354D01*
G01X237286Y284761D01*
G02X235143Y284781I-1062J1062D01*
G03X234394Y284750I-361J-346D01*
G02X234277Y284620I-1321J1072D01*
G01X227977Y278320D01*
G02X227745Y278126I-1203J1203D01*
G03X227890Y277235I285J-411D01*
G02X229018Y275986I-447J-1538D01*
G03X229338Y275607I492J91D01*
G02X229864Y275278I-516J-1410D01*
G03X230570Y275289I347J359D01*
G02X232956Y273505I1078J-1046D01*
G03X233088Y272861I435J-246D01*
G02X233720Y271587I-970J-1275D01*
G01Y270845D01*
X230970Y268096D01*
X230199D01*
G02X228617Y269946I0J1601D01*
G37*
G36*
G01X217975Y309522D02*
X217324D01*
G02X216425Y312225I0J1501D01*
G01X216453Y312247D01*
X217885Y313679D01*
G02X220009Y311555I1062J-1062D01*
G01X217975Y309522D01*
G37*
G36*
G01X270337Y522389D02*
G02X267578Y519346I-2065J-900D01*
G01X267548Y519356D01*
X265845D01*
X265815Y519346D01*
G02X264351Y519373I-693J2143D01*
G01X264318Y519385D01*
X262776D01*
X262743Y519373D01*
G02X260380Y519897I-770J2116D01*
G01X259409Y520867D01*
X256331D01*
X256327Y520863D01*
X254068D01*
X254064Y520867D01*
X251084D01*
X251082Y520869D01*
X250996Y520868D01*
G02X250952Y520867I-72J2201D01*
G01X250032D01*
X248151Y522748D01*
X248134Y522759D01*
G02X247267Y525435I1240J1880D01*
G01X247280Y525469D01*
Y526959D01*
X247267Y526993D01*
G02X247782Y529381I2107J795D01*
G01X247903Y529503D01*
Y532374D01*
X247782Y532496D01*
G02X247229Y534774I1592J1593D01*
G01X247238Y534804D01*
Y536523D01*
X247229Y536553D01*
G02X247329Y538179I2145J684D01*
G01X247347Y538219D01*
Y539404D01*
X247329Y539444D01*
G02X250117Y542513I2045J943D01*
G01X250149Y542502D01*
X251750D01*
X251782Y542513D01*
G02X253296Y542502I742J-2126D01*
G01X253330Y542490D01*
X254866D01*
X254900Y542502D01*
G02X257265Y541979I773J-2115D01*
G01X257387Y541858D01*
X260258D01*
X260380Y541979D01*
G02X263099Y542337I1593J-1592D01*
G01X263145Y542310D01*
X263948D01*
X263994Y542337D01*
G02X266071Y542430I1128J-1949D01*
G01X266111Y542411D01*
X267283D01*
X267323Y542430D01*
G02X270300Y539406I949J-2043D01*
G01X270280Y539365D01*
Y538258D01*
X270300Y538217D01*
G02X270315Y536289I-2028J-980D01*
G01X270296Y536249D01*
Y535077D01*
X270315Y535037D01*
G02X269864Y532496I-2043J-948D01*
G01X269743Y532374D01*
Y529503D01*
X269864Y529381D01*
G02X270241Y526695I-1592J-1593D01*
G01X270216Y526650D01*
Y525777D01*
X270241Y525732D01*
G02X270337Y523740I-1969J-1093D01*
G01X270320Y523702D01*
Y522427D01*
X270337Y522389D01*
G37*
G36*
G01X290007Y340087D02*
G03X289778Y339667I271J-420D01*
G01Y339044D01*
G02X287949Y338020I-1201J0D01*
G03X286774Y337925I-522J-853D01*
G02X285003Y337786I-980J1138D01*
G01X284881Y337862D01*
X283521D01*
G02X282359Y338757I0J1202D01*
G03X281317Y339499I-967J-255D01*
G02X279803Y340457I-112J1498D01*
G03X279337Y340777I-466J-180D01*
G01X279115D01*
G02Y343180I0J1201D01*
G01X280721D01*
X281409Y342492D01*
X281548Y342459D01*
G02X282694Y340798I-343J-1462D01*
G03X283287Y340241I496J-66D01*
G02X283521Y340264I234J-1179D01*
G01X284881D01*
X285003Y340340D01*
G02X286605Y340327I791J-1277D01*
G01X286729Y340248D01*
X286876D01*
G03X287376Y340748I0J500D01*
G01Y341232D01*
X287696Y341552D01*
X287729Y341691D01*
G02X290007Y340087I1462J-343D01*
G37*
G36*
G01X310891Y599441D02*
Y604009D01*
X310894Y604012D01*
Y599441D01*
X310891D01*
G37*
G36*
G01X370779Y301015D02*
G02X367782Y300809I-1499J-99D01*
G03X366958Y301723I-998J-71D01*
G02X368645Y303678I262J1479D01*
G03X369611Y303749I474J159D01*
G02X369719Y304100I1479J-263D01*
G03X369561Y304704I-457J203D01*
G02X371831Y305295I899J1204D01*
G03X371989Y304691I457J-203D01*
G02X371502Y302043I-899J-1203D01*
G03X370779Y301015I275J-962D01*
G37*
G36*
G01X417050Y70004D02*
X415578D01*
X415509Y69985D01*
G02X414389I-560J1921D01*
G01X414320Y70004D01*
X412848D01*
Y73808D01*
X412948D01*
Y75291D01*
G02X416950I2001J0D01*
G01Y73808D01*
X417050D01*
Y70004D01*
G37*
G36*
G01X699152Y97703D02*
G02X678801Y97704I-10176J-12073D01*
G03X679487Y99177I-1241J1474D01*
G01Y105315D01*
G02X698467I9490J0D01*
G01Y99177D01*
G03X699152Y97703I1927J-1D01*
G37*
G36*
G01Y711876D02*
G02X678801Y711877I-10176J-12073D01*
G03X679487Y713350I-1241J1474D01*
G01Y719488D01*
G02X698467I9490J0D01*
G01Y713350D01*
G03X699152Y711876I1927J-1D01*
G37*
G36*
G01X716660Y565132D02*
Y561328D01*
X710873D01*
G02Y565132I0J1902D01*
G01X716660D01*
G37*
G54D216*
X49244Y360352D03*
X145880Y584125D03*
X151900Y590454D03*
X177920Y739302D03*
X342955Y291523D03*
X520510Y337299D03*
X514400Y340829D03*
X509140Y338005D03*
X480830Y333921D03*
X494850Y315733D03*
X484780Y314090D03*
X475190Y339013D03*
X470090Y332824D03*
X545413Y547950D03*
X510338Y571325D03*
X513838Y556925D03*
G54D218*
X318968Y536052D03*
X245609Y517182D03*
X296913Y514460D03*
G54D217*
X301457Y513837D03*
G54D222*
X507489Y360278D03*
G54D224*
X590999Y84915D03*
X615657D03*
G54D219*
X291897Y523069D03*
X288747D03*
X285598D03*
X282448D03*
X279298D03*
X291897Y519919D03*
X288747D03*
X285598D03*
X282448D03*
X279298D03*
X291897Y516770D03*
X288747D03*
X285598D03*
X282448D03*
X291897Y513620D03*
X288747D03*
X285598D03*
X291897Y510471D03*
X288747D03*
G54D214*
X45282Y321764D03*
G54D221*
X414961Y98622D03*
G54D225*
X711575Y143555D03*
X733975D03*
G54D223*
X546181Y81889D03*
G54D213*
X25455Y356832D03*
G54D220*
X413386Y377165D03*
G54D215*
X45282Y338300D03*
%LPD*%
G75*
G54D100*
X186664Y43163D03*
X209694D03*
X199822Y427779D03*
X222852D03*
X268071Y614545D03*
X291101D03*
X294948Y20101D03*
X317978D03*
X361142Y611345D03*
X384172D03*
G54D200*
G01X154307Y507507D02*
X157387D01*
X157611Y507731D01*
G01X154517Y513931D02*
X154617Y514031D01*
X157610D01*
X157611Y514030D01*
G01X159185Y531356D02*
X160760Y529781D01*
Y529778D01*
G01X153731Y520734D02*
X154130Y520335D01*
X157605D01*
X157611Y520329D01*
G01Y532928D02*
X157608Y532931D01*
X155905D01*
X155400Y533436D01*
G01X160760Y532928D02*
Y532930D01*
X159186Y534504D01*
G01X160760Y526629D02*
X162337Y528206D01*
X162335D01*
G01X159185Y543953D02*
X160760Y542378D01*
Y542377D01*
G01X154945Y542383D02*
X154951Y542377D01*
X157611D01*
G01X154945Y536083D02*
X154951Y536077D01*
X157611D01*
G01Y545526D02*
X155060D01*
G01X154900Y548682D02*
X154906Y548676D01*
X157611D01*
G01Y539227D02*
X154951D01*
X154945Y539233D01*
G01X160760Y545526D02*
Y545528D01*
X159185Y547103D01*
G01X157611Y548676D02*
X157612D01*
X159185Y547103D01*
G01X162315Y553391D02*
X162333D01*
X163899Y551825D01*
X163910D01*
G01X154900Y551832D02*
X154907Y551825D01*
X157611D01*
G01X160760D02*
Y551828D01*
X159186Y553402D01*
G01X177720Y246805D02*
X174520D01*
G01X181232Y528205D02*
X181230D01*
X181229Y528206D01*
Y528207D01*
X179658Y529778D01*
G01Y520329D02*
Y520328D01*
X178085Y518755D01*
G01X179658Y523479D02*
Y523483D01*
X178087Y525054D01*
G01X179658Y526629D02*
Y526631D01*
X178117Y528172D01*
Y528187D01*
G01X178082Y537654D02*
Y537656D01*
X179658Y536080D01*
Y536077D01*
G01Y545526D02*
Y545504D01*
X181207Y543955D01*
X181230D01*
G01X179658Y542377D02*
Y542383D01*
X181230Y543955D01*
G01X176508Y536077D02*
X173696D01*
X173217Y536556D01*
G01X179658Y554975D02*
X180707Y556024D01*
Y556652D01*
X181491Y557436D01*
G01X192676Y402961D02*
X193590Y402047D01*
Y400255D01*
G01X186417Y518526D02*
X184614Y520329D01*
X182807D01*
G01X186467Y514036D02*
X186461Y514030D01*
X182807D01*
G01Y517180D02*
X183734Y516253D01*
X187600D01*
X189007Y514846D01*
G01X182807Y510881D02*
X186417D01*
X187417Y509881D01*
Y508756D01*
G01X182807Y532928D02*
X183946Y531789D01*
X186536D01*
X187875Y533128D01*
Y534128D01*
G01X182807Y536077D02*
Y536081D01*
X184382Y537656D01*
G01D02*
X184384D01*
G01X182807Y539227D02*
X182811D01*
X184382Y537656D01*
G01X181230Y543955D02*
X181232Y543953D01*
G01X182807Y542377D02*
X184631Y540553D01*
X186210D01*
X188927Y537836D01*
G01X182807Y545526D02*
X182813D01*
X184384Y543955D01*
G01X182807Y548676D02*
X183206Y549075D01*
X188229D01*
X190434Y546870D01*
G01X188383Y556895D02*
X184721D01*
X182807Y554981D01*
Y554975D01*
G01X184386Y553406D02*
X184382D01*
X182807Y551831D01*
Y551825D01*
G01X226774Y279523D02*
X229924Y282673D01*
G01X215749Y281098D02*
X217324Y282673D01*
G01X226774Y285823D02*
X225199Y284248D01*
G01X220474Y285823D02*
X222049Y287398D01*
G01D02*
X223624Y288973D01*
G01X214174Y285823D02*
X212599Y287398D01*
G01X217324Y285823D02*
X216643Y285142D01*
X214855D01*
X214174Y285823D01*
G01X226774Y307873D02*
X225199Y309448D01*
G01D02*
X226774Y311023D01*
G01Y314173D02*
X225199Y312598D01*
G01D02*
X223624Y311023D01*
G01X217324Y304723D02*
X218899Y306298D01*
G01X227326Y505741D02*
X228905Y507320D01*
Y507321D01*
G01X227329Y508894D02*
X228905Y510470D01*
Y510471D01*
G01Y504171D02*
X228864D01*
X227284Y502591D01*
G01X233074Y285823D02*
X231499Y284248D01*
G01X229924Y282673D02*
X231499Y284248D01*
G01X239374Y311023D02*
X242524Y314173D01*
G01X238510Y308737D02*
X239374Y307873D01*
G01X238510Y310159D02*
Y308737D01*
G01X239374Y311023D02*
X238510Y310159D01*
G01X231499Y309448D02*
X233074Y311023D01*
G01X229924Y298423D02*
X231499Y299998D01*
G01D02*
X233074Y301573D01*
G01X229924Y311023D02*
X231499Y312598D01*
G01D02*
X233074Y314173D01*
G01X240949Y309448D02*
X242524Y311023D01*
G01Y314173D02*
X245674Y317323D01*
G01X230476Y502591D02*
X232054Y504169D01*
Y504171D01*
G01X230476Y505741D02*
X232054Y507319D01*
Y507321D01*
G01Y504171D02*
X232056D01*
X235204Y507319D01*
Y507321D01*
G01X238354Y526219D02*
Y526217D01*
X236776Y524639D01*
G01X245674Y317323D02*
X247270Y315727D01*
X247281D01*
G01D02*
X247350Y315796D01*
Y315849D01*
X248824Y317323D01*
G01X254102Y523069D02*
X254094D01*
X252524Y524639D01*
G01X257251Y523069D02*
X257243D01*
X255673Y524639D01*
G01X250952Y523069D02*
X250944D01*
X249374Y524639D01*
G01X257251Y564014D02*
X257239D01*
X255673Y565580D01*
G01D02*
X254107Y564014D01*
X254102D01*
G01X257251Y551415D02*
X257242D01*
X255673Y552984D01*
G01D02*
X254104Y551415D01*
X254102D01*
G01X257251Y554565D02*
X257241D01*
X255673Y556133D01*
G01D02*
X254105Y554565D01*
X254102D01*
G01X257251Y557715D02*
X257240D01*
X255673Y559282D01*
G01D02*
X254106Y557715D01*
X254102D01*
G01X257251Y560864D02*
X257240D01*
X255673Y562431D01*
G01D02*
X254106Y560864D01*
X254102D01*
G01X247802Y551415D02*
X247805D01*
X249374Y552984D01*
G01D02*
X249344D01*
G01X250952Y551415D02*
X250943D01*
X249374Y552984D01*
G01X274886Y328797D02*
X275142Y329053D01*
Y331297D01*
X274886Y331553D01*
G01X274701Y333804D02*
X274886Y333619D01*
Y331553D01*
G01X265122Y502591D02*
X264535Y503179D01*
X263550Y504163D01*
Y504171D01*
G01X268272Y505741D02*
X267685Y506329D01*
X266700Y507313D01*
Y507321D01*
G01X268272Y508891D02*
X268009Y509153D01*
X267409Y509753D01*
X266810Y510353D01*
X266700Y510463D01*
Y510471D01*
G01X274571Y552985D02*
X273001Y551415D01*
X272999D01*
G01X265122Y552985D02*
X263552Y551415D01*
X263550D01*
G01X268272Y559291D02*
X266700Y557719D01*
Y557715D01*
G01X271422Y562434D02*
X269852Y560864D01*
X269850D01*
G01X271421Y556135D02*
X269851Y554565D01*
X269850D01*
G01X271422Y559291D02*
X269846Y557715D01*
X269850D01*
G01X261973Y552985D02*
X260403Y551415D01*
X260401D01*
G01Y557715D02*
X260447D01*
X262009Y556153D01*
G01D02*
X260421Y554565D01*
X260401D01*
G01Y564014D02*
Y564002D01*
X261972Y562431D01*
G01D02*
X260405Y560864D01*
X260401D01*
G01X271422Y565583D02*
X269853Y564014D01*
X269850D01*
G01X282448Y497872D02*
X282451D01*
X284024Y499445D01*
G01D02*
X282448Y501021D01*
Y501022D01*
G01X290323Y534092D02*
X288749Y532518D01*
X288747D01*
G01X280874Y534092D02*
X279300Y532518D01*
X279298D01*
G01X287174Y534092D02*
X285600Y532518D01*
X285598D01*
G01X280874Y537241D02*
X279300Y535667D01*
X279298D01*
G01X280874Y543541D02*
X279300Y541967D01*
X279298D01*
G01X284024Y543541D02*
X282450Y541967D01*
X282448D01*
G01X287174Y540391D02*
X285600Y538817D01*
X285598D01*
G01X287174Y543541D02*
X285600Y541967D01*
X285598D01*
G01X290323Y540391D02*
X288749Y538817D01*
X288747D01*
G01X290323Y543541D02*
X288749Y541967D01*
X288747D01*
G01X290323Y565589D02*
X288748Y564014D01*
X288747D01*
G01X284024Y565588D02*
X282450Y564014D01*
X282448D01*
G01X287174Y565588D02*
X285600Y564014D01*
X285598D01*
G01X290323Y559289D02*
X288749Y557715D01*
X288747D01*
G01X290323Y562439D02*
X288748Y560864D01*
X288747D01*
G01X290323Y556140D02*
X288748Y554565D01*
X288747D01*
G01X287174Y562438D02*
X285600Y560864D01*
X285598D01*
G01X280874Y562438D02*
X279300Y560864D01*
X279298D01*
G01X284024Y562438D02*
X282450Y560864D01*
X282448D01*
G01X284024Y559289D02*
X282450Y557715D01*
X282448D01*
G01X277725Y552989D02*
X276151Y551415D01*
X276149D01*
G01X280874Y559289D02*
X279300Y557715D01*
X279298D01*
G01X277725Y556135D02*
X276155Y554565D01*
X276149D01*
G01X277725Y559289D02*
X276151Y557715D01*
X276149D01*
G01X287174Y556139D02*
X285600Y554565D01*
X285598D01*
G01X280874Y552989D02*
X279300Y551415D01*
X279298D01*
G01X285598Y557715D02*
Y557713D01*
X284024Y556139D01*
G01X287174Y559289D02*
X285600Y557715D01*
X285598D01*
G01X284024Y556139D02*
X282450Y554565D01*
X282448D01*
G01X287174Y552989D02*
X285600Y551415D01*
X285598D01*
G01X284024Y552989D02*
X282450Y551415D01*
X282448D01*
G01X293473Y534092D02*
X291899Y532518D01*
X291897D01*
G01X293473Y540391D02*
X291899Y538817D01*
X291897D01*
G01X293473Y565589D02*
X291898Y564014D01*
X291897D01*
G01X293473Y562439D02*
X291898Y560864D01*
X291897D01*
G01X293473Y559290D02*
X291898Y557715D01*
X291897D01*
G01X313583Y122387D02*
Y114763D01*
G01X323032D02*
Y122237D01*
G01X384758Y657739D02*
X379093D01*
G01X384758Y660239D02*
X380101D01*
G01X384758Y680442D02*
X380779D01*
X379791Y679454D01*
G01X451840Y649436D02*
X456342D01*
G01X474840Y646876D02*
X481582D01*
X482180Y646278D01*
G01X594920Y123370D02*
X595515Y122775D01*
X600118D01*
G01X595345Y120216D02*
X600118D01*
G54D101*
X193300Y246260D03*
X187636D03*
X181236D03*
X180422Y350586D03*
X186822D03*
X192486D03*
X211028Y246260D03*
X205364D03*
X198964D03*
X204550Y350586D03*
X198150D03*
X210214D03*
X216692Y246260D03*
X223092D03*
X222278Y350586D03*
X215878D03*
X234420Y246260D03*
X240820D03*
X228756D03*
X227942Y350586D03*
X240006D03*
X233606D03*
X252148Y246260D03*
X246484D03*
X258548D03*
X245670Y350586D03*
X251334D03*
X257734D03*
X269876Y246260D03*
X264212D03*
X263398Y350586D03*
X269062D03*
X276276Y246260D03*
X275462Y350586D03*
G54D110*
X208430Y599735D03*
X198210Y601459D03*
X595294Y260495D03*
X605890Y258785D03*
X625835Y400347D03*
X637543Y399147D03*
G54D210*
G01X152990Y248096D02*
X155131D01*
X160865Y242362D01*
X164192D01*
X166467Y244637D01*
Y248352D01*
X168120Y250005D01*
G01X171320D02*
X169565Y248250D01*
Y241996D01*
X167483Y239914D01*
G01X171095Y262559D02*
Y263570D01*
X171367Y263842D01*
X171867D01*
X173120Y262589D01*
X173263D01*
G01X172982Y264570D02*
X173310Y264242D01*
X173967D01*
X175585Y262624D01*
X176301D01*
G01X166332Y283127D02*
X165769D01*
X164375Y281733D01*
Y280287D01*
G01D02*
Y276877D01*
X165230Y276022D01*
X166810D01*
X169660Y278872D01*
Y280774D01*
X170515Y281629D01*
X172313D01*
X172982Y282298D01*
G01X172426Y287813D02*
Y287581D01*
X174814Y285193D01*
X176740D01*
X178810Y287263D01*
G01X172426Y290569D02*
X173216Y289779D01*
X173658D01*
X174148Y289289D01*
G01X171095Y298015D02*
X170022Y296942D01*
X167442D01*
X166701Y297683D01*
Y300486D01*
X166332Y300855D01*
G01X166778Y287327D02*
X167900D01*
X169749Y285478D01*
Y284452D01*
X168424Y283127D01*
X166332D01*
G01X172982Y282298D02*
Y283170D01*
X171792Y284361D01*
X171591Y284561D01*
Y286724D01*
X171110Y287205D01*
Y288385D01*
X169684Y289811D01*
Y290951D01*
G01X166332Y300855D02*
X165623D01*
X164375Y299607D01*
Y298015D01*
G01X190155Y337649D02*
X190191Y337685D01*
X191867D01*
X192230Y337322D01*
G01X190155Y334649D02*
X190158Y334646D01*
X191000D01*
X192040Y333606D01*
G01X223166Y341784D02*
X222485D01*
X221280Y340579D01*
G01X240949Y299998D02*
X242524Y298423D01*
G01X234319Y337649D02*
X234272D01*
X232804Y336181D01*
G01X256886Y297517D02*
Y297478D01*
X258380Y295984D01*
G01X245674Y298423D02*
X244099Y299998D01*
G01X245674Y307873D02*
X247249Y306298D01*
G01X256886Y300273D02*
Y301855D01*
X257418Y302387D01*
Y303533D01*
G01X258386Y305337D02*
Y305242D01*
X259820Y303808D01*
Y303800D01*
G01X259886Y300273D02*
X260155D01*
X261915Y302033D01*
G54D201*
G01X27018Y16186D02*
X24411D01*
G01X57029Y257049D02*
X54062D01*
G01X59920Y170026D02*
X56190D01*
G01X61022Y180712D02*
X57257D01*
G01X60729Y204326D02*
X57749D01*
G01X60032Y228683D02*
X63720D01*
G01X56148Y530809D02*
X57754Y529203D01*
X59299D01*
G01X82030Y191733D02*
X86744D01*
G01X85876Y218939D02*
X86671Y219734D01*
X90733D01*
G01X74796Y267579D02*
X79544D01*
G01X72368Y290582D02*
Y287906D01*
G01X82368Y293732D02*
Y297135D01*
G01X79235Y513104D02*
X81635D01*
G01X79235Y517104D02*
X81635D01*
G01X79235Y521104D02*
X81635D01*
G01X90673Y205852D02*
X86560D01*
G01X91458Y509198D02*
Y511853D01*
G01X110490Y397362D02*
X112800D01*
X113620Y398182D01*
Y398184D01*
G01X106243Y406383D02*
Y410689D01*
X105670Y411262D01*
G01D02*
Y412353D01*
X106816Y413499D01*
X109342D01*
G01X114072Y480964D02*
X112948D01*
X112072Y481840D01*
Y483758D01*
G01X108026Y483711D02*
X108073Y483758D01*
X112072D01*
G01X129860Y14571D02*
Y12816D01*
X131514Y11162D01*
X135403D01*
G01X134082Y43439D02*
X131474D01*
G01X122018Y516353D02*
X121980Y516315D01*
Y513831D01*
G01X129607Y689212D02*
Y686735D01*
G01X141699Y25494D02*
X137500D01*
G01X145210Y57660D02*
Y60154D01*
G01X137091Y301799D02*
X138245Y300645D01*
X141242D01*
X141262Y300625D01*
G01X138857Y310543D02*
Y314543D01*
G01X139575Y305640D02*
X136130D01*
G01X138857Y323543D02*
X135224D01*
G01X135507Y421367D02*
Y417872D01*
X137704Y415675D01*
Y412003D01*
G01X151101Y441929D02*
X147820D01*
G01X134753Y726161D02*
X135741Y725173D01*
X137278D01*
G01X137177Y734726D02*
X134777D01*
G01X137177Y738726D02*
X134777D01*
G01X158181Y14450D02*
Y11978D01*
G01X150787Y12151D02*
Y9246D01*
G01X154592Y24216D02*
Y21173D01*
G01X153863Y17718D02*
Y15176D01*
G01X149157Y57580D02*
Y60010D01*
G01X161221Y82480D02*
Y89447D01*
G01X160040Y114763D02*
Y108844D01*
G01X161563Y432521D02*
X164447D01*
G01X164245Y436834D02*
X161577D01*
G01X165512Y50968D02*
X169149D01*
G01X177757Y82480D02*
Y88271D01*
G01X170506Y424127D02*
X170487Y424146D01*
X167861D01*
G01X175993Y417621D02*
Y414924D01*
G01X175619Y697976D02*
X178278D01*
G01X175619Y701976D02*
X178278D01*
G01X175619Y705976D02*
X178278D01*
G01X175619Y709976D02*
X178278D01*
G01X171689Y724473D02*
Y728920D01*
G01X180078Y730521D02*
X182674D01*
G01X191930Y82480D02*
Y88507D01*
G01X184843Y82480D02*
Y88467D01*
G01X180990Y108770D02*
X181293Y109073D01*
Y114756D01*
X181300Y114763D01*
G01X195473D02*
Y108767D01*
G01X190700Y418325D02*
X190100Y418925D01*
X188261D01*
G01X188267Y414885D02*
X188261Y414891D01*
Y418925D01*
G01X182163Y684555D02*
X184482D01*
X185993Y686066D01*
Y688002D01*
G01X183440Y708356D02*
X187744D01*
G01X206103Y82480D02*
Y88207D01*
G01X199016Y82480D02*
Y88434D01*
G01X210203Y108457D02*
X210813D01*
X212009Y109653D01*
Y114763D01*
G01X202560D02*
Y107797D01*
G01X202823Y376922D02*
X201995Y376094D01*
Y373701D01*
G01X212729Y382323D02*
X208729D01*
G01X207473Y678356D02*
Y676538D01*
X205732Y674797D01*
Y671772D01*
G01X196463Y685036D02*
X198485D01*
X199993Y686544D01*
Y688002D01*
G01X211440Y708356D02*
Y711425D01*
X210023Y712842D01*
G01X198940Y712499D02*
Y709856D01*
X197440Y708356D01*
G01X213190Y82480D02*
Y88414D01*
G01X219095Y114763D02*
Y108675D01*
G01X226713Y122007D02*
X226182Y121476D01*
Y114763D01*
G01X223561Y385108D02*
X224729Y383940D01*
Y382323D01*
G01X214008Y385165D02*
X212729Y383886D01*
Y382323D01*
G01X221438Y390655D02*
X220729Y389946D01*
Y382323D01*
G01X216729D02*
X220729D01*
G01X215768Y671993D02*
X215989Y671772D01*
X219229D01*
G01X224360Y684366D02*
X226993Y686999D01*
Y688002D01*
G01X213365D02*
Y692151D01*
G01X229725Y82480D02*
Y88719D01*
G01X236812Y82480D02*
Y88698D01*
G01X240355Y114763D02*
Y108757D01*
G01X233268Y114763D02*
Y121742D01*
G01X243940Y390885D02*
Y390219D01*
X242631Y388910D01*
Y387964D01*
G01X236687Y385234D02*
Y385237D01*
X236729Y385195D01*
Y382323D01*
G01X240729D02*
X236729D01*
G01X232172Y388814D02*
Y388816D01*
X232729Y388259D01*
Y382323D01*
G01X233017Y671672D02*
X229895D01*
G01X240493Y688002D02*
Y692678D01*
G01X238348Y712469D02*
X240440Y710377D01*
Y708356D01*
G01X258300Y22289D02*
Y23122D01*
X260110Y24932D01*
G01X250661Y384780D02*
X248729Y382848D01*
Y382323D01*
G01X250952Y564014D02*
X249909Y565057D01*
Y568653D01*
G01X246313Y629609D02*
X247408Y628514D01*
X249013D01*
G01X259895Y671772D02*
X257271D01*
G01X246475D02*
X243596D01*
G01X253993Y688002D02*
Y691762D01*
X253398Y692357D01*
G01D02*
X254986Y693945D01*
X255841D01*
G01X254940Y708356D02*
Y712381D01*
G01X271421Y10016D02*
Y7319D01*
G01X265934Y16522D02*
X265915Y16541D01*
X263289D01*
G01X265886Y268993D02*
Y271718D01*
G01X262798Y420929D02*
Y417886D01*
G01D02*
X263741Y416943D01*
X266732D01*
G01X281142Y402379D02*
X280319Y403202D01*
X277775D01*
Y403203D01*
G01X276347Y451576D02*
Y459741D01*
G01X297142Y372173D02*
X293142D01*
G01X298202Y374572D02*
X297142Y373512D01*
Y372173D01*
G01X302036Y623877D02*
X299629D01*
G01X303949Y717212D02*
Y719129D01*
X305213Y720393D01*
G01X299867Y721080D02*
X301687D01*
X301944Y720823D01*
X304783D01*
X305213Y720393D01*
G01X331376Y299883D02*
X316648D01*
X316585Y299946D01*
G01X309131Y374573D02*
X309142Y374562D01*
Y372173D01*
G01X312824Y387863D02*
X315383D01*
G01X307116Y385979D02*
X309117D01*
X311001Y387863D01*
X312824D01*
G01X315533Y384749D02*
X315758Y384524D01*
Y381793D01*
X316980Y380571D01*
G01X320113Y463789D02*
X323907D01*
G01X321357Y456709D02*
X320113Y457953D01*
Y463789D01*
G01X320106Y475619D02*
X322605D01*
X323921Y476935D01*
X325520D01*
G01X321246Y472669D02*
X320106Y473809D01*
Y475619D01*
G01X319135Y594112D02*
Y591407D01*
G01X320367Y618071D02*
X321275Y617163D01*
X323036D01*
G01X314910Y624577D02*
Y627222D01*
G01X332453Y122297D02*
X330119Y119963D01*
Y114763D01*
G01X336057Y575657D02*
X336267Y575447D01*
Y572677D01*
G01X340388Y572720D02*
X340345Y572677D01*
X336267D01*
G01X329260Y603381D02*
Y604254D01*
X328150Y605364D01*
X326628D01*
G01X328930Y611691D02*
Y611680D01*
X326730Y609480D01*
X326723D01*
G01X351533Y124697D02*
X351541D01*
X353741Y122497D01*
Y114763D01*
G01X356550Y74767D02*
X356503D01*
X355728Y73992D01*
Y69305D01*
G01X360827Y114763D02*
Y108541D01*
G01X365026Y329623D02*
Y332478D01*
G01X374203Y488024D02*
X369500D01*
G01X374207Y476524D02*
X374202Y476529D01*
X369989D01*
G01X368943Y509323D02*
Y506356D01*
G01X368238Y519528D02*
Y522673D01*
G01X361433Y543236D02*
X357871D01*
X357109Y542474D01*
Y535272D01*
X357820Y534561D01*
G01X361646Y689228D02*
X360367Y690507D01*
X359202D01*
X359085Y690624D01*
G01X367866Y677326D02*
X368762Y678222D01*
X370283D01*
G01X384450Y114763D02*
Y108830D01*
G01X374207Y473374D02*
X377284D01*
G01X374203Y484874D02*
Y482079D01*
G01X374207Y479329D02*
Y476524D01*
G01X374203Y491029D02*
Y488024D01*
G01X380786Y514797D02*
X383924D01*
G01X393371Y69643D02*
Y72919D01*
G01X399653Y108357D02*
X398623Y109387D01*
Y114763D01*
G01X391536D02*
Y108990D01*
G01X400154Y532016D02*
X396350D01*
G01X394593Y628233D02*
Y624115D01*
X394599Y624109D01*
G01X392063D02*
X394599D01*
G01X403739Y69610D02*
Y72783D01*
G01X416011Y550342D02*
Y548106D01*
X416515Y547602D01*
G01X402499Y554143D02*
X403124Y554768D01*
Y558626D01*
G01X405831Y554402D02*
Y553091D01*
X404578Y551838D01*
G01X412960Y618207D02*
X412979Y618188D01*
X415605D01*
G01X405426Y626809D02*
Y626808D01*
X407473Y624761D01*
Y624713D01*
G01X409581Y711643D02*
X407389Y713835D01*
X406646D01*
G01X419071Y509283D02*
Y509228D01*
X421422Y506877D01*
X421788D01*
G01X419221Y609542D02*
Y612253D01*
G01X419654Y644754D02*
Y644751D01*
X419854Y644551D01*
X422778D01*
X423623Y645396D01*
G01X422470Y647852D02*
Y647859D01*
X421630Y648699D01*
X419569D01*
G01X423317Y705344D02*
X422822Y704849D01*
X420762D01*
X420577Y704664D01*
G01X443845Y499673D02*
Y509635D01*
G01X443114Y498942D02*
X443845Y499673D01*
G01X439749Y509637D02*
Y506523D01*
G01X439440Y553337D02*
X442240D01*
G01X457583Y69194D02*
Y66384D01*
G01X450576Y234431D02*
Y237162D01*
G01D02*
Y241162D01*
G01X454150Y249053D02*
Y249054D01*
X453800Y249404D01*
X450910D01*
G01X457165Y262368D02*
X457088Y262291D01*
X453982D01*
G01X464767Y74997D02*
Y78145D01*
G01X495300Y201600D02*
Y198703D01*
X495276D01*
G01X482613Y210434D02*
X486738D01*
G01X491046Y207506D02*
Y207546D01*
X493258Y209758D01*
X498701D01*
G01X491304Y227953D02*
Y231793D01*
X491320Y231809D01*
G01X496140Y608883D02*
X495238D01*
X494238Y607883D01*
Y606600D01*
G01X512160Y214600D02*
X509539D01*
X509263Y214876D01*
X506279D01*
G01X496123Y230820D02*
Y233500D01*
G01X513500Y224618D02*
X513437Y224681D01*
X506356D01*
G01X507638Y522050D02*
X504613D01*
G01Y525200D02*
X507638D01*
G01X504268Y608625D02*
X504263D01*
X502238Y606600D01*
G01X498238D02*
Y607025D01*
X500098Y608885D01*
G01X511997Y207730D02*
Y211287D01*
X512160Y211450D01*
G01Y217073D02*
Y214600D01*
G01X519183Y224173D02*
X516478Y221468D01*
X513500D01*
G01X517189Y226229D02*
X515578Y224618D01*
X513500D01*
G01X526638Y608050D02*
Y605825D01*
X525570Y604757D01*
Y602466D01*
G01X547148Y220220D02*
X539858D01*
X539026Y219388D01*
X535929D01*
G01X539438Y250323D02*
X541572Y252457D01*
Y253862D01*
G01X536440Y434581D02*
Y431923D01*
G01X541440Y434581D02*
Y431787D01*
G01X531570Y716345D02*
X534322D01*
X535485Y715182D01*
G01D02*
X536471Y716168D01*
X541440D01*
G01X547927Y212190D02*
X545368D01*
X544810Y211632D01*
G01X556959Y443009D02*
X553860D01*
X553821Y443048D01*
G01X549940Y713018D02*
X549037D01*
X547542Y711523D01*
G01X564213Y524325D02*
Y524326D01*
X567088D01*
X568068Y525306D01*
G01X572113Y545425D02*
X575438D01*
G01X572113Y552025D02*
X575238D01*
G01X575038Y567725D02*
X572113D01*
G01Y571725D02*
X575538D01*
G01X571413Y579525D02*
X574738D01*
G01X571513Y587425D02*
X574738D01*
G01X568908Y735883D02*
Y735971D01*
X568940Y736003D01*
Y739081D01*
G01X586842Y158949D02*
X586422D01*
X584438Y160933D01*
G01D02*
X586769Y163264D01*
Y163311D01*
G01X589811Y175906D02*
X592491D01*
G01X585013Y545225D02*
Y547959D01*
G01Y540625D02*
Y545225D01*
G01X584413Y559445D02*
Y563198D01*
G01X584483Y555235D02*
Y553170D01*
X583538Y552225D01*
G01X579020Y658250D02*
X579008D01*
G01X581586Y657848D02*
X579410D01*
X579008Y658250D01*
G01X591918Y653385D02*
X594733D01*
G01X620131Y645072D02*
X614579D01*
G01X626978Y296525D02*
X627369Y296916D01*
Y300555D01*
G01X624101Y296525D02*
X626978D01*
G01X628378Y387178D02*
Y386529D01*
X627118Y385269D01*
Y383809D01*
X627022Y383713D01*
G01X629855Y383132D02*
X627603D01*
X627022Y383713D01*
G01X653352Y288333D02*
Y291388D01*
G01X655170Y636990D02*
Y639432D01*
G01X679552Y372873D02*
X678264Y371585D01*
Y369598D01*
G01X687571Y172292D02*
Y168207D01*
X687546Y168182D01*
G01X700829Y481755D02*
Y481754D01*
X702797Y479786D01*
G01X714559Y563230D02*
X710873D01*
G01X726829Y515757D02*
X729942D01*
G01X740126Y478975D02*
X743364D01*
G01X740104Y483641D02*
X743020D01*
X743150Y483511D01*
Y483502D01*
G01X739985Y487639D02*
X742779D01*
G54D120*
X284428Y654034D03*
Y656002D03*
Y657971D03*
Y659939D03*
Y661908D03*
Y663876D03*
Y665845D03*
Y667813D03*
Y669782D03*
Y671750D03*
Y673719D03*
Y675688D03*
Y677656D03*
Y679624D03*
Y681593D03*
Y683562D03*
Y685530D03*
Y687499D03*
Y689467D03*
Y691436D03*
Y693404D03*
Y695373D03*
Y697341D03*
Y699310D03*
Y701278D03*
X345452Y659939D03*
Y657971D03*
Y656002D03*
Y654034D03*
Y675688D03*
Y673719D03*
Y671750D03*
Y669782D03*
Y667813D03*
Y665845D03*
Y663876D03*
Y661908D03*
Y691436D03*
Y689467D03*
Y687499D03*
Y685530D03*
Y683562D03*
Y681593D03*
Y679624D03*
Y677656D03*
Y701278D03*
Y699310D03*
Y697341D03*
Y695373D03*
Y693404D03*
X510928Y650034D03*
Y652002D03*
Y653971D03*
Y655939D03*
Y657908D03*
Y659876D03*
Y661845D03*
Y663813D03*
Y665782D03*
Y667750D03*
Y669719D03*
Y671688D03*
Y673656D03*
Y675624D03*
Y677593D03*
Y679562D03*
Y681530D03*
Y683499D03*
Y685467D03*
Y687436D03*
Y689404D03*
Y691373D03*
Y693341D03*
Y695310D03*
Y697278D03*
X571952Y659876D03*
Y657908D03*
Y655939D03*
Y653971D03*
Y652002D03*
Y650034D03*
Y675624D03*
Y673656D03*
Y671688D03*
Y669719D03*
Y667750D03*
Y665782D03*
Y663813D03*
Y661845D03*
Y691373D03*
Y689404D03*
Y687436D03*
Y685467D03*
Y683499D03*
Y681530D03*
Y679562D03*
Y677593D03*
Y697278D03*
Y695310D03*
Y693341D03*
G54D102*
X197429Y393326D03*
G54D111*
X226331Y13885D03*
Y39081D03*
X245147Y13885D03*
Y39081D03*
G54D211*
G01X164280Y101810D02*
X163583Y101113D01*
Y82480D01*
G01X159190Y127781D02*
Y122200D01*
X162402Y118988D01*
Y114763D01*
G01X168850Y99251D02*
X170563Y97538D01*
Y89457D01*
X173032Y86988D01*
Y82480D01*
G01X173900Y97662D02*
X173708Y97470D01*
Y90272D01*
X175394Y88586D01*
Y82480D01*
G01X180119D02*
Y89211D01*
X177733Y91597D01*
Y91967D01*
G01X167383Y93147D02*
Y91847D01*
X165946Y90410D01*
Y82480D01*
G01X169510Y106579D02*
X171472Y108541D01*
X174489D01*
X176576Y110628D01*
Y114763D01*
G01X177680Y101764D02*
X178888Y102972D01*
X179928D01*
X186024Y109068D01*
Y114763D01*
G01X174710Y105699D02*
Y106295D01*
X178938Y110523D01*
Y114763D01*
G01X164490Y127110D02*
X164765Y126835D01*
Y114763D01*
G01X177763Y121057D02*
X181753D01*
X183662Y119148D01*
Y114763D01*
G01X168170Y123367D02*
X170095Y121442D01*
Y120098D01*
X169489Y119492D01*
Y114763D01*
G01X173170Y123367D02*
X171245Y121442D01*
Y120098D01*
X171851Y119492D01*
Y114763D01*
G01X184928Y91847D02*
X186336D01*
X186853Y91330D01*
Y89581D01*
X187811Y88623D01*
Y87815D01*
X187205Y87209D01*
Y82480D01*
G01X183013Y98813D02*
X181610Y97410D01*
Y91950D01*
X182481Y91079D01*
Y82480D01*
G01X190100Y99701D02*
X193423Y96378D01*
Y90497D01*
X194292Y89628D01*
Y82480D01*
G01X189928Y91847D02*
X188491D01*
X188003Y91359D01*
Y90058D01*
X188961Y89100D01*
Y87815D01*
X189568Y87208D01*
Y82480D01*
G01X194463Y122631D02*
X205611D01*
X207284Y120958D01*
Y114763D01*
G01X202530Y239636D02*
Y233556D01*
X199113Y230139D01*
X184050D01*
G01X200480Y97687D02*
Y97120D01*
X201379Y96221D01*
Y82480D01*
G01X208465D02*
Y87209D01*
X209071Y87815D01*
Y91982D01*
X210833Y93744D01*
Y95050D01*
X208908Y96975D01*
G01X210827Y82480D02*
Y87209D01*
X210221Y87815D01*
Y91505D01*
X211983Y93267D01*
Y95050D01*
X213908Y96975D01*
G01X196654Y82480D02*
X196653D01*
Y91837D01*
G01X203741Y82480D02*
Y88059D01*
X204001Y88319D01*
X204003D01*
Y91247D01*
G01X197835Y114763D02*
Y106979D01*
X196493Y105637D01*
G01X212423Y104957D02*
X209303D01*
X204922Y109338D01*
Y114763D01*
G01X200198D02*
Y106252D01*
X199993Y106047D01*
Y103637D01*
G01X215552Y82480D02*
Y89927D01*
X215772Y90147D01*
X215773D01*
G01X233083Y94817D02*
X228827D01*
X224430Y90420D01*
Y87825D01*
X225000Y87255D01*
X225001D01*
Y82480D01*
G01X222639D02*
Y91243D01*
X222983Y91587D01*
G01X220200Y93561D02*
X220193D01*
X218663Y92031D01*
Y90017D01*
X217913Y89267D01*
Y82480D01*
X217914D01*
G01X214320Y101978D02*
X214763Y102421D01*
Y108127D01*
X214371Y108519D01*
Y114763D01*
G01X234243Y100156D02*
X223820Y110579D01*
Y114763D01*
G01X220983Y106174D02*
X221453Y106644D01*
Y114763D01*
X221457D01*
G01X219510Y101338D02*
Y103542D01*
X216733Y106319D01*
Y114763D01*
G01X214559Y257697D02*
X215674D01*
X216512Y258535D01*
Y258490D01*
G01X234450Y82480D02*
Y90644D01*
X235113Y91307D01*
G01X232087Y82480D02*
Y90473D01*
X231013Y91547D01*
G01X241536Y82480D02*
Y86870D01*
X242623Y87957D01*
Y88017D01*
X243373Y88767D01*
G01X239174Y82480D02*
Y89346D01*
X239554Y89726D01*
X239563D01*
Y92077D01*
G01X235631Y114763D02*
Y109000D01*
X234452Y107821D01*
X231313D01*
X230643Y108491D01*
Y108497D01*
G01X237993Y114763D02*
Y103827D01*
X237773Y103607D01*
G01X242717Y114763D02*
Y106353D01*
X242913Y106157D01*
G01X230906Y114763D02*
Y119492D01*
X230300Y120098D01*
Y121187D01*
X231213Y122100D01*
Y123877D01*
X233138Y125802D01*
G01X228544Y114763D02*
Y119492D01*
X229150Y120098D01*
Y121664D01*
X230063Y122577D01*
Y123877D01*
X228138Y125802D01*
G01X258072Y82480D02*
Y87208D01*
X257465Y87815D01*
Y89285D01*
X255363Y91387D01*
X252543D01*
X251643Y92287D01*
Y93123D01*
X253558Y95038D01*
G01X255709Y82480D02*
Y87209D01*
X256315Y87815D01*
Y88808D01*
X254886Y90237D01*
X252066D01*
X250493Y91810D01*
Y93103D01*
X248558Y95038D01*
G01X261615Y114763D02*
Y110467D01*
X257665Y106517D01*
X253333D01*
X252683Y105867D01*
G01X254528Y114763D02*
X249909D01*
X249453Y114307D01*
G01X315600Y189807D02*
X313763D01*
X281900Y221670D01*
X270856D01*
X270080Y222446D01*
Y223544D01*
X270856Y224320D01*
X277704D01*
X278480Y225096D01*
Y226194D01*
X277704Y226970D01*
X267957D01*
X267181Y226194D01*
Y222655D01*
X266196Y221670D01*
X260021D01*
X258950Y222741D01*
Y224254D01*
X260021Y225325D01*
X263674D01*
X264450Y226101D01*
Y227199D01*
X263417Y228232D01*
X262534D01*
X262030Y228736D01*
Y240378D01*
G01X324393Y146984D02*
Y150477D01*
X321470Y153400D01*
Y184375D01*
X322246Y185151D01*
X323344D01*
X324120Y184375D01*
Y156327D01*
X324896Y155551D01*
X325994D01*
X326770Y156327D01*
Y186738D01*
X318373Y195135D01*
X312044D01*
X282072Y225107D01*
Y227439D01*
X280358Y229153D01*
X267220D01*
X264570Y231803D01*
Y238017D01*
G01X262796Y82480D02*
Y90744D01*
X261370Y92170D01*
Y97589D01*
X263683Y99902D01*
G01X272245Y82480D02*
Y89585D01*
G01X265158Y82480D02*
Y92392D01*
X263703Y93847D01*
G01X271133Y92787D02*
X269883Y91537D01*
Y82480D01*
G01X263977Y114763D02*
Y108441D01*
X262473Y106937D01*
G01X295060Y247266D02*
X297144Y245182D01*
X309223D01*
X311290Y247249D01*
G01X312680Y258353D02*
X308640Y262393D01*
Y267816D01*
X300070Y276386D01*
G01X299776Y248010D02*
X301194D01*
X305310Y252126D01*
Y267816D01*
X298131Y274995D01*
G01X300591Y82480D02*
Y87209D01*
X299985Y87815D01*
Y90187D01*
X301870Y92072D01*
G01X298229Y82480D02*
Y87209D01*
X298835Y87815D01*
Y90107D01*
X296870Y92072D01*
G01X291927Y102991D02*
X293882Y104946D01*
Y106598D01*
X295016Y107732D01*
X298886D01*
X300003Y108849D01*
Y109907D01*
X299410Y110500D01*
Y114763D01*
G01X296927Y102991D02*
X295032Y104886D01*
Y106121D01*
X295493Y106582D01*
X299363D01*
X301153Y108372D01*
Y109967D01*
X301772Y110586D01*
Y114763D01*
G01X320740Y98599D02*
Y94605D01*
X319483Y93348D01*
Y86947D01*
X319489Y86941D01*
Y82480D01*
G01X317970Y95961D02*
X317123Y95114D01*
Y90251D01*
X317127D01*
Y82480D01*
G01X315946Y114763D02*
X315940D01*
Y127388D01*
X316422Y127870D01*
X319060D01*
X319860Y128670D01*
Y130014D01*
X319060Y130814D01*
X316716D01*
X315940Y131590D01*
Y132880D01*
X316647Y133587D01*
X320761D01*
X321672Y134498D01*
Y136788D01*
X320280Y138180D01*
Y140702D01*
X321450Y141872D01*
Y143352D01*
X320280Y144522D01*
Y149356D01*
X317153Y152483D01*
Y154840D01*
X317929Y155616D01*
X318144D01*
X318920Y156392D01*
Y157490D01*
X318144Y158266D01*
X317626D01*
X316850Y159042D01*
Y160140D01*
X317626Y160916D01*
X318144D01*
X318920Y161692D01*
Y162790D01*
X318144Y163566D01*
X317476D01*
X316700Y164342D01*
Y165440D01*
X317476Y166216D01*
X318144D01*
X318920Y166992D01*
Y168090D01*
X318144Y168866D01*
X317526D01*
X316750Y169642D01*
Y170740D01*
X317526Y171516D01*
X318144D01*
X318920Y172292D01*
Y173390D01*
X318144Y174166D01*
X317416D01*
X316640Y174942D01*
Y176040D01*
X317416Y176816D01*
X318144D01*
X318920Y177592D01*
Y178690D01*
X318144Y179466D01*
X317436D01*
X316660Y180242D01*
Y181340D01*
X317436Y182116D01*
X318144D01*
X318880Y182852D01*
Y185505D01*
X320760Y187385D01*
Y188561D01*
X318207Y191114D01*
X316900D01*
X315600Y189814D01*
Y189807D01*
G01X318308Y114763D02*
Y123226D01*
X321856Y126774D01*
X322723D01*
X324390Y128441D01*
Y130595D01*
X324393D01*
Y146984D01*
G01X333662Y82480D02*
Y87209D01*
X333056Y87815D01*
Y88930D01*
X333763Y89637D01*
Y90917D01*
X335668Y92822D01*
G01X331300Y82480D02*
Y87209D01*
X331906Y87815D01*
Y89407D01*
X332613Y90114D01*
Y90877D01*
X330668Y92822D01*
G01X325360Y92517D02*
X326576Y91301D01*
Y82480D01*
G01X324070Y88861D02*
X324213Y88718D01*
Y82480D01*
G01X327430Y108208D02*
X327757Y108535D01*
Y114763D01*
G01X327190Y103818D02*
Y104877D01*
X325394Y106673D01*
Y114763D01*
G01X334843D02*
Y108751D01*
X337299Y106295D01*
X337630D01*
Y106304D01*
G01X334720Y102184D02*
Y102193D01*
X336469D01*
X339820Y105544D01*
Y108014D01*
X337205Y110629D01*
Y114763D01*
G01X340749Y82480D02*
Y88441D01*
X340543Y88647D01*
G01X347835Y82480D02*
Y92765D01*
X345753Y94847D01*
X344873D01*
G01X338387Y82480D02*
X338393Y82486D01*
Y90307D01*
X340060Y91974D01*
Y95334D01*
X341163Y96437D01*
X341170D01*
X343070Y98337D01*
Y99372D01*
G01X345473Y82480D02*
Y90827D01*
X345463Y90837D01*
G01X341930Y114763D02*
Y109802D01*
X343090Y108642D01*
Y104554D01*
X340450Y101914D01*
G01X349016Y114763D02*
Y119492D01*
X349622Y120098D01*
Y121911D01*
X347642Y123891D01*
Y128764D01*
X348965Y130087D01*
X350623D01*
X351503Y130967D01*
Y130972D01*
G01X344292Y114763D02*
Y120418D01*
X343743Y120967D01*
G01X351379Y114763D02*
Y119491D01*
X350772Y120098D01*
Y122388D01*
X348792Y124368D01*
Y128287D01*
X349442Y128937D01*
X350543D01*
X351503Y127977D01*
Y127972D01*
G01X369670Y99845D02*
X364363Y94538D01*
Y82488D01*
X364371Y82480D01*
G01X362009D02*
Y88171D01*
X362129Y88291D01*
X362133D01*
Y90877D01*
G01X369095Y82480D02*
Y87209D01*
X369701Y87815D01*
Y89821D01*
X367776Y91746D01*
G01X357284Y82480D02*
Y89889D01*
X358343Y90948D01*
G01X354922Y82480D02*
Y87548D01*
X353713Y88757D01*
Y93057D01*
G01X361470Y101757D02*
X364051D01*
X372639Y110345D01*
Y114763D01*
G01X354943Y104191D02*
X360133D01*
X365552Y109610D01*
Y114763D01*
G01X356103D02*
Y109747D01*
X354448Y108092D01*
G01X365283Y128125D02*
X364214D01*
X358465Y122376D01*
Y114763D01*
G01X367350Y123927D02*
X366352D01*
X363190Y120765D01*
Y114763D01*
G01X378544Y82480D02*
Y90638D01*
X380480Y92574D01*
Y96264D01*
X380483Y96267D01*
Y99047D01*
G01X371457Y82480D02*
Y87209D01*
X370851Y87815D01*
Y89821D01*
X372776Y91746D01*
G01X384863Y95437D02*
Y92083D01*
X383263Y90483D01*
Y82485D01*
X383268Y82480D01*
G01X376723Y94178D02*
X376720D01*
X376180Y93638D01*
Y90496D01*
X376182D01*
Y82480D01*
G01X382087Y114763D02*
X382083D01*
Y103647D01*
X382087D01*
G01X379725Y114763D02*
Y106979D01*
X378733Y105987D01*
G01X375001Y114763D02*
Y109879D01*
X376100Y108780D01*
G01X391310Y99570D02*
X395079Y95801D01*
Y82480D01*
G01X391233Y96093D02*
Y95473D01*
X388773Y93013D01*
Y92459D01*
X385631Y89317D01*
Y82480D01*
G01X392717D02*
X392710Y82487D01*
Y92437D01*
X392500Y92647D01*
X392493D01*
G01X393898Y114763D02*
Y104782D01*
X399503Y99177D01*
X400163D01*
G01X396261Y114763D02*
Y107149D01*
X398753Y104657D01*
X399613D01*
G01X398088Y128455D02*
X396163Y126530D01*
Y124984D01*
X394006Y122827D01*
X390623D01*
X388568Y120772D01*
Y120098D01*
X389174Y119492D01*
Y114763D01*
G01X393088Y128455D02*
X395013Y126530D01*
Y125461D01*
X393529Y123977D01*
X390146D01*
X387418Y121249D01*
Y120098D01*
X386812Y119492D01*
Y114763D01*
G54D202*
G01X-41265Y641923D02*
X-42472D01*
G01X-36758Y133213D02*
X-34986D01*
G01X-36758Y746493D02*
Y734483D01*
X-39858Y731383D01*
G01X-34986Y746493D02*
Y734511D01*
X-31858Y731383D01*
G01X20650Y546243D02*
X20578D01*
X15317Y551504D01*
Y561223D01*
G01X20350Y555807D02*
X20659D01*
X22994Y558142D01*
Y561223D01*
G01X19450Y550297D02*
X17040Y554735D01*
Y557632D01*
X17876Y558468D01*
Y561223D01*
G01X26145Y547371D02*
Y547612D01*
X22405Y551352D01*
X22400D01*
X18650Y555102D01*
Y556825D01*
X20435Y558610D01*
Y561223D01*
G01D02*
Y564936D01*
X23610Y568111D01*
G01X15317Y584223D02*
Y575704D01*
X18960Y572061D01*
G01X17876Y584223D02*
Y578422D01*
G01X12758Y584223D02*
Y570361D01*
X16198Y566921D01*
X16200D01*
G01X20435Y584223D02*
Y577357D01*
X28153Y569639D01*
X45239D01*
X50870Y564008D01*
G01X13820Y597179D02*
X13950Y597049D01*
Y592379D01*
X13510Y591939D01*
G01X14500Y601957D02*
Y608210D01*
X15469Y609179D01*
X19930D01*
X21030Y610279D01*
Y618917D01*
X20507Y619440D01*
Y622914D01*
G01X13820Y597179D02*
X12520Y598479D01*
Y609528D01*
X12178Y609870D01*
Y612129D01*
G01X13820Y597179D02*
X17914Y601273D01*
X19870D01*
X21542Y602945D01*
X22935D01*
G01X17820Y605979D02*
X24982D01*
X25830Y605131D01*
Y601259D01*
X27833Y599256D01*
X50987D01*
X51676Y599945D01*
X68630D01*
G01X9820Y605979D02*
X9028Y606771D01*
Y612129D01*
G01D02*
Y616768D01*
X8871Y616925D01*
Y626154D01*
X11014Y628297D01*
X14550D01*
G01X11980Y617956D02*
X12830Y618806D01*
Y622914D01*
G01X15389D02*
X15349Y622874D01*
Y614142D01*
G01X17948Y622914D02*
Y626859D01*
X16510Y628297D01*
X14550D01*
G01X17948Y622914D02*
Y618188D01*
X18603Y617533D01*
Y614914D01*
G01X15389Y645914D02*
Y636406D01*
X13809Y634826D01*
X13807D01*
G01X12830Y645914D02*
Y637179D01*
X9300Y633649D01*
Y631472D01*
G01X9240Y638699D02*
X9241D01*
X10271Y639729D01*
Y645914D01*
G01X20507D02*
Y639927D01*
X30710Y629724D01*
X48340D01*
X50270Y627794D01*
Y627793D01*
G01X17948Y645914D02*
Y638867D01*
X29650Y627165D01*
X46328D01*
X48540Y624953D01*
G01X36900Y12883D02*
Y14359D01*
X37912Y15371D01*
X41422D01*
X42205Y14588D01*
G01X36900Y20757D02*
Y19153D01*
X38196Y17857D01*
X41474D01*
X42205Y18588D01*
G01X36567Y79540D02*
Y73145D01*
G01X34008Y102540D02*
Y91017D01*
G01X36567Y102540D02*
Y107988D01*
G01X31449Y102540D02*
Y97710D01*
X32260Y96899D01*
G01X36024Y199249D02*
X47183D01*
X50300Y202366D01*
Y205568D01*
X52208Y207476D01*
X60729D01*
G01X36024Y193241D02*
X53476D01*
X54000Y193765D01*
X59821D01*
G01X60182Y253099D02*
X41027Y236119D01*
X39314Y234406D01*
X36024Y217272D01*
G01X35790Y561223D02*
Y553100D01*
X36700Y552190D01*
Y540374D01*
X38610Y538464D01*
X39540D01*
G01X34140Y547324D02*
Y550956D01*
X33231Y551865D01*
Y556346D01*
G01X30140Y547324D02*
Y550713D01*
X30672Y551245D01*
G01X33231Y556346D02*
Y561223D01*
G01X30672D02*
Y551245D01*
G01X53988Y568748D02*
Y568749D01*
X51898Y570839D01*
X30572D01*
X22994Y578417D01*
Y584223D01*
G01X57710Y572918D02*
X50736D01*
X50330Y572512D01*
X32518D01*
X25553Y579477D01*
Y584223D01*
G01X35790D02*
Y580314D01*
X38590Y577514D01*
X47485D01*
X49680Y579709D01*
G01X33231Y584223D02*
Y579254D01*
X36551Y575934D01*
X50234D01*
X54374Y580074D01*
X57070D01*
G01X30672Y584223D02*
Y578194D01*
X34654Y574212D01*
X49620D01*
G01X28105Y595792D02*
X28112Y595785D01*
Y591718D01*
G01D02*
Y584223D01*
G01X33303Y622914D02*
Y615757D01*
X34840Y614220D01*
Y604299D01*
X38183Y600956D01*
X39370D01*
G01X28185Y622914D02*
Y612088D01*
G01X28270Y608415D02*
X28185Y608500D01*
Y612088D01*
G01X32270Y608415D02*
Y610513D01*
X30744Y612039D01*
Y617898D01*
G01Y622914D02*
Y617898D01*
G01X33303Y645914D02*
Y642977D01*
X35946Y640334D01*
X59223D01*
X62160Y643271D01*
Y644091D01*
G01X59390Y642906D02*
X58018Y641534D01*
X37241D01*
X35862Y642913D01*
Y645914D01*
G01X23066D02*
Y641582D01*
X32784Y631864D01*
X54457D01*
X56240Y630081D01*
G01X30744Y645914D02*
Y642821D01*
X37188Y636377D01*
X46921D01*
X48966Y634332D01*
X55463D01*
X58091Y631704D01*
X59530D01*
G01X28185Y645914D02*
Y642777D01*
X37403Y633559D01*
X46890D01*
Y633564D01*
G01X25625Y645914D02*
Y654293D01*
X24168Y655750D01*
G01X23170Y658951D02*
Y656748D01*
X24168Y655750D01*
G01X38421Y645914D02*
Y651327D01*
X37920Y651828D01*
G01X35960Y658951D02*
Y656712D01*
X37920Y654752D01*
Y651828D01*
G01X42205Y14588D02*
Y14586D01*
X43903Y12888D01*
X46882D01*
X51580Y17586D01*
Y17595D01*
G01X45355Y14588D02*
X51430Y20663D01*
X55946D01*
X56056Y20553D01*
X56610D01*
G01X42205Y21518D02*
Y18588D01*
G01X54800Y25547D02*
X54655D01*
X51731Y22623D01*
X49385D01*
X45355Y18593D01*
Y18588D01*
G01X41685Y79540D02*
Y73110D01*
G01X50981Y65593D02*
Y68822D01*
X51340Y69181D01*
G01X51922Y79540D02*
Y69763D01*
X51340Y69181D01*
G01X49363Y79540D02*
Y76684D01*
X46570Y73891D01*
G01X46981Y65593D02*
Y69160D01*
X46570Y69571D01*
Y73891D01*
G01X39126Y79540D02*
Y84631D01*
G01X51922Y102540D02*
Y108827D01*
X50103Y110646D01*
Y124704D01*
X58751Y133352D01*
X105861D01*
X115813Y143304D01*
Y153100D01*
X111220Y157693D01*
Y160923D01*
G01X41685Y102540D02*
Y123867D01*
X54399Y136581D01*
X105694D01*
X113413Y144300D01*
Y151113D01*
X107910Y156616D01*
Y174220D01*
X106760Y175370D01*
G01X39126Y102540D02*
Y123266D01*
X54006Y138146D01*
X105561D01*
X112213Y144798D01*
Y150613D01*
X106090Y156736D01*
Y167615D01*
G01X44244Y102540D02*
Y124176D01*
X55332Y135264D01*
X106075D01*
X114613Y143802D01*
Y151612D01*
X109520Y156705D01*
Y164770D01*
X114920Y170170D01*
Y179082D01*
G01X49363Y102540D02*
Y107568D01*
X47510Y109421D01*
G01X46803Y102540D02*
Y108714D01*
X47510Y109421D01*
G01X57040Y102540D02*
Y107820D01*
X52503Y112357D01*
Y123708D01*
X59555Y130760D01*
X106665D01*
X118213Y142308D01*
Y183891D01*
X108910Y193194D01*
G01X54481Y102540D02*
Y108320D01*
X51303Y111498D01*
Y124206D01*
X59178Y132081D01*
X106288D01*
X117013Y142806D01*
Y181880D01*
X112530Y186363D01*
G01X46811Y115664D02*
Y110120D01*
X47510Y109421D01*
G01X61022Y183862D02*
X56210D01*
X49835Y190237D01*
X41930D01*
G01Y184229D02*
X59920Y175826D01*
G01X60242Y212743D02*
X52420D01*
X41930Y202253D01*
G01Y208260D02*
X57125Y229308D01*
X60032Y231833D01*
G01X51337Y526060D02*
Y528574D01*
X50630Y529281D01*
G01X46140Y547324D02*
Y550848D01*
X43467Y553521D01*
Y555938D01*
G01X50140Y550572D02*
Y547324D01*
G01Y544174D02*
Y542497D01*
X46107Y538464D01*
X39540D01*
G01X43467Y561223D02*
Y555938D01*
G01X46026Y561223D02*
Y555216D01*
X50140Y551102D01*
Y550572D01*
G01X38349Y584223D02*
Y581374D01*
X39665Y580058D01*
X46935D01*
X50488Y583611D01*
X55444D01*
X57440Y585607D01*
G01X47657Y597285D02*
X47557Y597185D01*
Y588971D01*
G01X46026Y584223D02*
Y587440D01*
X47557Y588971D01*
G01X43467Y584223D02*
Y590026D01*
X44507Y591066D01*
Y594082D01*
G01D02*
Y597285D01*
G01X40347D02*
Y591885D01*
X40908Y591324D01*
Y589691D01*
G01D02*
Y584223D01*
G01X48270Y605265D02*
Y603149D01*
X46077Y600956D01*
X39370D01*
G01X44270Y608415D02*
Y611167D01*
X42950Y612487D01*
G01X48270Y608415D02*
Y616058D01*
X47480Y616848D01*
G01X40980Y622914D02*
Y617967D01*
X42950Y615997D01*
Y612487D01*
G01X43539Y622914D02*
Y620789D01*
X47480Y616848D01*
G01X43539Y645914D02*
Y649928D01*
X44640Y651029D01*
G01X43467Y658951D02*
Y652202D01*
X44640Y651029D01*
G01X40980Y645914D02*
Y656396D01*
G01X40317Y658951D02*
Y657166D01*
X40980Y656503D01*
Y656396D01*
G01X64717Y79540D02*
Y76834D01*
X69910Y71641D01*
Y57961D01*
X69140Y57191D01*
X57210D01*
X54981Y59420D01*
G01D02*
Y62443D01*
G01Y65593D02*
Y73372D01*
X54101Y74252D01*
G01X54481Y79540D02*
Y74632D01*
X54101Y74252D01*
G01X66981Y65593D02*
Y70050D01*
X64190Y72841D01*
G01X62158Y79540D02*
Y74873D01*
X64190Y72841D01*
G01X62158Y102540D02*
Y106923D01*
X61760Y107321D01*
G01X58654Y115158D02*
Y113287D01*
X61760Y110181D01*
Y107321D01*
G01X59599Y102540D02*
Y108152D01*
X55230Y112521D01*
G01X64717Y102540D02*
Y111264D01*
X63900Y112081D01*
G01X54703Y115946D02*
Y115176D01*
X54705Y115174D01*
Y113046D01*
X55230Y112521D01*
G01X61804Y115158D02*
Y114177D01*
X63900Y112081D01*
G01X67831Y145032D02*
X70842D01*
X72605Y143269D01*
X76880D01*
G01X59920Y175826D02*
X61202D01*
X64032Y172996D01*
X67785D01*
X70745Y170036D01*
G01X65440Y164548D02*
X71510D01*
G01X65696Y170071D02*
Y167949D01*
X65440Y167693D01*
Y164548D01*
G01X77944Y195733D02*
X77940Y195729D01*
Y187933D01*
X76426Y186419D01*
X61570D01*
X60663Y187326D01*
Y189182D01*
G01X77944Y181967D02*
X74466D01*
X72515Y183918D01*
X65169D01*
Y183921D01*
G01X61022Y183862D02*
X61081Y183921D01*
X65169D01*
G01X67853Y180744D02*
X71730D01*
G01X65169Y180771D02*
X67826D01*
X67853Y180744D01*
G01X70745Y173186D02*
Y173745D01*
X68901Y175589D01*
X68690D01*
G01X65696Y175871D02*
X68408D01*
X68690Y175589D01*
G01X59821Y193765D02*
Y192567D01*
X60660Y191728D01*
Y189182D01*
X60663D01*
G01X65821Y199565D02*
X66558D01*
X68930Y197193D01*
G01X71880Y195309D02*
X70814D01*
X68930Y197193D01*
G01X66570Y189983D02*
X65769Y189182D01*
X63813D01*
G01X69485Y188946D02*
X67607D01*
X66570Y189983D01*
G01X63813Y189182D02*
Y191142D01*
X65821Y193150D01*
Y193765D01*
G01X71778Y212026D02*
X70023Y210271D01*
X63229D01*
X60757Y212743D01*
X60242D01*
G01X81873Y209852D02*
X74928D01*
X72089Y207013D01*
X65486D01*
X64906Y207593D01*
Y207595D01*
G01X60729Y207476D02*
X60848Y207595D01*
X64906D01*
G01X66055Y223944D02*
Y221720D01*
X66242Y221533D01*
Y218543D01*
G01X64906Y204445D02*
X72557D01*
X73870Y205758D01*
G01X66242Y212743D02*
Y213229D01*
X68830Y215817D01*
G01D02*
X69471Y215176D01*
X71778D01*
G01X60032Y231833D02*
X60029Y231836D01*
Y235880D01*
G01D02*
X61913D01*
X63873Y233920D01*
X65684D01*
G01X75560Y218513D02*
Y225175D01*
X73822Y226913D01*
X67400D01*
X66055Y225568D01*
Y223944D01*
G01X77239Y260814D02*
X75958Y259533D01*
Y256083D01*
X74734Y254859D01*
X71095D01*
X65974Y249738D01*
Y247944D01*
G01X60182Y249949D02*
X60177Y246022D01*
G01X65974Y247944D02*
X63711D01*
X61789Y246022D01*
X60177D01*
G01X63718Y239030D02*
X71650Y240720D01*
X80348D01*
X84429Y238791D01*
X89496D01*
X93526Y236390D01*
X96652Y233892D01*
X101766Y228778D01*
X103950Y224532D01*
Y220734D01*
X103958Y220726D01*
Y218734D01*
G01X60029Y239030D02*
X63718D01*
G01X70796Y258779D02*
X61909D01*
X60179Y257049D01*
G01D02*
Y253102D01*
X60182Y253099D01*
G01X69339Y515836D02*
X70046D01*
X75314Y521104D01*
X76085D01*
G01X68489Y613914D02*
X63570D01*
G01X58108Y614907D02*
X62577D01*
X63570Y613914D01*
G01X68489Y618914D02*
X63610D01*
Y618917D01*
G01X58108Y619407D02*
X63120D01*
X63610Y618917D01*
G01X63650Y646957D02*
X60668D01*
X57639Y643928D01*
X56901D01*
G01X68489Y643914D02*
X65651D01*
X63650Y645915D01*
Y646957D01*
G01X56901Y648428D02*
Y648912D01*
X61600Y653611D01*
G01D02*
X66297Y648914D01*
X68489D01*
G01X66880Y761625D02*
Y767062D01*
X72000Y772182D01*
Y783574D01*
X66988Y788586D01*
Y807872D01*
G01X55177Y805904D02*
Y790990D01*
X56500Y789667D01*
G01X78740Y30708D02*
X79360Y31328D01*
Y39926D01*
G01X98800Y167685D02*
Y157768D01*
X95880Y154848D01*
X77334D01*
X76030Y156152D01*
G01X76210Y163577D02*
Y164571D01*
X70745Y170036D01*
G01X71730Y180744D02*
X72592D01*
X74680Y178656D01*
X81300D01*
X83660Y181016D01*
X97449D01*
G01X70745Y173186D02*
X71890D01*
X72360Y172716D01*
X73029D01*
X73140Y172605D01*
X74745D01*
G01X73870Y205758D02*
X81452D01*
X84277Y202933D01*
X92232D01*
X95107Y200058D01*
X103275D01*
X103958Y200741D01*
Y204167D01*
G01X71778Y212026D02*
X72613D01*
X81930Y221343D01*
Y223731D01*
X81933Y223734D01*
G01X71758Y218914D02*
Y215196D01*
X71778Y215176D01*
G01X98700Y234650D02*
Y234673D01*
X92436Y240937D01*
X86735D01*
X84362Y243310D01*
X80391D01*
Y243309D01*
G01X74774Y243944D02*
X79756D01*
X80391Y243309D01*
G01X77239Y260814D02*
Y262093D01*
X78917Y263771D01*
X79385D01*
X87215Y271601D01*
G01X81165Y257717D02*
X90955Y267507D01*
Y279475D01*
G01X80369Y253829D02*
Y256921D01*
X81165Y257717D01*
G01X74774Y251944D02*
X76542D01*
X78427Y253829D01*
X80369D01*
G01X95951Y404368D02*
Y400267D01*
X85305Y389621D01*
X83084D01*
G01X80074Y385722D02*
Y389621D01*
G01D02*
X83084D01*
G01X80094Y393857D02*
Y397913D01*
G01X90951Y404368D02*
Y399520D01*
X89340Y397909D01*
X83245D01*
Y397913D01*
G01X80094D02*
X83245D01*
G01X84103Y506011D02*
X87527D01*
X87721Y505817D01*
G01X82031Y523928D02*
X76574D01*
X76085Y523439D01*
Y521104D01*
G01X95060Y159811D02*
Y175698D01*
X97449Y178087D01*
Y181016D01*
G01X98800Y167685D02*
Y173809D01*
X100190Y175199D01*
X102257D01*
G01D02*
Y183020D01*
X99453Y185824D01*
X97441D01*
X93449Y189816D01*
G01X98840Y204167D02*
Y212844D01*
X101399Y215403D01*
Y218734D01*
G01D02*
Y222969D01*
X101020Y223348D01*
G01D02*
X99318Y225050D01*
Y225836D01*
G01X95968Y374257D02*
Y376644D01*
X95951Y376661D01*
G01X90951Y383568D02*
Y387601D01*
X92520Y389170D01*
X103052D01*
X109390Y382832D01*
X123340D01*
X125050Y384542D01*
Y384546D01*
G01X85951Y383568D02*
Y387508D01*
X89518Y391075D01*
X103157D01*
X103162Y391070D01*
X103840D01*
X110178Y384732D01*
X120122D01*
X122120Y386730D01*
Y386736D01*
G01X95951Y383568D02*
Y376661D01*
G01X100951Y404368D02*
Y398658D01*
X105586Y394023D01*
X107531D01*
G01X87721Y505817D02*
X87952Y506048D01*
X91458D01*
G01X98590Y782494D02*
X100290Y784194D01*
Y788177D01*
X98484Y789983D01*
Y807872D01*
G01X101449Y189816D02*
Y194368D01*
G01X101399Y204167D02*
Y208687D01*
X108517Y215805D01*
Y230106D01*
X114650Y236239D01*
Y256002D01*
X104990Y265662D01*
X104270D01*
G01X106517Y218734D02*
Y231241D01*
X112490Y237214D01*
Y254646D01*
X104777Y262359D01*
X104550D01*
G01X110624Y387978D02*
Y392023D01*
G01X317140Y421775D02*
X315376Y420011D01*
X311161D01*
X304170Y413020D01*
X165362D01*
X144645Y392303D01*
X121090D01*
X117670Y395723D01*
X116250D01*
X116189Y395662D01*
X109785D01*
X105837Y399610D01*
Y402572D01*
X106656Y403391D01*
X106661D01*
X109390Y406120D01*
Y406383D01*
X109393D01*
G01D02*
X109342Y406434D01*
Y410349D01*
G01X110624Y392023D02*
X109531D01*
X107531Y394023D01*
G01X119039Y410295D02*
X114392D01*
X114338Y410349D01*
X109342D01*
G01X108026Y492500D02*
Y486861D01*
G01X116698Y493127D02*
X115072D01*
X112072Y490127D01*
Y486908D01*
G01X108026Y486861D02*
X112025D01*
X112072Y486908D01*
G01X109972Y509321D02*
Y512558D01*
G01D02*
X114372D01*
G01X116698Y505333D02*
Y506885D01*
X114372Y509211D01*
Y512558D01*
G01X106650Y779581D02*
Y782044D01*
X104350Y784344D01*
Y787952D01*
X106358Y789960D01*
Y807872D01*
G01X110295D02*
Y785734D01*
G01X118169Y807872D02*
Y787740D01*
X116370Y785941D01*
G01X102421Y807872D02*
Y785938D01*
G01X125050Y384546D02*
X130661D01*
X135940Y379267D01*
X144355D01*
X144443Y379355D01*
X150543D01*
X150902Y379714D01*
G01X122120Y386736D02*
X143031D01*
X144549Y388254D01*
X165762D01*
X167330Y386686D01*
Y384536D01*
X171139Y380727D01*
X175155D01*
G01X126300Y390369D02*
X126659Y390728D01*
X145070D01*
X166250Y411908D01*
X306303D01*
X310120Y415725D01*
X316725D01*
X319514Y412936D01*
X323977D01*
X324940Y413899D01*
G01X131245Y410295D02*
X133982D01*
X134742Y411055D01*
Y414666D01*
X132164Y417244D01*
Y418152D01*
G01D02*
Y422306D01*
X132178Y422320D01*
G01D02*
Y423337D01*
X132808Y423967D01*
X138272D01*
X139395Y425090D01*
G01X124467Y670879D02*
X121440D01*
X121070Y670509D01*
G01X127617Y670879D02*
X131112D01*
X132050Y671817D01*
G01X127617Y670879D02*
Y669764D01*
X126343Y668490D01*
X125630D01*
X124103Y666963D01*
Y665638D01*
G01X133447Y675464D02*
Y673214D01*
X132050Y671817D01*
G01X128501Y699863D02*
Y697368D01*
X125100Y693967D01*
Y684870D01*
X125105D01*
X127740Y682235D01*
X127861D01*
X130260Y679836D01*
G01X130470Y699863D02*
Y696113D01*
X130468D01*
X127007Y692652D01*
Y685658D01*
X128530Y684135D01*
X130357D01*
X135280Y679212D01*
G01X127617Y675871D02*
X133040D01*
X133447Y675464D01*
G01X129607Y692362D02*
X133607D01*
G01X125960Y785699D02*
X126063Y785802D01*
Y807852D01*
X126043Y807872D01*
G01X120090Y780618D02*
X120710Y781238D01*
Y786029D01*
X122106Y787425D01*
Y807872D01*
G01X130850Y782456D02*
X128440Y784866D01*
Y786754D01*
X129980Y788294D01*
Y807872D01*
G01X144203Y15162D02*
Y16554D01*
X141490Y19267D01*
G01X146380Y27366D02*
Y29320D01*
X147427Y30367D01*
G01D02*
Y31070D01*
X148357Y32000D01*
Y34404D01*
G01X180218Y245238D02*
Y245288D01*
X180018Y245488D01*
Y247197D01*
X181477Y248656D01*
X182612D01*
G01X179018Y245238D02*
Y245338D01*
X179218D01*
Y247529D01*
X180711Y249022D01*
Y249724D01*
X180229Y250206D01*
G01X169684Y269723D02*
X169023D01*
X167441Y271305D01*
X160057D01*
X158337Y273025D01*
X148640D01*
X145200Y276465D01*
Y276468D01*
G01X166778Y269599D02*
X160067D01*
X157813Y271853D01*
X146042D01*
X138930Y278965D01*
G01X146093Y284987D02*
X149203D01*
X152733Y288517D01*
G01X146093Y288987D02*
X149879D01*
X151527Y290635D01*
X158076D01*
G01X142007Y310543D02*
X143217D01*
X144010Y311336D01*
X145720D01*
G01D02*
X146290Y311906D01*
X156555D01*
X159758Y308703D01*
X166771D01*
G01X166332Y318583D02*
X163904D01*
X163620Y318867D01*
X158293D01*
X157563Y319597D01*
X155870D01*
X151924Y323543D01*
X146100D01*
G01X142007D02*
X146100D01*
G01X166122Y312753D02*
X159827D01*
X158037Y314543D01*
X147873D01*
X145580Y316836D01*
G01X142007Y314543D02*
X143287D01*
X145580Y316836D01*
G01X142388Y327933D02*
X148999D01*
X151230Y330164D01*
G01X142007Y319043D02*
X150009D01*
X150918Y318134D01*
G01X142531Y332046D02*
X146250D01*
X150510Y336306D01*
G01X141510Y411428D02*
Y421617D01*
X142239Y422346D01*
G01X132851Y470738D02*
X134468D01*
X136290Y472560D01*
X145791D01*
X146240Y472111D01*
G01D02*
Y468280D01*
G01X132851Y466738D02*
X133594D01*
X135300Y468444D01*
G01X132851Y462738D02*
Y458733D01*
G01Y466738D02*
Y462738D01*
G01X135300Y468444D02*
X135464Y468280D01*
X138760D01*
G01X137759Y684325D02*
Y685326D01*
X139158Y686725D01*
G01X137759Y689175D02*
Y688124D01*
X139158Y686725D01*
G01X134406Y699863D02*
Y696386D01*
X133490Y695470D01*
G01X133607Y692362D02*
X134267Y693022D01*
Y694693D01*
X133490Y695470D01*
G01X137759Y692325D02*
Y693876D01*
X138726Y694843D01*
Y696707D01*
G01X136375Y699863D02*
Y697321D01*
X136989Y696707D01*
X138726D01*
G01X139600Y781281D02*
X137850Y783031D01*
Y785477D01*
X137854D01*
Y807872D01*
G01X135470Y781697D02*
X133420Y783747D01*
Y786131D01*
X133917Y786628D01*
Y807872D01*
G01X149450Y780429D02*
X148090Y781789D01*
Y787760D01*
X149665Y789335D01*
Y807872D01*
G01X145728D02*
Y789071D01*
X144000Y787343D01*
Y782150D01*
X145570Y780580D01*
G01X153937Y12151D02*
X155982Y14196D01*
Y15891D01*
X157691Y17600D01*
X158181D01*
G01X158165Y24372D02*
Y21300D01*
G01X158181Y17600D02*
Y21284D01*
X158165Y21300D01*
G01X170670Y82480D02*
Y78340D01*
X167193Y74863D01*
X156440D01*
G01D02*
X152553D01*
G01X175572Y252980D02*
Y252966D01*
X174203Y251597D01*
X159369D01*
X157690Y249918D01*
G01X164375Y262559D02*
X163837Y263097D01*
X158100D01*
X153809Y258806D01*
X148330D01*
G01X168095Y262759D02*
X167377D01*
X165820Y261202D01*
X163171D01*
X162747Y261626D01*
X159186D01*
X154546Y256986D01*
G01X169684Y273223D02*
X168891D01*
X167576Y274538D01*
X166104D01*
X164757Y273191D01*
X162114D01*
X158496Y276809D01*
X152634D01*
G01X166771Y273247D02*
X166684D01*
X165556Y272119D01*
X161464D01*
X158837Y274746D01*
X152289D01*
X148350Y278685D01*
Y281769D01*
G01X152733Y288517D02*
X152756Y288540D01*
X159987D01*
X160330Y288883D01*
X163492D01*
X165048Y287327D01*
X166778D01*
G01X158076Y290635D02*
X158099Y290658D01*
G01D02*
Y294868D01*
X165409Y302178D01*
X167127D01*
X167815Y301490D01*
Y298495D01*
X168095Y298215D01*
G01X166771Y290975D02*
X165807Y290011D01*
X158746D01*
X158099Y290658D01*
G01X164375Y315743D02*
X162743D01*
X162370Y315370D01*
X158625D01*
X158452Y315543D01*
X155233D01*
X152642Y318134D01*
X150918D01*
G01X170272Y330795D02*
X168431D01*
X166808Y329172D01*
X165597D01*
X164605Y330164D01*
X151230D01*
G01X166122Y330481D02*
X165180Y331423D01*
X156866D01*
X151983Y336306D01*
X150510D01*
G01X164920Y340441D02*
X160260D01*
X156448Y336629D01*
G01X164920Y337241D02*
X162365D01*
X162071Y336947D01*
G01X190500Y389487D02*
X189261D01*
X188078Y388304D01*
X185795D01*
X176085Y378594D01*
X152022D01*
X150902Y379714D01*
G01X162940Y406188D02*
X167409Y410657D01*
X284003D01*
X295388Y399272D01*
Y375644D01*
G01X160760Y507731D02*
Y490498D01*
X163570Y487688D01*
X166646D01*
G01X160760Y510881D02*
X162209Y510067D01*
X163562Y509306D01*
X164843D01*
X166993Y507156D01*
Y507131D01*
X169903Y502594D01*
Y502551D01*
X175032Y497422D01*
X191778D01*
X196718Y502362D01*
X199845Y503533D01*
X201291Y504075D01*
X208209D01*
G01X163910Y514030D02*
X162266Y517070D01*
Y517694D01*
X161260Y518700D01*
X160362D01*
X159873Y519189D01*
X159869Y519204D01*
X159390Y519683D01*
X159179Y521893D01*
G01X160760Y514030D02*
X160761D01*
X162335Y512456D01*
G01X160760Y517180D02*
Y517176D01*
X159196Y515612D01*
G01X163910Y510881D02*
X163913Y510884D01*
X164779D01*
X165906Y509757D01*
X169057D01*
X169470Y509344D01*
Y506193D01*
X176574Y499089D01*
X191100D01*
X198465Y506454D01*
X199565D01*
G01X163910Y517180D02*
Y516502D01*
X165728Y514684D01*
Y512152D01*
X166478Y511402D01*
X169005D01*
X170318Y512715D01*
Y516186D01*
X172105Y517973D01*
Y519517D01*
X172371Y519783D01*
G01X163910Y507731D02*
X165707Y506156D01*
G01X160760Y520329D02*
X162304Y519417D01*
X163467Y518876D01*
X164376Y518744D01*
X166334Y517186D01*
X166738Y515973D01*
X168189Y514331D01*
G01X157611Y523479D02*
X155058D01*
X154126Y524411D01*
G01X160760Y523479D02*
X160762D01*
X162335Y521906D01*
G01X157611Y529778D02*
X155119D01*
X154475Y530422D01*
G01X157611Y526629D02*
X159180Y528198D01*
Y528227D01*
G01X163910Y532928D02*
X165785D01*
X166297Y532416D01*
G01X163910Y529778D02*
X166107D01*
X167963Y531634D01*
Y534236D01*
X168872Y535145D01*
X170159D01*
X171068Y534236D01*
Y531279D01*
X169491Y529702D01*
G01X163910Y526629D02*
Y526963D01*
X165010Y528063D01*
X168798D01*
X171142Y525719D01*
Y524085D01*
X170402Y523345D01*
X169357D01*
X168617Y524085D01*
Y525756D01*
G01X163910Y523479D02*
X163426D01*
X162992Y523913D01*
Y524755D01*
X163431Y525194D01*
X164502D01*
X165745Y526437D01*
X166520D01*
X166837Y526120D01*
Y523486D01*
G01X163910Y520329D02*
X168502D01*
X169615Y519216D01*
G01X160760Y539227D02*
Y539234D01*
X162382Y540856D01*
X164877D01*
X166727Y542706D01*
X168243D01*
G01X163910Y542377D02*
X163886D01*
X162335Y543928D01*
Y543954D01*
G01X160760Y536077D02*
Y536078D01*
X159182Y537656D01*
X159183D01*
X159185Y537654D01*
G01X163910Y548676D02*
X167105Y552882D01*
G01X160760Y548676D02*
X162336Y550252D01*
Y550253D01*
G01X163910Y545526D02*
X168413Y551028D01*
X172889Y562710D01*
G01X160760Y554975D02*
X164259Y557273D01*
G01X163910Y554975D02*
X169444Y558757D01*
G01X158430Y575710D02*
Y576565D01*
X161280Y579415D01*
Y581585D01*
G01X166570Y583874D02*
X164070Y581374D01*
Y579075D01*
X162663Y577668D01*
Y575608D01*
G01X162668Y592020D02*
Y587173D01*
X158810Y583315D01*
X156480D01*
G01X164636Y592020D02*
Y586177D01*
X161280Y582821D01*
Y581585D01*
G01X157550Y605012D02*
X152507D01*
X150380Y602885D01*
G01X160699Y627846D02*
X159459D01*
X157963Y629342D01*
Y633735D01*
G01Y636958D02*
Y633735D01*
G01X166605Y627846D02*
Y630160D01*
X165830Y630935D01*
Y639935D01*
X162530Y643235D01*
G01X164636Y627846D02*
Y634329D01*
X162530Y636435D01*
G01X163195Y653433D02*
X169538Y647090D01*
Y643933D01*
G01X155170Y780656D02*
Y785192D01*
X157539Y787561D01*
Y807872D01*
G01X153602D02*
Y783781D01*
X153320Y783499D01*
G01X160320Y786346D02*
Y786594D01*
X161476Y787749D01*
Y807872D01*
G01X178040Y228978D02*
X178834D01*
X182343Y232487D01*
X185203D01*
X186518Y233802D01*
Y235992D01*
X187240Y236714D01*
Y243945D01*
X188987Y245692D01*
Y246744D01*
X190460Y248217D01*
G01X175572Y249980D02*
X177235D01*
X177891Y249324D01*
G01X180312Y260229D02*
Y260861D01*
X178929Y262244D01*
G01X177312Y260229D02*
X175293D01*
X175110Y260412D01*
G01X180312Y273113D02*
X180245D01*
X178818Y274540D01*
G01X168095Y280487D02*
X170102Y282494D01*
Y282919D01*
G01X166122Y277297D02*
Y278514D01*
X168095Y280487D01*
G01X169684Y290951D02*
Y291585D01*
X171682Y293583D01*
Y297428D01*
X171095Y298015D01*
G01X169684Y287451D02*
X166771Y290364D01*
Y290975D01*
G01X170102Y282919D02*
X170643Y283460D01*
Y286492D01*
X169684Y287451D01*
G01Y305179D02*
Y308679D01*
G01X172426Y305541D02*
X171267D01*
X170905Y305179D01*
X169684D01*
G01Y308679D02*
X170947D01*
X172010Y309742D01*
X173710D01*
X174410Y310442D01*
Y311542D01*
X173510Y312442D01*
X172510D01*
X171510Y313442D01*
Y315328D01*
X171095Y315743D01*
G01X166778Y305055D02*
X167788D01*
X168932Y303911D01*
X170336D01*
X170532Y304107D01*
X172995D01*
X173772Y304884D01*
Y306025D01*
X172426Y307371D01*
Y308297D01*
G01D02*
X174070D01*
X174694Y307673D01*
X175954D01*
X176500Y308219D01*
X176731D01*
X177687Y309175D01*
Y310529D01*
X177467Y310749D01*
Y315562D01*
X176467Y316562D01*
X174174D01*
X172982Y317754D01*
G01X166771Y308703D02*
X166778Y308696D01*
Y305055D01*
G01X170102Y300647D02*
X172361D01*
X172982Y300026D01*
G01X168095Y298215D02*
X168827D01*
X170102Y299490D01*
Y300647D01*
G01X166778Y326424D02*
X166771Y326431D01*
G01X172426Y323269D02*
X170753Y324942D01*
X168260D01*
X167116Y326085D01*
X166778Y326424D01*
G01D02*
Y322783D01*
G01D02*
X166051Y322056D01*
Y319542D01*
X166332Y319261D01*
Y318583D01*
G01X171095Y315743D02*
X171066D01*
X169641Y317168D01*
X167747D01*
X166332Y318583D01*
G01X172426Y326025D02*
X172044Y326407D01*
X169684D01*
G01Y322907D02*
X170701D01*
X171719Y321889D01*
X173337D01*
X174367Y322919D01*
Y324542D01*
X172884Y326025D01*
X172426D01*
G01X170102Y318375D02*
X168521D01*
X167027Y319869D01*
Y320957D01*
X168112Y322042D01*
X168819D01*
X169684Y322907D01*
G01X172982Y317754D02*
X172361Y318375D01*
X170102D01*
G01X179579Y336149D02*
X177754D01*
X175076Y333471D01*
X171095D01*
G01X182335Y333149D02*
X180803D01*
X179579Y334373D01*
Y336149D01*
G01X172914Y338267D02*
X174397Y339750D01*
X176697D01*
X179579Y336868D01*
Y336149D01*
G01X171095Y333471D02*
Y331618D01*
X170272Y330795D01*
G01X172426Y340997D02*
X173545D01*
X173888Y340654D01*
X178074D01*
X179579Y339149D01*
G01X172426Y340997D02*
Y340318D01*
X168919Y336811D01*
Y334495D01*
X168095Y333671D01*
G01X181922Y345277D02*
X180117Y343472D01*
X178091D01*
X177983Y343364D01*
X176883D01*
X176775Y343472D01*
X176238D01*
X175307Y342541D01*
X173970D01*
X172426Y340997D01*
G01X179579Y339149D02*
Y338905D01*
X182335Y336149D01*
G01X168095Y333671D02*
Y332454D01*
X166122Y330481D01*
G01X190500Y392046D02*
X189083D01*
X187382Y390345D01*
X185145D01*
X175527Y380727D01*
X175155D01*
G01X179361Y401571D02*
X183361D01*
G01X172760Y406540D02*
X175877Y409657D01*
X283588D01*
X289920Y403325D01*
Y388925D01*
X288925Y387930D01*
X285931D01*
X285392Y388469D01*
X279021D01*
X276732Y390758D01*
X275497D01*
G01X173892Y487664D02*
X169728D01*
G01X166646Y487688D02*
X169704D01*
X169728Y487664D01*
G01X176508Y507731D02*
Y508840D01*
X175229Y510119D01*
X173950D01*
X172739Y508908D01*
X171690D01*
X171144Y508362D01*
Y507418D01*
X172931Y505631D01*
X173487D01*
X174031Y506175D01*
X175771D01*
X176423Y505523D01*
Y502100D01*
X177800Y500723D01*
X190066D01*
X198056Y508713D01*
X205247D01*
G01X179658Y510881D02*
X181297Y509242D01*
Y507165D01*
X182686Y505776D01*
X187517D01*
X189609Y507868D01*
Y512775D01*
X191719Y514885D01*
Y517440D01*
X194022Y519743D01*
X199050D01*
X199480Y520173D01*
Y522198D01*
X200408Y523126D01*
X201625D01*
X202249Y522502D01*
Y520972D01*
X202754Y520467D01*
X204778D01*
X205195Y520884D01*
Y522335D01*
G01X179658Y514030D02*
Y514028D01*
X181231Y512455D01*
G01X179658Y517180D02*
Y517178D01*
X181229Y515607D01*
X181232D01*
G01X176508Y514030D02*
Y514028D01*
X178080Y512456D01*
X178085D01*
G01X179658Y507731D02*
Y506199D01*
X181814Y504043D01*
X188615D01*
X192288Y507710D01*
Y509331D01*
X192289Y509896D01*
X191628Y510558D01*
Y511939D01*
X192236Y512547D01*
X193033D01*
Y512546D01*
X193988Y511591D01*
X194552D01*
X195904Y512942D01*
X199280D01*
X199983Y513645D01*
Y514927D01*
X199568Y515342D01*
X196909D01*
G01X176508Y510881D02*
X177756D01*
X178241Y510396D01*
Y508317D01*
X178042Y508118D01*
Y503422D01*
X179141Y502323D01*
X189266D01*
X194385Y507442D01*
Y509139D01*
X194850Y509604D01*
X195400D01*
X196549Y510753D01*
X199908D01*
X200558Y511403D01*
X201181D01*
X201831Y510753D01*
X203209D01*
X203759Y511303D01*
Y512381D01*
X202009Y514131D01*
Y515238D01*
X202513Y515742D01*
X203920D01*
X205294Y514368D01*
G01X176508Y523479D02*
X175376Y522347D01*
X173252Y517200D01*
Y515693D01*
G01X176508Y517180D02*
X176506D01*
X175560Y516234D01*
X172087Y510536D01*
G01X179658Y532928D02*
X181113Y534383D01*
X184455D01*
X184843Y533995D01*
G01X176508Y520329D02*
X176511D01*
X178148Y521966D01*
X186696D01*
X186909Y521753D01*
X196058D01*
X198809Y524504D01*
Y534262D01*
X197709Y535362D01*
Y567464D01*
G01X176508Y532928D02*
X176531D01*
X178094Y531365D01*
G01X176508Y539227D02*
X174105Y541630D01*
Y542290D01*
G01X179658Y548676D02*
X180123D01*
X181704Y547095D01*
X184253D01*
X185976Y545372D01*
X186841D01*
G01X176508Y545526D02*
Y545530D01*
X174932Y547106D01*
X174930D01*
G01X179658Y539227D02*
X179661D01*
X181232Y537656D01*
Y537654D01*
G01X176508Y542377D02*
Y542380D01*
X170212Y548676D01*
X169157D01*
G01X176508Y554975D02*
X175829D01*
X173163Y552309D01*
Y551903D01*
G01X179658Y551825D02*
Y551832D01*
X181232Y553406D01*
Y553402D01*
G01X170930Y575710D02*
Y580735D01*
X172430Y582235D01*
Y584035D01*
G01X179263Y575708D02*
Y582102D01*
X177830Y583535D01*
G01X174479Y592020D02*
Y579386D01*
X175330Y578535D01*
G01X175263Y575708D02*
Y578468D01*
X175330Y578535D01*
G01X170542Y592020D02*
Y583547D01*
X166930Y579935D01*
Y578435D01*
G01X166663Y575608D02*
Y578168D01*
X166930Y578435D01*
G01X172510Y592020D02*
Y584115D01*
X172430Y584035D01*
G01X176447Y592020D02*
Y584918D01*
X177830Y583535D01*
G01X168573Y592020D02*
Y585877D01*
X166570Y583874D01*
G01X178416Y627846D02*
Y633309D01*
X184794Y639687D01*
X184748D01*
G01X176447Y627846D02*
Y636942D01*
X179120Y639615D01*
G01X170542Y627846D02*
Y631803D01*
X169930Y632415D01*
Y635329D01*
G01X172510Y639771D02*
Y627846D01*
G01X187410Y643700D02*
X183205D01*
X179120Y639615D01*
G01X169930Y635329D02*
Y643541D01*
X169538Y643933D01*
G01X172510Y639771D02*
Y642555D01*
X173888Y643933D01*
G01X179731Y653433D02*
X173888Y647590D01*
Y643933D01*
G01X179419Y667816D02*
Y670618D01*
X171180Y678857D01*
Y679529D01*
G01X164812Y669524D02*
X166417D01*
X167810Y668131D01*
G01X170619Y671816D02*
Y670940D01*
X167810Y668131D01*
G01X171180Y683815D02*
Y679529D01*
G01X179689Y724473D02*
Y719045D01*
X180820Y717914D01*
G01X172455Y732775D02*
X174674D01*
X176928Y730521D01*
G01D02*
Y729445D01*
X179689Y726684D01*
Y724473D01*
G01X185440Y742231D02*
Y759231D01*
X177224Y767447D01*
Y777765D01*
G01Y807872D02*
Y777765D01*
G01X169350Y807872D02*
Y785470D01*
G01X169860Y782086D02*
X165413Y786533D01*
Y807872D01*
G01X205903Y101477D02*
Y101476D01*
X204913Y100486D01*
X196715D01*
X193111Y104090D01*
Y114763D01*
G01X190749D02*
Y107393D01*
X188203Y104847D01*
Y104567D01*
G01X200364Y251569D02*
X200979D01*
X202538Y250010D01*
Y243963D01*
X202530Y243955D01*
Y239636D01*
G01X190668Y251987D02*
X191849D01*
X192378Y251458D01*
X193623D01*
X195126Y249955D01*
G01X183550Y235060D02*
X183551D01*
X183981Y235490D01*
Y237157D01*
X185896Y239072D01*
Y244520D01*
X187636Y246260D01*
G01X188543Y250223D02*
Y248541D01*
X187638Y247636D01*
X187058D01*
X184296Y244874D01*
Y241098D01*
G01X195976Y252157D02*
X196737Y251396D01*
Y249523D01*
X197760Y248500D01*
Y247714D01*
X195343Y245297D01*
Y240727D01*
X198685Y237385D01*
G01X191099Y259197D02*
Y259082D01*
X189313Y257296D01*
X189307D01*
X188881Y256870D01*
X188658D01*
G01X188343Y265197D02*
Y265167D01*
X186873Y263697D01*
G01X188343Y259197D02*
X187729D01*
X185798Y257266D01*
Y256760D01*
G01X188343Y262197D02*
Y262167D01*
X186873Y260697D01*
G01X183312Y273113D02*
X183245D01*
X181818Y274540D01*
G01X196163Y269697D02*
X195542D01*
X194205Y271034D01*
G01X196163Y266697D02*
X195560D01*
X193855Y268402D01*
X193606D01*
X191860Y270148D01*
G01X187812Y312213D02*
X187804D01*
X186254Y310663D01*
G01X184812Y312213D02*
X184804D01*
X183254Y310663D01*
G01X187812Y314969D02*
Y315654D01*
X186350Y317116D01*
G01X184812Y314969D02*
Y315439D01*
X183228Y317023D01*
G01X193812Y314969D02*
Y316919D01*
X193957Y317064D01*
G01X197975Y321149D02*
Y319903D01*
X196805Y318733D01*
X192721D01*
X191159Y317171D01*
G01X182284Y342535D02*
X185040D01*
G01X181798Y348183D02*
X183410Y346571D01*
Y344780D01*
X182284Y343654D01*
Y342535D01*
G01D02*
Y341965D01*
X184132Y340117D01*
X184592D01*
X186016Y338693D01*
Y336830D01*
X182335Y333149D01*
G01X185040Y342535D02*
X185058D01*
X187190Y340403D01*
X190212D01*
X191523Y339092D01*
X192998D01*
X194355Y340449D01*
X197926D01*
X200012Y342535D01*
G01X199526Y348183D02*
X198498Y349211D01*
X197652D01*
X196934Y349929D01*
X193702D01*
X192984Y349211D01*
X192563D01*
X191210Y347858D01*
Y344908D01*
X192252Y343866D01*
X192486D01*
G01D02*
X193479Y344859D01*
X195118D01*
G01X195326Y348629D02*
X195913Y348042D01*
X197710D01*
X199650Y346102D01*
Y345277D01*
G01X192686Y346866D02*
X194449Y348629D01*
X195326D01*
G01X185446Y348190D02*
X183977Y349659D01*
X181396D01*
X180477Y348740D01*
Y347647D01*
X181922Y346202D01*
Y345277D01*
G01X185446Y348190D02*
Y351959D01*
X185225Y352180D01*
Y356966D01*
X186325Y358066D01*
X198721D01*
X200587Y356200D01*
Y350777D01*
X203174Y348190D01*
G01X185446D02*
X185422Y348166D01*
Y345277D01*
G01X198708Y386396D02*
Y381529D01*
X195420Y378241D01*
Y372406D01*
G01X196149Y386396D02*
Y381362D01*
X192681Y377894D01*
Y377554D01*
G01X193590Y386396D02*
Y383383D01*
G01X183361Y404721D02*
X187297Y408657D01*
X283173D01*
X288767Y403063D01*
Y393927D01*
X285390Y390550D01*
G01X183361Y401571D02*
X186577D01*
X190188Y405182D01*
X194243D01*
X196273Y403152D01*
G01X181470Y485105D02*
X188809D01*
X193500Y489796D01*
G01X225755Y516770D02*
X223444D01*
X219387Y512713D01*
X210686D01*
X204932Y518467D01*
X203323D01*
X202598Y517742D01*
X194804D01*
X193738Y516676D01*
Y515763D01*
X194159Y515342D01*
X196909D01*
G01X182807Y523479D02*
X182981Y523653D01*
X186426D01*
X187226Y522853D01*
X195415D01*
X196709Y524147D01*
Y543643D01*
X193466Y546886D01*
G01X182807Y529778D02*
X184033D01*
X184433Y530178D01*
X188151D01*
X188640Y530667D01*
G01X182807Y526629D02*
X184430D01*
X184875Y527074D01*
Y527925D01*
X185491Y528541D01*
X186500D01*
X187321Y527720D01*
Y525741D01*
X188209Y524853D01*
X189700D01*
X190300Y525453D01*
Y528353D01*
X190700Y528753D01*
X192300D01*
X192700Y528353D01*
Y525262D01*
X193109Y524853D01*
X194509D01*
X195100Y525444D01*
Y532262D01*
X193909Y533453D01*
X192009D01*
X191457Y532901D01*
Y531553D01*
G01X186290Y592020D02*
Y585251D01*
X194656Y576885D01*
X201510D01*
G01X184321Y592020D02*
Y588944D01*
X184320D01*
Y582268D01*
X193695Y572893D01*
X197730D01*
G01X182353Y592020D02*
Y589034D01*
X183120Y588267D01*
Y581594D01*
X191500Y573214D01*
Y571956D01*
G01X193376Y595169D02*
Y590678D01*
X194319Y589735D01*
X196740D01*
G01X188258Y592020D02*
Y586055D01*
X188448Y585865D01*
X188450D01*
X193080Y581235D01*
G01X204028Y580893D02*
X201922D01*
X201580Y581235D01*
X193080D01*
G01X190227Y592020D02*
Y589318D01*
X195440Y584105D01*
X198890D01*
G01X193376Y622728D02*
X196423D01*
X200380Y626685D01*
Y629085D01*
G01X186290Y627846D02*
Y631895D01*
X191200Y636805D01*
X194470D01*
X197480Y639815D01*
G01X190227Y627846D02*
Y630332D01*
X192130Y632235D01*
G01X188258Y627846D02*
Y631563D01*
X191560Y634865D01*
X199230D01*
X203065Y638700D01*
G01X193376Y616823D02*
X196018D01*
X198088Y618893D01*
X199786D01*
G01X193376Y618791D02*
X195589D01*
X200803Y624005D01*
X202510D01*
G01X180384Y627846D02*
Y632489D01*
X182480Y634585D01*
G01X184321Y627846D02*
Y632426D01*
X191030Y639135D01*
X191480D01*
G01X193376Y620760D02*
X196055D01*
X202080Y626785D01*
Y627745D01*
X205221Y630886D01*
G01X192130Y632235D02*
X198951D01*
X202706Y635990D01*
X204680D01*
X206667Y637977D01*
X209299D01*
G01X187410Y653700D02*
X188815D01*
X189760Y652755D01*
Y642485D01*
X187008Y639733D01*
X184794D01*
X184748Y639687D01*
G01X191910Y643700D02*
Y642315D01*
X186430Y636835D01*
X184730D01*
X182480Y634585D01*
G01X191480Y639135D02*
X191850D01*
X196410Y643695D01*
Y643700D01*
G01D02*
Y643925D01*
X194360Y645975D01*
Y651650D01*
X196410Y653700D01*
G01X185993Y678356D02*
Y682670D01*
G01X189733Y688002D02*
Y690116D01*
X191542Y691925D01*
G01D02*
X191440Y692027D01*
Y694284D01*
X192746Y695590D01*
Y701361D01*
X191440Y702667D01*
Y708356D01*
G01X190375Y695624D02*
X188535Y693784D01*
X187565D01*
X187462Y693887D01*
G01X187440Y699556D02*
X187462Y699534D01*
Y693887D01*
G01X189940Y727581D02*
Y725877D01*
X188566Y724503D01*
Y722353D01*
G01X189940Y719081D02*
Y719822D01*
X188566Y721196D01*
Y722353D01*
G01X185440Y727581D02*
Y725815D01*
X183566Y723941D01*
Y722353D01*
G01X185440Y719081D02*
Y719275D01*
X183566Y721149D01*
Y722353D01*
G01X194440Y727581D02*
Y725585D01*
X193566Y724711D01*
Y722333D01*
G01X194440Y719048D02*
Y720444D01*
X193566Y721318D01*
Y722333D01*
G01X191440Y708356D02*
Y709046D01*
X187520Y712966D01*
Y720523D01*
X186164Y721879D01*
Y724134D01*
G01X185440Y742231D02*
Y742125D01*
X182938Y739623D01*
Y734623D01*
X185440Y732121D01*
Y730731D01*
G01X189940D02*
Y732625D01*
X191938Y734623D01*
Y740123D01*
X189940Y742121D01*
Y742231D01*
G01X194440Y730731D02*
Y732625D01*
X196438Y734623D01*
Y740123D01*
X194440Y742121D01*
Y742231D01*
G01X182500Y780786D02*
Y770413D01*
X189940Y762973D01*
Y742231D01*
G01X194440D02*
Y764382D01*
X189973Y768849D01*
Y777879D01*
X189770Y778082D01*
G01X192949Y771020D02*
Y770132D01*
X195973Y767108D01*
Y749171D01*
X198940Y746204D01*
Y742231D01*
G01X189035Y807872D02*
Y784737D01*
X192949Y780823D01*
Y771020D01*
G01X199760Y763929D02*
X197750Y765939D01*
Y781655D01*
X192972Y786433D01*
Y807872D01*
G01X182500Y780786D02*
X181161Y782125D01*
Y807872D01*
G01X185098Y805904D02*
Y785801D01*
X189770Y781129D01*
Y778082D01*
G01X209646Y114763D02*
Y120297D01*
X210616Y121267D01*
X210623D01*
G01X205535Y234497D02*
X207970Y236932D01*
Y247999D01*
X208188Y248217D01*
G01X208396Y251987D02*
X209508Y250875D01*
Y232655D01*
X205535Y228682D01*
G01X197957Y250206D02*
X200706D01*
X201645Y249267D01*
Y244477D01*
X200571Y243403D01*
Y234974D01*
X198296Y232699D01*
G01X205364Y246260D02*
Y243699D01*
X205566Y243497D01*
G01X206271Y250223D02*
Y249188D01*
X203952Y246869D01*
Y242009D01*
X205271Y240690D01*
Y240209D01*
G01X198685Y244085D02*
X200340Y245740D01*
Y248656D01*
G01X211803Y257697D02*
Y257832D01*
X210305Y259330D01*
G01X211803Y260697D02*
Y260791D01*
X210305Y262289D01*
G01X203983Y259197D02*
X203286Y259894D01*
Y259939D01*
X201977Y261248D01*
X201994D01*
G01X198919Y257697D02*
X199295D01*
X200687Y256305D01*
X200977D01*
G01X203983Y262197D02*
Y262319D01*
X202589Y263713D01*
X202402D01*
G01X198919Y260697D02*
Y260689D01*
X200469Y259139D01*
G01X211803Y269697D02*
X211773D01*
X210303Y268227D01*
G01X211803Y272697D02*
X211773D01*
X210303Y271227D01*
G01X207874Y298423D02*
Y298418D01*
X206319Y296863D01*
G01X205795Y322649D02*
Y322995D01*
X208000Y325200D01*
G01X196812Y314969D02*
Y316706D01*
X196476Y317042D01*
G01X205795Y325649D02*
X208146Y328000D01*
X208700D01*
G01X200012Y342535D02*
X202754Y345277D01*
X203150D01*
G01X210214Y343866D02*
X210414Y344066D01*
Y346866D01*
G01X203150Y345277D02*
X204249Y344178D01*
X207027D01*
X207538Y344689D01*
G01D02*
X208361Y343866D01*
X210214D01*
G01X199650Y345277D02*
Y342897D01*
X200012Y342535D01*
G01X212846Y344859D02*
Y344593D01*
X210232Y341979D01*
X208203D01*
G01D02*
X207791D01*
X206658Y343112D01*
X203345D01*
X202768Y342535D01*
G01X217378Y345277D02*
Y346220D01*
X212474Y351124D01*
Y356399D01*
X206973Y361900D01*
G01X203174Y348190D02*
Y347184D01*
X205024Y345334D01*
X206344D01*
X206999Y345989D01*
X207312D01*
X209741Y348418D01*
X212843D01*
X213054Y348629D01*
G01X203174Y348190D02*
X199533D01*
X199526Y348183D01*
G01X208729Y379173D02*
Y363656D01*
X206973Y361900D01*
G01X221228Y396690D02*
Y399707D01*
X216227Y404708D01*
X202676D01*
X201267Y403299D01*
Y403294D01*
G01Y400255D02*
Y403294D01*
G01X196149Y400255D02*
Y403028D01*
X196273Y403152D01*
G01X198708Y400255D02*
Y404512D01*
X199904Y405708D01*
X219079D01*
X223085Y401702D01*
G01X225755Y510471D02*
X219359Y504075D01*
X208209D01*
G01X228905Y519919D02*
X227328Y518342D01*
X222498D01*
X218757Y514601D01*
X211061D01*
X207724Y517938D01*
Y523605D01*
X207005Y524324D01*
X205662D01*
X205195Y523857D01*
Y522335D01*
G01X228905Y523069D02*
X228173D01*
X226657Y521553D01*
X222656D01*
X220711Y523498D01*
X218311D01*
X217575Y522762D01*
Y519338D01*
X216935Y518698D01*
X213364D01*
X212269Y519793D01*
Y520497D01*
X212870Y521098D01*
X214405D01*
X215108Y521801D01*
Y523376D01*
X214160Y524324D01*
X210323D01*
X209364Y523365D01*
Y519214D01*
X211609Y516969D01*
Y516553D01*
G01X228905Y513620D02*
X227302Y512017D01*
X224973D01*
X219410Y506454D01*
X199565D01*
G01X228905Y516770D02*
X227234Y515099D01*
X224355D01*
X219969Y510713D01*
X208849D01*
X208353Y511209D01*
X207782D01*
X207286Y510713D01*
X206549D01*
X206159Y511103D01*
Y513503D01*
X205294Y514368D01*
G01X225755Y513620D02*
X224976D01*
X220069Y508713D01*
X205247D01*
G01X228905Y526219D02*
X227408Y524722D01*
X224676D01*
X224450Y524948D01*
X216614D01*
X215638Y525924D01*
X205155D01*
X203368Y527711D01*
Y528325D01*
X203865Y528822D01*
X205257D01*
G01X225755Y532518D02*
X224857D01*
X222093Y535282D01*
X220244D01*
X219323Y536203D01*
X215759D01*
X213109Y538853D01*
X211477D01*
X209736Y537112D01*
X199539D01*
G01X207178Y572893D02*
X211240D01*
G01D02*
X212302D01*
X217150Y577741D01*
Y585174D01*
X219185Y587209D01*
X224297D01*
X231670Y594582D01*
Y605805D01*
X234269Y608404D01*
Y610268D01*
X233566Y610971D01*
Y610977D01*
X221223D01*
X220520Y611680D01*
Y612674D01*
X221223Y613377D01*
X233566D01*
X234269Y614080D01*
Y615074D01*
X233566Y615777D01*
X221223D01*
X220520Y616480D01*
Y617474D01*
X221223Y618177D01*
X232810D01*
X234269Y619636D01*
Y623433D01*
G01X207178Y576893D02*
X210040D01*
G01X204028D02*
X202958D01*
X202950Y576885D01*
X201510D01*
G01X204028Y572893D02*
X197730D01*
G01X204028Y584893D02*
Y580893D01*
G01Y588893D02*
X198483D01*
X197643Y589733D01*
Y589735D01*
X196740D01*
G01X207178Y584893D02*
X209940D01*
G01X207178Y588893D02*
Y591595D01*
G01X209299Y621977D02*
X205550D01*
X202466Y618893D01*
X199786D01*
G01X209299Y625977D02*
X204482D01*
X202510Y624005D01*
G01X209299Y633977D02*
X204857D01*
X200380Y629500D01*
Y629085D01*
G01X200910Y653700D02*
X198640Y651430D01*
Y645165D01*
X200105Y643700D01*
X200910D01*
G01D02*
Y643245D01*
X197480Y639815D01*
G01X205410Y653700D02*
X203410Y651700D01*
Y645035D01*
X204745Y643700D01*
X205410D01*
G01D02*
Y641045D01*
X203065Y638700D01*
G01X209299Y629977D02*
X206130D01*
X205221Y630886D01*
G01X196410Y656850D02*
Y660058D01*
X199510Y663158D01*
G01X205410Y656850D02*
Y661200D01*
G01X200910Y656850D02*
Y659735D01*
G01X199993Y678356D02*
Y681048D01*
X199590Y681451D01*
Y682868D01*
G01X199350Y692724D02*
X200631Y691443D01*
X202598D01*
X203733Y690308D01*
Y688002D01*
G01X217530Y715305D02*
X216770Y714545D01*
Y712832D01*
X214353Y710415D01*
Y703959D01*
X209536Y699142D01*
Y693554D01*
X210824Y692266D01*
G01X199350Y692724D02*
Y694763D01*
X200943Y696356D01*
X203730D01*
X207014Y699640D01*
Y706782D01*
X205440Y708356D01*
G01X215440Y699556D02*
X212236D01*
X211236Y698556D01*
Y695586D01*
G01X201440Y699556D02*
X198900D01*
X197243Y697899D01*
G01X198940Y727581D02*
Y725220D01*
X198566Y724846D01*
Y722353D01*
G01X198940Y719081D02*
Y721979D01*
X198566Y722353D01*
G01X207940Y727581D02*
Y723421D01*
X209017Y722344D01*
G01X207940Y719081D02*
Y719749D01*
X209017Y720826D01*
Y722344D01*
G01X203440Y719048D02*
Y720189D01*
X203611Y720360D01*
Y722303D01*
G01X203440Y727581D02*
Y725346D01*
X203611Y725175D01*
Y722303D01*
G01X205440Y708356D02*
Y712510D01*
G01X207940Y730731D02*
Y733123D01*
X209938Y735121D01*
Y740123D01*
X207940Y742121D01*
Y742231D01*
G01X198940Y730731D02*
Y733125D01*
X200938Y735123D01*
Y740123D01*
X198940Y742121D01*
Y742231D01*
G01X203440Y730731D02*
Y733123D01*
X205438Y735121D01*
Y740123D01*
X203440Y742121D01*
Y742231D01*
G01X202050Y784919D02*
Y755153D01*
X207940Y749263D01*
Y742231D01*
G01X203440D02*
Y749878D01*
X199760Y753558D01*
Y763929D01*
G01X206210Y771577D02*
Y763654D01*
X212440Y757424D01*
Y742231D01*
G01X196909Y807872D02*
Y788559D01*
X200549Y784919D01*
X202050D01*
G01X206210Y771577D02*
Y773345D01*
X204783Y774772D01*
Y807872D01*
G01X208720D02*
Y786484D01*
X212360Y782844D01*
Y773293D01*
X212350Y773283D01*
G01X227363Y82480D02*
Y88740D01*
X226718Y89385D01*
X226620D01*
G01X224862Y230503D02*
X223090Y232275D01*
Y238091D01*
X223092Y238093D01*
Y246260D01*
G01X226010Y233542D02*
Y237960D01*
X227725Y239675D01*
Y241433D01*
X225914Y243244D01*
Y246021D01*
X227249Y247356D01*
Y248773D01*
X226339Y249683D01*
Y250101D01*
X227338Y251100D01*
Y251490D01*
X226841Y251987D01*
X226124D01*
G01X223999Y250223D02*
X224300Y249922D01*
Y232687D01*
X225376Y231611D01*
X227277D01*
X228220Y230668D01*
G01X218092Y251569D02*
Y250643D01*
X220335Y248400D01*
Y237781D01*
X217135Y234581D01*
Y230585D01*
G01X213704Y252157D02*
Y250208D01*
X215347Y248565D01*
Y233997D01*
X211935Y230585D01*
G01X225916Y248217D02*
Y247455D01*
X225111Y246650D01*
Y241241D01*
X226010Y240342D01*
G01X215685Y250206D02*
X216525Y249366D01*
Y248340D01*
X218735Y246130D01*
Y241369D01*
X218151Y240785D01*
X217135D01*
G01X218068Y248656D02*
X219535Y247189D01*
Y239785D01*
X217135Y237385D01*
G01X227443Y260697D02*
Y260727D01*
X225973Y262197D01*
G01X219623Y259197D02*
X218508Y258082D01*
Y256664D01*
G01X219623Y271197D02*
Y271047D01*
X217163Y268587D01*
X216184D01*
G01X214559Y269697D02*
X214627D01*
X216069Y271139D01*
X216109D01*
G01X221435Y337649D02*
X221973D01*
X223166Y338842D01*
G01X221435Y334649D02*
Y334631D01*
X222911Y333155D01*
G01X217740Y342535D02*
Y343800D01*
X218678Y344738D01*
Y346062D01*
X218554Y346186D01*
Y348739D01*
X218054Y349239D01*
Y354387D01*
X216810Y355631D01*
Y359898D01*
X214007Y362701D01*
G01X226499Y336149D02*
Y336120D01*
X224996Y334617D01*
G01X226499Y339149D02*
X226391D01*
X223483Y336241D01*
X223095D01*
G01X217254Y348183D02*
Y353608D01*
X214657Y356205D01*
G01X212729Y379173D02*
Y376881D01*
X211419Y375571D01*
Y362067D01*
X213950Y359536D01*
Y356912D01*
X214657Y356205D01*
G01X220902Y348190D02*
Y348661D01*
X220254Y349309D01*
Y372264D01*
X221770Y373780D01*
G01X223285Y346640D02*
Y347706D01*
X221078Y349913D01*
Y353452D01*
X221254Y353628D01*
Y357052D01*
X222225Y358023D01*
Y364031D01*
G01X227942Y343866D02*
Y344228D01*
X226252Y345918D01*
Y349307D01*
X224674Y350885D01*
Y357198D01*
X225342Y357866D01*
Y368632D01*
X230010Y373300D01*
G01X228142Y346866D02*
Y348566D01*
X226363Y350345D01*
Y366625D01*
X227745Y368007D01*
G01X213054Y348629D02*
Y345067D01*
X212846Y344859D01*
G01X220878Y345277D02*
X219478Y346677D01*
Y348953D01*
X219056Y349375D01*
Y359372D01*
X217818Y360610D01*
Y368665D01*
G01X216729Y379173D02*
Y376539D01*
X214007Y373817D01*
Y362701D01*
G01X224729Y379173D02*
Y376739D01*
X221770Y373780D01*
G01X228729Y379173D02*
Y376986D01*
X223119Y371376D01*
Y364925D01*
X222225Y364031D01*
G01X220729Y379173D02*
Y376461D01*
X217818Y373550D01*
Y368665D01*
G01X225228Y396690D02*
Y399559D01*
X223085Y401702D01*
G01X218040Y469399D02*
Y473853D01*
G01X223953Y469967D02*
Y470133D01*
X226255Y472435D01*
Y472579D01*
G01X219640Y479308D02*
X221794D01*
X222419Y479933D01*
G01X225755Y497872D02*
Y495645D01*
X225909Y495491D01*
Y487387D01*
X222558Y484036D01*
Y480072D01*
X222419Y479933D01*
G01X219640Y476158D02*
Y475453D01*
X218040Y473853D01*
G01X238354Y507321D02*
X236776Y505743D01*
Y496120D01*
X234164Y493508D01*
Y492403D01*
X224848Y483087D01*
Y477700D01*
X223786Y476638D01*
G01X241503Y501022D02*
X239876Y499395D01*
Y495653D01*
X237909Y493686D01*
Y492790D01*
X226255Y481136D01*
Y472579D01*
G01X225755Y519919D02*
X222375D01*
X220527Y521767D01*
X219811D01*
X219381Y521337D01*
Y517489D01*
X218245Y516353D01*
X217609D01*
G01X228905Y532518D02*
X228072D01*
X226588Y531034D01*
X224994D01*
X222075Y533953D01*
X215118D01*
X212342Y536729D01*
G01X225755Y526219D02*
X218360D01*
X218000Y526579D01*
Y527479D01*
X219328Y528807D01*
Y528823D01*
G01X225755Y523069D02*
X223629D01*
X223376Y523322D01*
G01X228905Y538817D02*
X227340Y540382D01*
X224509D01*
X220876Y544015D01*
X218931D01*
X218751Y543835D01*
G01X225755Y538817D02*
X225310Y539262D01*
X223900D01*
X221083Y542079D01*
X218069D01*
X215946Y544202D01*
G01X226228Y583822D02*
Y581788D01*
X227100Y580916D01*
G01X224269Y602633D02*
Y598283D01*
X225099Y597453D01*
X225100D01*
G01X225179Y635939D02*
Y633004D01*
X228290Y629893D01*
G01X211560Y670575D02*
X213365Y672380D01*
Y678356D01*
G01X218240Y674433D02*
Y680241D01*
X219780Y681781D01*
X225742D01*
X226993Y680530D01*
Y678356D01*
G01X217105Y688002D02*
Y693486D01*
X219440Y695821D01*
Y708356D01*
G01X216940Y727581D02*
Y726466D01*
X221320Y722086D01*
Y720698D01*
G01X212440Y727581D02*
Y726902D01*
X213610Y725732D01*
Y720623D01*
X213310Y720323D01*
Y719064D01*
G01X219440Y708356D02*
Y710436D01*
X222710Y713706D01*
G01X216820Y723301D02*
Y722384D01*
X221537Y717667D01*
X240098D01*
X242958Y714807D01*
X251797D01*
X254605Y717615D01*
X261623D01*
X279928Y699310D01*
X284428D01*
G01X221440Y727581D02*
X224410Y719970D01*
G01X221440Y730731D02*
Y732478D01*
X223690Y734728D01*
Y740767D01*
X222226Y742231D01*
X221440D01*
G01X212440Y730731D02*
Y732650D01*
X214650Y734860D01*
Y740084D01*
X212503Y742231D01*
X212440D01*
G01X216940Y730731D02*
Y732902D01*
X219110Y735072D01*
Y739928D01*
X216940Y742098D01*
Y742231D01*
G01X225940Y730731D02*
X227640Y732431D01*
Y734392D01*
X227040Y734992D01*
Y735337D01*
X225940Y736437D01*
G01D02*
Y739081D01*
G01X218270Y785657D02*
Y764204D01*
X221440Y761034D01*
Y742231D01*
G01X220960Y778561D02*
Y768048D01*
X225940Y763068D01*
Y742231D01*
G01X216940D02*
Y758409D01*
X212360Y762989D01*
Y773273D01*
X212350Y773283D01*
G01X216594Y807872D02*
Y787333D01*
X218270Y785657D01*
G01X220532Y807872D02*
Y796155D01*
X222650Y794037D01*
Y780251D01*
X220960Y778561D01*
G01X224469Y807872D02*
Y776084D01*
X226670Y773883D01*
Y773299D01*
G01D02*
Y771866D01*
X230440Y768096D01*
Y742231D01*
G01X230690Y230591D02*
Y231513D01*
X228015Y234188D01*
Y238046D01*
X229298Y239329D01*
Y244915D01*
X229957Y245574D01*
Y246932D01*
X228554Y248335D01*
Y249978D01*
X228556Y249980D01*
G01X228756Y252980D02*
X230168Y251568D01*
Y247866D01*
X230845Y247189D01*
Y245316D01*
X230108Y244579D01*
Y239203D01*
X230380Y238931D01*
Y234285D01*
X232910Y231755D01*
Y231032D01*
G01X239444Y248663D02*
X239443D01*
X238455Y247676D01*
Y242048D01*
X239260Y241243D01*
Y236154D01*
X241400Y234014D01*
Y233676D01*
G01X238600D02*
X237721Y234555D01*
Y240459D01*
X234989Y243191D01*
Y245691D01*
X234420Y246260D01*
G01X235800Y232664D02*
Y239603D01*
X234180Y241223D01*
Y244626D01*
X233219Y245587D01*
Y248527D01*
X231430Y250316D01*
Y252155D01*
X231432Y252157D01*
G01X231746Y248007D02*
Y245887D01*
X233361Y244272D01*
Y235429D01*
X232948Y235016D01*
Y234047D01*
G01X235796Y248656D02*
X236610Y247842D01*
Y244142D01*
X236710Y244042D01*
G01X240820Y246260D02*
X240388Y245828D01*
Y242453D01*
X240800Y242041D01*
Y236726D01*
X244200Y233326D01*
Y233141D01*
G01X242460Y237591D02*
Y242731D01*
X242138Y243053D01*
Y245657D01*
X242141Y245660D01*
Y248759D01*
X243082Y249700D01*
Y250745D01*
X242217Y251610D01*
Y254297D01*
X241688Y254826D01*
G01X239320Y251569D02*
Y251396D01*
X237654Y249730D01*
Y249719D01*
G01X238019Y268197D02*
Y268189D01*
X239569Y266639D01*
G01X242524Y307873D02*
X240925Y306274D01*
Y306257D01*
G01X237075Y334649D02*
X237048D01*
X238548Y333149D01*
G01X229255Y336149D02*
X229263D01*
X230725Y334687D01*
Y334547D01*
G01X244895Y336149D02*
X244174D01*
X242667Y334642D01*
X240598D01*
G01X242139Y339149D02*
X241357D01*
X240218Y338010D01*
G01X229255Y339149D02*
X230220D01*
X231144Y338225D01*
G01X238224Y342535D02*
Y342750D01*
X237213Y343761D01*
Y349984D01*
X235364Y351833D01*
Y360407D01*
X233567Y362204D01*
Y364356D01*
X235195Y365984D01*
Y367201D01*
X237578Y369584D01*
G01X242139Y336149D02*
X241460D01*
X241213Y336396D01*
X238820D01*
X238560Y336136D01*
G01X232738Y342020D02*
Y344823D01*
X233999Y346084D01*
Y347162D01*
X232882Y348279D01*
Y349500D01*
X232057Y350325D01*
Y355504D01*
X233635Y357082D01*
G01X234319Y334649D02*
X234211D01*
X232769Y333207D01*
G01X240894Y341784D02*
X240781D01*
X239425Y340428D01*
X239290D01*
G01X241013Y346640D02*
Y349720D01*
X241206Y349913D01*
Y351259D01*
X239943Y352522D01*
Y356906D01*
X239410Y357439D01*
Y371283D01*
X241215Y373088D01*
Y374601D01*
G01X230782Y348629D02*
X230392Y349019D01*
Y351777D01*
X230457Y351842D01*
Y354724D01*
X230257Y354924D01*
Y359202D01*
X229497Y359962D01*
Y363431D01*
X233136Y367070D01*
G01X230574Y344859D02*
Y346998D01*
X229142Y348430D01*
Y351659D01*
X229657Y352174D01*
Y353826D01*
X228419Y355064D01*
Y356855D01*
G01X232699Y346623D02*
X232082Y347240D01*
Y349168D01*
X231192Y350058D01*
Y351445D01*
X231257Y351510D01*
Y362218D01*
G01X238630Y348190D02*
Y350265D01*
X236407Y352488D01*
Y361786D01*
X237094Y362473D01*
Y364095D01*
X237076Y364113D01*
G01X232729Y379173D02*
Y376828D01*
X230010Y374109D01*
Y373300D01*
G01X244729Y379173D02*
Y378115D01*
X241215Y374601D01*
G01X236729Y379173D02*
Y377259D01*
X234144Y374674D01*
Y374406D01*
X227745Y368007D01*
G01X240729Y379173D02*
Y377522D01*
X233136Y369929D01*
Y367070D01*
G01X232647Y396011D02*
X232650D01*
X233790Y394871D01*
Y390936D01*
X235304Y389422D01*
X237117D01*
X244216Y382323D01*
X244729D01*
G01X233309Y466578D02*
Y464439D01*
X231461Y462591D01*
G01D02*
X230609Y463443D01*
Y480653D01*
X240209Y490253D01*
Y493156D01*
X241876Y494823D01*
Y495820D01*
X243166Y497110D01*
Y499535D01*
X244653Y501022D01*
G01X242009Y466578D02*
Y465362D01*
X243471Y463900D01*
Y460292D01*
G01X250952Y501022D02*
X249409Y499479D01*
Y496753D01*
X245909Y493253D01*
Y489065D01*
X241509Y484665D01*
Y481453D01*
X240009Y479953D01*
Y462442D01*
X242168Y460283D01*
X243471D01*
Y460292D01*
G01X247802Y501022D02*
Y500268D01*
X246366Y498832D01*
Y497110D01*
X243876Y494620D01*
Y493993D01*
X242509Y492626D01*
Y489153D01*
X236309Y482953D01*
Y480253D01*
X235497Y479441D01*
Y468690D01*
X237609Y466578D01*
G01D02*
Y463676D01*
X238430Y462855D01*
Y460338D01*
G01X228242Y469924D02*
X228604Y470286D01*
Y479682D01*
G01X241909Y478128D02*
Y480155D01*
X242542Y480788D01*
Y481912D01*
X244390Y483760D01*
G01X233309Y478128D02*
Y480053D01*
X234209Y480953D01*
G01X244653Y497872D02*
Y496997D01*
X242876Y495220D01*
Y494408D01*
X241309Y492841D01*
Y489653D01*
X234209Y482553D01*
Y480953D01*
G01X237609Y478128D02*
Y481053D01*
X239309Y482753D01*
G01X247802Y497872D02*
Y497046D01*
X244876Y494120D01*
Y489755D01*
X239309Y484188D01*
Y482753D01*
G01X241503Y497872D02*
Y496862D01*
X240876Y496235D01*
Y495238D01*
X238909Y493271D01*
Y490449D01*
X228604Y480144D01*
Y479682D01*
G01X235204Y504171D02*
Y504169D01*
X233626Y502591D01*
G01X235204Y516770D02*
Y516768D01*
X233626Y515190D01*
G01X232054Y516770D02*
Y516768D01*
X230476Y515190D01*
G01X232054Y513620D02*
Y513618D01*
X230476Y512040D01*
G01X235204Y513620D02*
Y513618D01*
X233626Y512040D01*
G01X235204Y523069D02*
Y523067D01*
X233626Y521489D01*
G01X238354Y532518D02*
X238345D01*
X236776Y534087D01*
G01X238354Y519919D02*
Y519917D01*
X236776Y518339D01*
G01X235204Y529368D02*
Y529366D01*
X233626Y527788D01*
G01X232054Y532518D02*
X232045D01*
X230476Y534087D01*
G01X238354Y523069D02*
Y523067D01*
X236776Y521489D01*
G01X238354Y529368D02*
Y529327D01*
X236815Y527788D01*
X236776D01*
G01X235204Y526219D02*
Y526177D01*
X233666Y524639D01*
X233626D01*
G01X235204Y519919D02*
Y519917D01*
X233626Y518339D01*
G01X232054Y526219D02*
Y526217D01*
X230476Y524639D01*
G01X235204Y532518D02*
X235195D01*
X233626Y534087D01*
G01X232054Y519919D02*
Y519917D01*
X230476Y518339D01*
G01X232054Y529368D02*
Y529327D01*
X230515Y527788D01*
X230476D01*
G01X232054Y523069D02*
Y523067D01*
X230476Y521489D01*
G01X235204Y541967D02*
X235195D01*
X233626Y543536D01*
G01X238354Y538817D02*
X238345D01*
X236776Y540386D01*
G01X238354Y535667D02*
X238345D01*
X236776Y537236D01*
G01X232054Y535667D02*
X232045D01*
X230476Y537236D01*
G01X232054Y541967D02*
X232045D01*
X230476Y543536D01*
G01X232054Y538817D02*
X232045D01*
X230476Y540386D01*
G01X235204Y538817D02*
X235195D01*
X233626Y540386D01*
G01X238354Y541967D02*
X238345D01*
X236776Y543536D01*
G01X235204Y535667D02*
X235195D01*
X233626Y537236D01*
G01X241503Y560864D02*
X239979Y562388D01*
Y564703D01*
X238325Y566357D01*
X235307D01*
G01X247802Y564014D02*
X247810D01*
X248050Y564254D01*
Y576749D01*
X246270Y578529D01*
X243197D01*
X242204Y579522D01*
X228494D01*
X227100Y580916D01*
G01X242830Y597409D02*
X240541Y595120D01*
X236150D01*
X234269Y597001D01*
Y602633D01*
G01X229269D02*
Y597682D01*
G01X246199Y596382D02*
X243857D01*
X242830Y597409D01*
G01X239269Y623433D02*
Y626249D01*
X236780Y628738D01*
G01X229269Y623433D02*
Y628914D01*
X228290Y629893D01*
G01X229199Y635939D02*
Y633785D01*
X233580Y629404D01*
X236114D01*
X236780Y628738D01*
G01X229199Y639089D02*
Y642180D01*
G01X241809Y641295D02*
X239273D01*
X238420Y642148D01*
G01X241670Y646103D02*
X240802D01*
X238420Y643721D01*
Y642148D01*
G01X234500Y637685D02*
X234329Y637856D01*
Y641295D01*
G01D02*
Y642205D01*
X237451Y645327D01*
Y646199D01*
G01X229584D02*
X233584D01*
G01D02*
X237451D01*
G01X240493Y678356D02*
X238528D01*
X237275Y679609D01*
G01X233940Y708356D02*
Y699820D01*
X235654Y698106D01*
Y695913D01*
X230733Y690992D01*
Y688002D01*
G01X229940Y699556D02*
X231793D01*
X233954Y697395D01*
G01X244440Y699556D02*
X242388D01*
X239084Y696252D01*
G01X248440Y708356D02*
X249092Y709008D01*
X245939D01*
X242680Y712267D01*
Y712337D01*
G01X233940Y708356D02*
Y713044D01*
X234960Y714064D01*
G01X239210Y720040D02*
X239432D01*
X243465Y716007D01*
X251299D01*
X254107Y718815D01*
X262123D01*
X268526Y712412D01*
X276376D01*
X284645Y704143D01*
X286798D01*
G01X284428Y687499D02*
X289334D01*
X290580Y688745D01*
Y702073D01*
X288860Y703793D01*
Y705327D01*
X280575Y713612D01*
X269026D01*
X262623Y720015D01*
X253600D01*
X251342Y717757D01*
X243898D01*
X239915Y721740D01*
X235834D01*
X234910Y720816D01*
G01X239440Y730731D02*
Y730994D01*
X237240Y733194D01*
Y741241D01*
X238230Y742231D01*
X239440D01*
G01X230440Y730731D02*
Y733300D01*
X228240Y735500D01*
Y740857D01*
X229614Y742231D01*
X230440D01*
G01X239440Y727581D02*
X240695D01*
X241470Y728356D01*
Y732523D01*
X240470Y733523D01*
X239500D01*
G01X230440Y727581D02*
Y724242D01*
G01X234940Y739081D02*
Y736392D01*
G01Y730731D02*
X233240Y732431D01*
Y734692D01*
X234940Y736392D01*
G01X236180Y786517D02*
Y775343D01*
X239440Y772083D01*
Y742231D01*
G01X234011Y772902D02*
X234940Y771973D01*
Y742231D01*
G01X240217Y807872D02*
Y795692D01*
X242230Y793679D01*
Y774803D01*
G01D02*
Y771996D01*
X243940Y770286D01*
Y742231D01*
G01X228406Y807872D02*
Y778507D01*
X234011Y772902D01*
G01X236280Y807872D02*
Y786617D01*
X236180Y786517D01*
G01X256891Y114763D02*
Y109785D01*
X256273Y109167D01*
X251553D01*
X250423Y108037D01*
Y105057D01*
X256133Y99347D01*
G01X249810Y229679D02*
Y230690D01*
X248414Y232086D01*
Y238089D01*
X245342Y241161D01*
Y244783D01*
X244947Y245178D01*
Y249967D01*
X243852Y251062D01*
Y251987D01*
G01X243644Y248217D02*
Y244553D01*
X244168Y244029D01*
Y239861D01*
X246330Y237699D01*
Y231188D01*
X247000Y230518D01*
Y228486D01*
G01X246484Y246260D02*
Y242247D01*
X250321Y238410D01*
Y232417D01*
X252600Y230138D01*
Y228892D01*
G01X251260Y255062D02*
X250517Y254319D01*
Y251508D01*
X249916Y250907D01*
Y249515D01*
X250873Y248558D01*
Y245705D01*
X252888Y243690D01*
X253582D01*
X256118Y241154D01*
Y227540D01*
X255287Y226709D01*
G01X254221Y230582D02*
Y231009D01*
X251744Y233486D01*
Y238899D01*
X247910Y242733D01*
Y246662D01*
X247213Y247359D01*
Y249020D01*
X247659Y249466D01*
Y252428D01*
X247107Y252980D01*
X246484D01*
G01X253548Y251569D02*
Y250578D01*
X252225Y249255D01*
Y248063D01*
X257818Y242470D01*
Y239782D01*
X259562Y238038D01*
Y227581D01*
X256492Y224511D01*
Y222466D01*
G01X262030Y240378D02*
Y240796D01*
X255856Y246970D01*
Y250377D01*
X257048Y251569D01*
G01X264570Y238017D02*
Y239659D01*
X258546Y245683D01*
Y246258D01*
X258548Y246260D01*
G01X266750Y239528D02*
X264265Y242013D01*
X263585D01*
X260074Y245524D01*
Y247960D01*
X258953Y249081D01*
X257590D01*
X257172Y248663D01*
G01X253524Y248656D02*
X255018Y247162D01*
Y246581D01*
X260108Y241491D01*
Y240376D01*
G01X257950Y236924D02*
X256918Y237956D01*
Y241548D01*
X252206Y246260D01*
X252148D01*
G01X249474Y248007D02*
X250044Y247437D01*
Y243552D01*
X251876Y241720D01*
X253105D01*
X254418Y240407D01*
G01X249160Y252157D02*
Y251545D01*
X248687Y251072D01*
Y249243D01*
X248042Y248598D01*
Y247663D01*
X248951Y246754D01*
Y243219D01*
X254181Y237989D01*
Y234521D01*
G01X245839Y257697D02*
X247281Y259139D01*
X247389D01*
G01X258723Y257697D02*
X257907Y256881D01*
X256553D01*
G01X258723Y269697D02*
Y269727D01*
X257253Y271197D01*
G01X258723Y266697D02*
Y266727D01*
X257253Y268197D01*
G01X252715Y325649D02*
X253698D01*
X254631Y324716D01*
G01X257779Y327149D02*
X257628D01*
X254998Y329779D01*
G01X252715Y328649D02*
X253469D01*
X254905Y327213D01*
G01X244895Y339149D02*
Y339147D01*
X246685Y337357D01*
G01X245670Y343866D02*
Y344585D01*
X243980Y346275D01*
Y349271D01*
X243670Y349581D01*
Y358922D01*
X243748Y359000D01*
Y362688D01*
X244595Y363535D01*
G01X249959Y334649D02*
Y335309D01*
X251366Y336716D01*
Y338735D01*
X254496Y341865D01*
Y347077D01*
X254010Y347563D01*
Y349499D01*
X253184Y350325D01*
Y361569D01*
X256248Y364633D01*
G01X252715Y337649D02*
Y338287D01*
X255167Y340739D01*
X255854D01*
X257534Y342419D01*
Y345775D01*
X256732Y346577D01*
X256273D01*
X254943Y347907D01*
Y350232D01*
X254384Y350791D01*
Y359064D01*
X267838Y372518D01*
X269966D01*
X272031Y374583D01*
G01X252715Y334649D02*
X254529D01*
X255124Y335244D01*
G01X257779Y336149D02*
Y337002D01*
X259234Y338457D01*
Y339987D01*
X259822Y340575D01*
Y342733D01*
X259522Y343033D01*
Y345382D01*
X260254Y346114D01*
Y346846D01*
X261608Y348200D01*
Y349478D01*
X261498Y349588D01*
Y357384D01*
X266874Y362760D01*
Y364373D01*
X270002Y367501D01*
X274425D01*
X279569Y372645D01*
X280944D01*
X281450Y373151D01*
G01X257779Y333149D02*
X259132Y334502D01*
X262247D01*
G01X257734Y350586D02*
X256449Y351871D01*
Y356426D01*
X261470Y361447D01*
Y364915D01*
X264067Y367512D01*
X266130D01*
X269532Y370914D01*
X271782D01*
X277040Y376172D01*
G01X268729Y379173D02*
X266377Y376821D01*
Y376003D01*
X257482Y367108D01*
X255753D01*
X251051Y362406D01*
Y357574D01*
X251491Y357134D01*
G01X250427Y346623D02*
Y348701D01*
X249734Y349392D01*
Y353529D01*
X251051Y354846D01*
Y356694D01*
X251491Y357134D01*
G01X248510Y348629D02*
Y354004D01*
X249282Y354776D01*
Y365246D01*
X252994Y368958D01*
X255063D01*
X255503Y369398D01*
X256533D01*
X260536Y373401D01*
Y374216D01*
G01X256358Y348190D02*
Y349963D01*
X255184Y351137D01*
Y357601D01*
X256588Y359005D01*
G01X258741Y346640D02*
Y349720D01*
X258968Y349947D01*
Y351225D01*
X257483Y352710D01*
Y355913D01*
X263575Y362005D01*
Y364050D01*
G01X248302Y344859D02*
Y346998D01*
X247210Y348090D01*
Y349168D01*
X247494Y349452D01*
Y354553D01*
X247982Y355041D01*
Y367811D01*
X251419Y371248D01*
X254111D01*
X257226Y374363D01*
G01X245870Y346866D02*
Y348513D01*
X244470Y349913D01*
Y356850D01*
X246446Y358826D01*
Y368134D01*
X251856Y373544D01*
G01X252729Y379173D02*
Y377551D01*
X245165Y369987D01*
Y364105D01*
X244595Y363535D01*
G01X272729Y379173D02*
Y378926D01*
X258436Y364633D01*
X256248D01*
G01X260729Y379173D02*
Y379172D01*
X257226Y375669D01*
Y374363D01*
G01X256729Y379173D02*
Y378417D01*
X251856Y373544D01*
G01X254383Y392464D02*
Y390187D01*
X256606Y387964D01*
G01D02*
X258847D01*
X261754Y390871D01*
G01X252729Y382323D02*
X253762Y383356D01*
Y385255D01*
G01X254813Y430445D02*
Y427018D01*
G01X254798Y424079D02*
X254813Y424094D01*
Y427018D01*
G01X265696Y446936D02*
X261821D01*
X258477Y443592D01*
G01X258553Y438319D02*
Y443516D01*
X258477Y443592D01*
G01X251309Y466078D02*
X249893D01*
X248708Y464893D01*
X246465D01*
G01X257251Y501022D02*
X255766Y499537D01*
Y496910D01*
X252607Y493751D01*
Y482736D01*
X248909Y479038D01*
Y471854D01*
X246458Y469403D01*
Y464893D01*
X246465D01*
G01X255509Y465978D02*
Y464437D01*
X255508Y464436D01*
Y462373D01*
X254018Y460883D01*
X251780D01*
G01X260401Y497872D02*
X257427Y494898D01*
Y481929D01*
X256329Y480831D01*
X255304D01*
X253509Y479036D01*
Y464534D01*
X251898Y462923D01*
Y461001D01*
X251780Y460883D01*
G01X255509Y478128D02*
X257586Y476051D01*
Y461531D01*
X257568Y461513D01*
G01X246109Y478128D02*
Y479595D01*
X249722Y483208D01*
G01X254102Y497872D02*
Y496846D01*
X250571Y493315D01*
Y484057D01*
X249722Y483208D01*
G01X250952Y497872D02*
Y496796D01*
X247209Y493053D01*
Y486953D01*
X244906Y484650D01*
Y484276D01*
X244390Y483760D01*
G01X251309Y478128D02*
Y479677D01*
X255055Y483423D01*
Y483635D01*
G01X257251Y497872D02*
Y496695D01*
X255055Y494499D01*
Y483635D01*
G01X260401Y501022D02*
X260426D01*
X261909Y499539D01*
Y497253D01*
X258672Y494016D01*
Y481291D01*
X255509Y478128D01*
G01X257251Y510471D02*
Y510469D01*
X255673Y508891D01*
G01X254102Y504171D02*
Y504169D01*
X252524Y502591D01*
G01X244653Y504171D02*
Y504169D01*
X243075Y502591D01*
G01X244653Y510471D02*
Y510469D01*
X243075Y508891D01*
G01X257251Y507321D02*
Y507319D01*
X255673Y505741D01*
G01X250952Y507321D02*
Y507319D01*
X249374Y505741D01*
G01X250952Y510471D02*
Y510469D01*
X249374Y508891D01*
G01X257251Y504171D02*
Y504169D01*
X255673Y502591D01*
G01X250952Y504171D02*
Y504169D01*
X249374Y502591D01*
G01X254102Y507321D02*
Y507319D01*
X252524Y505741D01*
G01X254102Y510471D02*
Y510469D01*
X252524Y508891D01*
G01X247802Y504171D02*
Y504169D01*
X246224Y502591D01*
G01X247802Y557715D02*
X247793D01*
X246224Y559284D01*
G01X244653Y564014D02*
X244660D01*
X245860Y565214D01*
Y575049D01*
G01X247802Y554565D02*
X247793D01*
X246224Y556134D01*
G01X247802Y560864D02*
X247794D01*
X246224Y562434D01*
G01X244653Y560864D02*
X243209Y562308D01*
Y574018D01*
G01X259678Y581553D02*
X255073Y576948D01*
Y568917D01*
X252609Y566453D01*
Y562521D01*
X250952Y560864D01*
G01X244653Y554565D02*
Y554562D01*
X243075Y552984D01*
G01X257109Y582978D02*
X258253D01*
X259678Y581553D01*
G01X242830Y597409D02*
Y597415D01*
G01X244780Y682521D02*
X252973D01*
X253993Y681501D01*
Y678356D01*
G01X244233Y688002D02*
Y692903D01*
X248440Y697110D01*
Y708356D01*
G01X262940D02*
Y694778D01*
X257733Y689571D01*
Y688002D01*
G01X251451Y697465D02*
X253542Y699556D01*
X258940D01*
G01X267124Y707892D02*
Y709662D01*
X260871Y715915D01*
X255310D01*
G01X289248Y680521D02*
Y683167D01*
X293900Y687819D01*
Y700454D01*
X290060Y704294D01*
Y706375D01*
X281623Y714812D01*
X270008D01*
X263605Y721215D01*
X253100D01*
X250740Y723575D01*
Y725548D01*
X248707Y727581D01*
X248440D01*
G01X257440Y730731D02*
X255550Y732621D01*
Y740811D01*
X256970Y742231D01*
X257440D01*
G01X248440Y730731D02*
Y731337D01*
X246160Y733617D01*
Y739951D01*
X248440Y742231D01*
G01X257440Y727581D02*
Y726932D01*
X258570Y725802D01*
Y722981D01*
G01X243940Y739081D02*
Y736412D01*
G01D02*
Y730731D01*
G01X252940Y739081D02*
X251070Y737211D01*
Y735437D01*
X252940Y733567D01*
G01D02*
Y730731D01*
G01X256650Y778342D02*
Y746839D01*
X257440Y746049D01*
Y742231D01*
G01X248440D02*
Y778283D01*
X247900Y778823D01*
G01X252470Y785797D02*
Y761569D01*
X252940Y761099D01*
Y742231D01*
G01X255965Y807872D02*
Y779027D01*
X256650Y778342D01*
G01X244154Y807872D02*
Y782569D01*
X247900Y778823D01*
G01X248091Y807872D02*
Y790176D01*
X252470Y785797D01*
G01X272620Y238653D02*
X274993Y241026D01*
Y246889D01*
X277183Y249079D01*
Y250223D01*
G01X267202Y248007D02*
Y245671D01*
X267118Y245587D01*
G01X271458Y241347D02*
X272532D01*
X273958Y242773D01*
Y243619D01*
X273962Y243623D01*
Y247623D01*
X273503Y248082D01*
Y250296D01*
X274776Y251569D01*
G01X264012Y249980D02*
X264020D01*
X264360Y249640D01*
Y248834D01*
X265340Y247854D01*
Y244559D01*
X269630Y240269D01*
Y237667D01*
X270260Y237037D01*
G01X266888Y252157D02*
Y250553D01*
X266187Y249852D01*
G01X274363Y263697D02*
Y265007D01*
X273521Y265849D01*
G01X259416Y254799D02*
X260118Y255501D01*
Y262137D01*
X260068Y262187D01*
G01X261479Y260697D02*
X261499D01*
X263172Y262370D01*
X263268D01*
G01X262201Y254867D02*
X262377D01*
X263574Y256064D01*
Y256264D01*
X263774Y256464D01*
G01X274363Y257697D02*
Y258065D01*
X272464Y259964D01*
G01X268869Y250206D02*
Y252406D01*
X269263Y252800D01*
G01X261479Y272697D02*
X263029Y271147D01*
Y271139D01*
G01X261479Y266697D02*
X261587D01*
X263029Y268139D01*
G01X274886Y268993D02*
Y269101D01*
X273444Y270543D01*
G01X273386Y276813D02*
X273394D01*
X274944Y278363D01*
G01X268886Y281877D02*
X268916D01*
X270386Y280407D01*
G01X265886Y281877D02*
X265916D01*
X267386Y280407D01*
G01X265886Y297517D02*
Y297478D01*
X267317Y296047D01*
X267386D01*
G01X259886Y297517D02*
X260057D01*
X261463Y296111D01*
G01X264386Y292453D02*
Y292548D01*
X265825Y293987D01*
G01X267386Y292453D02*
Y292461D01*
X268867Y293942D01*
G01X268886Y284633D02*
X268894D01*
X270444Y286183D01*
G01X264386Y289697D02*
X262944Y291139D01*
Y293810D01*
X262904Y293850D01*
G01X267386Y289697D02*
X268775Y291086D01*
X268943D01*
G01X265886Y284633D02*
Y287428D01*
X265768Y287546D01*
G01X274886Y284633D02*
Y284678D01*
X273444Y286120D01*
Y286183D01*
G01X274886Y281877D02*
X274018D01*
X273701Y282194D01*
Y282970D01*
X274164Y283433D01*
X276272D01*
X276686Y283019D01*
Y280707D01*
X276386Y280407D01*
G01X273386Y289697D02*
X274686Y290997D01*
Y294319D01*
X273618Y295387D01*
G01X267386Y308093D02*
X267394D01*
X268944Y309643D01*
G01X264386Y308093D02*
X264397D01*
X265944Y309640D01*
G01X268886Y300273D02*
Y302242D01*
X269380Y302736D01*
G01X264386Y305337D02*
Y305318D01*
X264501Y305203D01*
Y303109D01*
G01X267386Y305337D02*
Y305319D01*
X266939Y304872D01*
Y303281D01*
G01X273386Y305337D02*
X274303Y304420D01*
Y303413D01*
G01X273386Y308093D02*
Y308241D01*
X274832Y309687D01*
G01X267386Y320977D02*
X265792Y322571D01*
Y326013D01*
X265318Y326487D01*
G01X273386Y320977D02*
X274774Y322365D01*
X277063D01*
X278067Y323369D01*
Y325842D01*
G01X265599Y328649D02*
X265962D01*
X267172Y327439D01*
X269880D01*
X270525Y326794D01*
Y325754D01*
G01X262201Y328491D02*
X262199Y328493D01*
X259938D01*
X259138Y327693D01*
Y320667D01*
X260046Y319759D01*
X261827D01*
X263045Y320977D01*
X264386D01*
G01X268886Y328797D02*
X270293Y330204D01*
Y330540D01*
G01X271886Y328797D02*
X272964Y329875D01*
Y330669D01*
G01X273386Y323733D02*
Y325423D01*
X272967Y325842D01*
G01X260535Y324149D02*
X261355D01*
X262700Y325494D01*
G01X268355Y337649D02*
X269104D01*
X270485Y339030D01*
G01X260535Y336149D02*
X264013D01*
X264015Y336151D01*
G01X265599Y331649D02*
X265454Y331794D01*
X263173D01*
G01X266030Y344859D02*
Y344562D01*
X266651Y343941D01*
Y340909D01*
X267943Y339617D01*
G01X263398Y343866D02*
Y345227D01*
X262398Y346227D01*
Y347858D01*
X262508Y347968D01*
Y349710D01*
X262298Y349920D01*
Y351710D01*
X263339Y352751D01*
Y357505D01*
X268145Y362311D01*
Y364229D01*
X269517Y365601D01*
X277951D01*
X279863Y367513D01*
G01X265409Y341979D02*
Y343641D01*
X264730Y344320D01*
Y345398D01*
X266370Y347038D01*
X266486D01*
X267538Y348090D01*
Y350687D01*
X267517Y350708D01*
Y355819D01*
X268751Y357053D01*
X270666D01*
X274354Y360741D01*
X284283D01*
X287993Y364451D01*
G01X265599Y337649D02*
X265145Y338103D01*
X262379D01*
G01X260535Y333149D02*
Y331964D01*
X262352Y330147D01*
X267030D01*
G01X273680Y342535D02*
X274326D01*
X275602Y343811D01*
G01X268355Y331649D02*
X268700D01*
X270071Y333021D01*
G01X273419Y336149D02*
Y335378D01*
X272263Y334222D01*
G01X270924Y342535D02*
Y342328D01*
X272352Y340900D01*
G01X270438Y348183D02*
X270717Y348462D01*
Y354092D01*
X269456Y355353D01*
G01X274062Y345277D02*
Y345972D01*
X275286Y347196D01*
Y349008D01*
X274272Y350022D01*
Y352529D01*
X278061Y356318D01*
X285884D01*
X286020Y356454D01*
G01X263598Y346866D02*
Y348097D01*
X265452Y349951D01*
Y356724D01*
X271766Y363038D01*
X279761D01*
X286340Y369617D01*
Y374192D01*
X286550Y374402D01*
G01X263398Y350586D02*
X264372Y351560D01*
Y357116D01*
X270293Y363037D01*
Y363972D01*
G01X266238Y348629D02*
X266462Y348853D01*
Y356180D01*
X269035Y358753D01*
X269886D01*
G01X270562Y345277D02*
Y345522D01*
X271738Y346698D01*
Y353229D01*
X277961Y359452D01*
X288753D01*
X293606Y364305D01*
G01X274086Y348190D02*
X273472Y348804D01*
Y353144D01*
X278634Y358306D01*
X294021D01*
X295527Y359812D01*
G01X264729Y379173D02*
Y378914D01*
X260536Y374721D01*
Y374216D01*
G01X280729Y379173D02*
Y377372D01*
X272812Y369455D01*
X270401D01*
X264996Y364050D01*
X263575D01*
G01X276729Y379173D02*
X276621D01*
X272031Y374583D01*
G01X280729Y382323D02*
X279277D01*
X278538Y383062D01*
Y386573D01*
X277772Y387339D01*
X271492D01*
X270796Y386643D01*
G01X272729Y382323D02*
X276729D01*
G01X261754Y390871D02*
X260713Y391912D01*
Y397834D01*
X260887Y398008D01*
Y399450D01*
G01X268729Y382323D02*
Y384315D01*
X266882Y386162D01*
Y388165D01*
G01X260729Y382323D02*
X259593Y383459D01*
Y385809D01*
X261539Y387755D01*
G01X264729Y382323D02*
Y384504D01*
X264421Y384812D01*
G01X260887Y399450D02*
X263221D01*
X265162Y401391D01*
G01X274625Y394703D02*
X273619Y395709D01*
X268762D01*
X268761Y395710D01*
G01D02*
Y397907D01*
X272197Y401343D01*
X272220D01*
G01X268761Y403190D02*
X274612D01*
X274625Y403203D01*
G01X262798Y424079D02*
X264101D01*
X265532Y422648D01*
G01X266732Y420093D02*
Y421448D01*
X265532Y422648D01*
G01X258798Y424079D02*
X262798D01*
G01X262293Y430445D02*
Y427134D01*
X262798Y426629D01*
Y424079D01*
G01X266822Y443297D02*
X265696Y444423D01*
Y446936D01*
G01X268052Y440162D02*
Y442067D01*
X266822Y443297D01*
G01X307800Y467859D02*
X302530D01*
X297764Y463093D01*
X278285D01*
X271809Y469569D01*
Y472278D01*
X269109Y474978D01*
G01X263550Y497872D02*
Y497394D01*
X260063Y493907D01*
Y480781D01*
X258790Y479508D01*
Y468053D01*
X258830Y468013D01*
Y467757D01*
X260609Y465978D01*
G01D02*
Y464432D01*
X263807Y461234D01*
G01X269109Y478128D02*
X269012Y478225D01*
Y483553D01*
X265001Y487564D01*
Y490677D01*
X263924Y491754D01*
G01X263550Y501022D02*
X265109Y499463D01*
Y497253D01*
X261842Y493986D01*
Y484870D01*
X263324Y483388D01*
G01X260609Y478128D02*
X263324Y480843D01*
Y483388D01*
G01X266700Y497872D02*
Y496644D01*
X265001Y494945D01*
Y492831D01*
X263924Y491754D01*
G01X260401Y504171D02*
Y504162D01*
X261709Y502853D01*
X261972Y502591D01*
G01X263550Y510471D02*
Y510462D01*
X265121Y508891D01*
G01X260401Y510471D02*
Y510462D01*
X261972Y508891D01*
G01X260401Y507321D02*
Y507312D01*
X261535Y506179D01*
X261972Y505741D01*
G01X263550Y507321D02*
Y507313D01*
X265122Y505741D01*
G01X272999Y560864D02*
X274424Y562289D01*
Y567338D01*
X269609Y572153D01*
Y576413D01*
G01X265019Y562333D02*
Y566025D01*
G01X269850Y551415D02*
X269851D01*
X271421Y552985D01*
G01X272999Y564014D02*
Y564843D01*
X273087Y564931D01*
Y566273D01*
X268407Y570953D01*
X268009D01*
G01X274572Y556142D02*
X272999Y557715D01*
G01X269609Y582978D02*
Y576413D01*
G01X276149Y564014D02*
Y572813D01*
X274309Y574653D01*
G01X273809Y582978D02*
Y575153D01*
X274309Y574653D01*
G01X284428Y657971D02*
X279625D01*
X279405Y658191D01*
X272236D01*
X265666Y664761D01*
X261890D01*
G01X273051Y652214D02*
X271735D01*
X270943Y653006D01*
X267775D01*
X266610Y654171D01*
G01X273051Y648117D02*
X271565D01*
X270040Y649642D01*
Y651241D01*
G01X273051Y656491D02*
X270857D01*
X269640Y655274D01*
Y655290D01*
G01X284428Y659939D02*
X281391D01*
X280010Y661320D01*
X272211D01*
X271575Y661956D01*
X270930D01*
X268221Y664665D01*
X268220D01*
Y665311D01*
X265550Y667981D01*
Y668415D01*
G01X266170Y694826D02*
Y690552D01*
X271298Y685424D01*
X275818D01*
X276239Y685003D01*
X279880D01*
X280407Y685530D01*
X284428D01*
G01Y683562D02*
X268280D01*
X267240Y682522D01*
Y682519D01*
G01X269420Y677062D02*
X275396D01*
X280708Y671750D01*
X284428D01*
G01X258940Y699556D02*
X258991Y699505D01*
Y693945D01*
G01X273510Y699749D02*
X277300D01*
X281676Y695373D01*
X284428D01*
G01X270135Y696891D02*
Y696889D01*
X271035Y695989D01*
X277209D01*
X277475Y695723D01*
G01X260680Y712988D02*
X262940Y710728D01*
Y708356D01*
G01X289150Y718548D02*
X288629Y719069D01*
X274689D01*
X271920Y716300D01*
X270505D01*
X268170Y718635D01*
Y721921D01*
X262513Y727578D01*
X261940D01*
Y727581D01*
G01X266440D02*
Y726339D01*
X269240Y723539D01*
Y721375D01*
X270347Y720268D01*
X291976D01*
X293300Y718944D01*
G01X270940Y727581D02*
Y722080D01*
G01X261940Y730731D02*
X259850Y732821D01*
Y740678D01*
X261403Y742231D01*
X261940D01*
G01X266440Y730731D02*
X264250Y732921D01*
Y740811D01*
X265670Y742231D01*
X266440D01*
G01X270940Y730731D02*
X268470Y733201D01*
Y741522D01*
X269179Y742231D01*
X270940D01*
G01X275440Y730731D02*
Y731250D01*
X273240Y733450D01*
Y740031D01*
X275440Y742231D01*
G01X263430Y770417D02*
Y767929D01*
X261940Y766439D01*
Y742231D01*
G01X266440D02*
Y771513D01*
X264340Y773613D01*
Y778780D01*
G01X272175Y783074D02*
Y747096D01*
X270940Y745861D01*
Y742231D01*
G01X259902Y807872D02*
Y796160D01*
X262090Y793972D01*
Y771757D01*
X263430Y770417D01*
G01X263839Y807872D02*
Y779281D01*
X264340Y778780D01*
G01X267776Y807872D02*
Y787473D01*
X272175Y783074D01*
G01X278660Y6643D02*
Y10073D01*
G01Y6643D02*
X278653Y6636D01*
G01X282553Y6670D02*
X278687D01*
X278660Y6643D01*
G01Y10073D02*
X278011Y10722D01*
X274972D01*
G01Y13872D02*
Y16378D01*
X274990Y16396D01*
G01Y19572D02*
Y16396D01*
G01X274900Y248663D02*
X275738Y249501D01*
Y250674D01*
X276268Y251204D01*
Y251914D01*
X276904Y252550D01*
G01X279265Y252157D02*
Y249582D01*
X280431Y248416D01*
Y239087D01*
X279161Y237817D01*
G01X286426Y266051D02*
X287704D01*
X291671Y262084D01*
X292934D01*
X294555Y260463D01*
Y251206D01*
X296176Y249585D01*
G01X283716Y261364D02*
Y261372D01*
X282166Y262922D01*
G01X277119Y257697D02*
X277373D01*
X278811Y259135D01*
G01X277119Y260697D02*
X279336Y262914D01*
Y264795D01*
G01X288603Y263175D02*
X289312D01*
X291332Y261155D01*
X292550D01*
X293527Y260178D01*
Y248799D01*
X295060Y247266D01*
G01X301511Y262204D02*
Y262713D01*
X302460Y263662D01*
Y267151D01*
X295849Y273762D01*
X291585D01*
X291284Y274063D01*
X289920D01*
G01X287014Y273939D02*
X288226Y272727D01*
X295041D01*
X300477Y267291D01*
Y265010D01*
G01X300070Y276386D02*
X298960Y277496D01*
X296810D01*
X295307Y278999D01*
X291691D01*
X291002Y279688D01*
X285720D01*
X285141Y279109D01*
Y277664D01*
X283784Y276307D01*
G01X298131Y274995D02*
X295549Y277577D01*
X291955D01*
X290724Y276346D01*
X288360D01*
G01X277886Y268993D02*
Y269101D01*
X276444Y270543D01*
G01X288603Y280903D02*
X290314D01*
X291860Y282449D01*
X296070D01*
X297810Y280709D01*
G01X280886Y266237D02*
X282309Y267660D01*
Y270435D01*
G01X280886Y268993D02*
Y269101D01*
X279444Y270543D01*
G01X285603Y281103D02*
X286833D01*
X288446Y282716D01*
X290899D01*
X291896Y283713D01*
X297810D01*
X301146Y280377D01*
Y279727D01*
X301723Y279150D01*
G01X288377Y268032D02*
X291220D01*
X292710Y266542D01*
G01X276386Y276813D02*
X276394D01*
X277944Y278363D01*
G01X277886Y281877D02*
X277916D01*
X279386Y280407D01*
G01X280886Y281877D02*
X281118Y281645D01*
Y278391D01*
X281767Y277742D01*
G01X284272Y291305D02*
X286028Y293061D01*
Y293442D01*
X287861Y295275D01*
X289040D01*
X289580Y294735D01*
X291142D01*
X291653Y295246D01*
X296356D01*
X298117Y294050D01*
X299917Y292826D01*
X301151Y291987D01*
X301182Y291966D01*
G01X286426Y283779D02*
X288293D01*
X290363Y285849D01*
Y286082D01*
G01X289927Y288143D02*
X290452Y288668D01*
X298911D01*
X300096Y287483D01*
Y284062D01*
X301508Y282650D01*
X301473D01*
G01X289920Y291791D02*
X290073Y291638D01*
X294054D01*
X294382Y291966D01*
G01X287014Y291667D02*
X285748Y290401D01*
Y286337D01*
X286132Y285953D01*
G01X280886Y284633D02*
Y287856D01*
X281318Y288288D01*
Y290287D01*
X281818Y290787D01*
G01X276386Y289697D02*
Y289419D01*
X278918Y286887D01*
G01X277886Y284633D02*
Y284678D01*
X276598Y285967D01*
X276444Y286120D01*
Y286183D01*
G01X277886Y300273D02*
Y301432D01*
X277020Y302298D01*
G01X284272Y309033D02*
X283456Y308217D01*
X282337D01*
G01X288377Y303488D02*
Y302181D01*
X290037Y300521D01*
X294692D01*
X296223Y298990D01*
X299788D01*
X306317Y292461D01*
X306782D01*
G01X288360Y311802D02*
X290722D01*
X291424Y312504D01*
X299689D01*
X301795Y310398D01*
G01X287014Y305895D02*
X288290Y307171D01*
X290466D01*
X290832Y306805D01*
X294607D01*
X295405Y306007D01*
X305463D01*
X307204Y304266D01*
G01X287014Y309395D02*
X287188D01*
X288555Y308028D01*
X292019D01*
X292419Y307628D01*
X296210D01*
X296639Y308057D01*
G01X283521Y303607D02*
X283832D01*
X285126Y302312D01*
Y300546D01*
X285541Y300131D01*
X288986D01*
X289627Y299490D01*
X289915D01*
X292074Y297331D01*
X298349D01*
X305617Y290063D01*
X321890D01*
X324441Y292614D01*
G01X284272Y306277D02*
X286050Y304499D01*
X287549D01*
X287838Y304788D01*
X288916D01*
X289324Y304380D01*
X290309D01*
X291911Y302778D01*
X295453D01*
X295653Y302978D01*
X296584D01*
X297903Y304297D01*
X303197D01*
G01X283784Y311763D02*
X282760D01*
X281859Y310862D01*
G01X276386Y308093D02*
Y308248D01*
X277816Y309678D01*
G01X276386Y305337D02*
X277160D01*
X279228Y303269D01*
X279754D01*
G01X289927Y323599D02*
X290797Y324469D01*
X299220D01*
X300157Y325406D01*
X304830D01*
X310285Y330861D01*
X313847D01*
X314550Y331564D01*
G01X289920Y327247D02*
X291301Y325866D01*
X297560D01*
X300860Y329166D01*
X305160D01*
X310005Y334011D01*
X317452D01*
X318480Y335039D01*
G01X280886Y328797D02*
X280269D01*
X279025Y330041D01*
X277241D01*
X276586Y330696D01*
Y333580D01*
X277288Y334282D01*
G01X276386Y320977D02*
X277466D01*
X278735Y322246D01*
X279694D01*
X281690Y324242D01*
X282167D01*
G01X287014Y323623D02*
X288064D01*
X289288Y322399D01*
X290566D01*
X291490Y323323D01*
X296050D01*
X296937Y322436D01*
X306480D01*
X309931Y325887D01*
X311692D01*
X311740Y325839D01*
G01X284272Y326761D02*
X285690Y325343D01*
X288466D01*
G01X276386Y323733D02*
Y323739D01*
X275517Y324608D01*
Y325842D01*
G01X284272Y324005D02*
Y323426D01*
X285704Y321994D01*
Y321809D01*
G01X285603Y334287D02*
X286718D01*
X287918Y335487D01*
X292476D01*
X294999Y338010D01*
X298395D01*
X300320Y339935D01*
Y354324D01*
X305446Y359450D01*
G01X280886Y331553D02*
X282741D01*
X283218Y331076D01*
X284179D01*
X286071Y329184D01*
G01X279386Y336617D02*
X279488D01*
X282234Y333871D01*
Y333792D01*
G01X283521Y339063D02*
X285794D01*
G01X279115Y341979D02*
X280223D01*
X281205Y340997D01*
G01X288603Y334087D02*
X290718D01*
X291618Y333187D01*
X295032D01*
X297146Y335301D01*
X298374D01*
X302599Y339526D01*
Y351127D01*
X305848Y354376D01*
X307420D01*
G01X297073Y329159D02*
X296039Y330193D01*
X289812D01*
X288350Y331655D01*
X286596D01*
G01X288577Y339044D02*
Y340734D01*
X289191Y341348D01*
G01X283716Y332276D02*
X284028Y332588D01*
X285690D01*
X286057Y332955D01*
X287377D01*
X287447Y332885D01*
X290720D01*
X291695Y331910D01*
X295289D01*
X296894Y333515D01*
X298334D01*
X303867Y339048D01*
Y344837D01*
X307410Y348380D01*
G01X276729Y382323D02*
X278744Y380308D01*
Y377876D01*
X277040Y376172D01*
G01X288729Y379173D02*
X288342D01*
X284550Y375381D01*
Y375090D01*
X284440Y374980D01*
Y372090D01*
X279863Y367513D01*
G01X292729Y379173D02*
X291619D01*
X288629Y376183D01*
X288331D01*
X286550Y374402D01*
G01X284729Y379173D02*
Y378676D01*
X282336Y376283D01*
Y374037D01*
X281450Y373151D01*
G01X293142Y369023D02*
X289142D01*
G01D02*
Y365600D01*
X287993Y364451D01*
G01X274625Y399203D02*
Y403203D01*
G01X286710Y398785D02*
X287067Y399142D01*
Y402358D01*
G01D02*
X284492Y404933D01*
X279910D01*
X279909Y404932D01*
X276354D01*
X274625Y403203D01*
G01X288747Y501022D02*
X291897Y497872D01*
G01X282448Y504171D02*
X284024Y502595D01*
G01X288747Y504171D02*
X290323Y502595D01*
G01X276149Y507321D02*
Y506902D01*
X277318Y505733D01*
X284010D01*
X285598Y507321D01*
G01X279298Y513620D02*
X277708Y512030D01*
Y509453D01*
X276659Y508404D01*
Y507831D01*
X276149Y507321D01*
G01X285598D02*
Y507253D01*
X287058Y505793D01*
X294778D01*
X296298Y504273D01*
X304478D01*
X305708Y503043D01*
G01X279298Y548266D02*
Y548267D01*
X280872Y549841D01*
G01X276149Y560864D02*
Y561893D01*
X277698Y563442D01*
Y572483D01*
X279658Y574443D01*
G01X285530Y573002D02*
X280312Y567784D01*
X280308D01*
X279298Y566774D01*
Y564014D01*
G01Y554565D02*
X279300D01*
X280874Y556139D01*
G01X288747Y551415D02*
X288748D01*
X290322Y549841D01*
G01X278109Y582978D02*
Y577102D01*
X279658Y575553D01*
Y574443D01*
G01X282309Y582978D02*
Y578681D01*
X285530Y575460D01*
Y573002D01*
G01X293843Y642536D02*
Y641376D01*
X292913Y640446D01*
X288366D01*
X280695Y648117D01*
X276201D01*
G01X293286Y647144D02*
Y649828D01*
X292228Y650886D01*
X289819D01*
X287997Y649064D01*
G01X280880Y650295D02*
X278933D01*
X277014Y652214D01*
X276201D01*
G01X284428Y654034D02*
Y652951D01*
X281772Y650295D01*
X280880D01*
G01X284428Y656002D02*
X279188D01*
X278699Y656491D01*
G01D02*
X276201D01*
G01X284428Y665845D02*
X289365D01*
G01D02*
X293979D01*
X295820Y667686D01*
Y679600D01*
X292970Y682450D01*
G01X284428Y673719D02*
X289365D01*
G01X274360Y673831D02*
X276921D01*
X280970Y669782D01*
X284428D01*
G01Y667813D02*
X293490D01*
X294068Y668391D01*
X294120D01*
G01X284428Y681593D02*
X275710D01*
G01X284428Y679624D02*
X288352D01*
X289248Y680520D01*
Y680521D01*
G01X284428Y675688D02*
X279843D01*
G01X284428Y677656D02*
X289074D01*
X289622Y677108D01*
X293068D01*
G01X284428Y697341D02*
X287504D01*
X288950Y698787D01*
Y701991D01*
X286798Y704143D01*
G01X284428Y701278D02*
Y702515D01*
X281850Y705093D01*
X278370D01*
G01X284428Y693404D02*
X281393D01*
X279074Y695723D01*
X277475D01*
G01X275440Y727581D02*
Y722581D01*
X275880Y722141D01*
G01X284440Y727581D02*
X285850Y725466D01*
Y722298D01*
X285880Y722268D01*
G01X285666Y717269D02*
X287064Y715871D01*
X292499D01*
X293286Y715084D01*
Y708168D01*
G01X284440Y730731D02*
X283802D01*
X282140Y732393D01*
Y740481D01*
X283936Y742277D01*
X284394D01*
G01X279940Y739081D02*
Y735075D01*
X280210Y734805D01*
G01D02*
X279940Y734535D01*
Y730731D01*
G01X288940D02*
Y734246D01*
X288390Y734796D01*
G01D02*
X288820Y735226D01*
Y738961D01*
X288940Y739081D01*
G01X275440Y742231D02*
X275627Y742418D01*
Y777692D01*
G01X281930Y773190D02*
X279940Y771200D01*
Y742231D01*
G01X286722Y785929D02*
Y747270D01*
X284394Y744942D01*
Y742277D01*
G01D02*
X284440Y742231D01*
G01X288940D02*
Y745235D01*
X291370Y747665D01*
Y771217D01*
G01X275650Y807872D02*
Y777715D01*
X275627Y777692D01*
G01X279587Y807872D02*
Y794917D01*
X281470Y793034D01*
Y773650D01*
X281930Y773190D01*
G01X291370Y771217D02*
Y784059D01*
X287461Y787968D01*
Y807872D01*
G01X283524D02*
Y798097D01*
X285050Y796571D01*
Y787601D01*
X286722Y785929D01*
G01X290576Y266365D02*
X292154Y264787D01*
X295618D01*
X296763Y263642D01*
Y253740D01*
X296210Y253187D01*
G01X290576Y284093D02*
X291157Y284674D01*
X296139D01*
X298332Y286867D01*
G01X313323Y295851D02*
X305165D01*
X301226Y299790D01*
Y299849D01*
X300201Y300874D01*
G01X313173Y307843D02*
X308699D01*
X306200Y310342D01*
X305250D01*
G01X292323Y310895D02*
X292864Y311436D01*
X298360D01*
X301133Y308663D01*
X303571D01*
X305250Y310342D01*
G01X313435Y299946D02*
X306615D01*
X303197Y303364D01*
Y304297D01*
G01X298452Y340487D02*
X298008Y340931D01*
Y355251D01*
X303150Y360393D01*
Y360406D01*
X305080Y362336D01*
X305090D01*
X306200Y363446D01*
X307030D01*
X311657Y368073D01*
X313222Y374229D01*
G01X313242Y338320D02*
X312869Y338693D01*
X308487D01*
X304484Y334690D01*
X302721D01*
X299410Y331379D01*
Y331201D01*
G01X290366Y331447D02*
X290766Y331047D01*
X299256D01*
X299410Y331201D01*
G01X311015Y362506D02*
Y361128D01*
X309337Y359450D01*
X305446D01*
G01X309142Y369023D02*
Y368933D01*
X306215Y366006D01*
X305331D01*
X299137Y359812D01*
X295527D01*
G01X301142Y369023D02*
X297142D01*
G01D02*
Y367841D01*
X293606Y364305D01*
G01X305142Y369023D02*
X309142D01*
G01X291897Y497872D02*
Y501022D01*
G01D02*
X298129D01*
X299028Y500123D01*
X305138D01*
X305708Y500693D01*
Y503043D01*
G01X291897Y554565D02*
X295047D01*
G01X304410Y572782D02*
X304440Y572812D01*
Y573985D01*
X314794Y584339D01*
X320942D01*
X330960Y594357D01*
Y621664D01*
X329110Y623514D01*
G01X291318Y647144D02*
Y643537D01*
X292313Y642542D01*
X293843D01*
Y642536D01*
G01X303110Y639381D02*
Y641003D01*
X305097Y642990D01*
Y647144D01*
G01X297394Y657033D02*
Y654906D01*
X297223Y654735D01*
Y647144D01*
G01X299192D02*
Y662608D01*
X300880Y664296D01*
G01X303129Y647144D02*
Y650527D01*
X303060Y650596D01*
Y659324D01*
X302780Y659604D01*
X302772D01*
G01X301160Y647144D02*
Y651983D01*
X301360Y652183D01*
G01X295890Y662662D02*
Y660466D01*
X295255Y659831D01*
Y647144D01*
G01X297770Y674720D02*
Y670798D01*
X304480Y664088D01*
Y658565D01*
X306900Y656145D01*
Y651976D01*
X305097Y650173D01*
Y647144D01*
G01X296858Y702544D02*
Y702538D01*
X295600Y701280D01*
Y694580D01*
X300680Y689500D01*
Y674365D01*
X306189Y668856D01*
X306999D01*
X320852Y655003D01*
X326619D01*
X328760Y657144D01*
G01X297300Y697221D02*
Y694633D01*
X302720Y689213D01*
Y676325D01*
X306189Y672856D01*
X307005D01*
X309301Y670560D01*
X311556D01*
X317567Y664549D01*
X321924D01*
X324090Y662383D01*
X329912D01*
G01X320846Y647144D02*
Y653064D01*
X308454Y665456D01*
X305589D01*
X299470Y671575D01*
Y686000D01*
X295950Y689520D01*
G01X296858Y702544D02*
X299192Y704878D01*
Y708168D01*
G01X301160D02*
Y703917D01*
X299440Y702197D01*
Y700540D01*
X297300Y698400D01*
Y697221D01*
G01X293286Y703504D02*
Y708168D01*
G01X305990Y697189D02*
Y701270D01*
X303129Y704131D01*
Y708168D01*
G01X305097D02*
Y713005D01*
X303681Y714421D01*
G01X296717Y721080D02*
Y718227D01*
X296885Y718059D01*
G01D02*
X295250Y716424D01*
Y711528D01*
X295255Y711523D01*
Y708168D01*
G01X300799Y717212D02*
X298727D01*
X297223Y715708D01*
Y715523D01*
G01D02*
X297220D01*
Y711108D01*
X297223D01*
Y708168D01*
G01X291318Y713875D02*
Y708168D01*
G01X293440Y730731D02*
Y734514D01*
X293990Y735064D01*
Y735071D01*
X295640Y736721D01*
Y740031D01*
X293440Y742231D01*
G01X302440D02*
X304860Y739811D01*
Y735447D01*
X303571Y734158D01*
X303161D01*
X302810Y733807D01*
G01X297940Y730731D02*
Y733019D01*
X298590Y733669D01*
G01D02*
X299860Y734939D01*
Y737194D01*
X298865Y738189D01*
X298832D01*
X297940Y739081D01*
G01X293440Y727581D02*
Y725120D01*
X293480Y725080D01*
G01X293440Y742231D02*
Y744462D01*
X295312Y746334D01*
Y786057D01*
X295100Y786269D01*
G01X297940Y742231D02*
Y751654D01*
X299249Y752963D01*
Y771403D01*
G01X304740Y777277D02*
Y749470D01*
X302440Y747170D01*
Y742231D01*
G01X291370Y771217D02*
X291340D01*
G01X299249Y771403D02*
Y784583D01*
X301050Y786384D01*
Y794936D01*
X299272Y796714D01*
Y807872D01*
G01X303209D02*
Y790002D01*
X304740Y788471D01*
Y777277D01*
G01X295335Y807872D02*
Y786504D01*
X295100Y786269D01*
G01X310850Y99620D02*
X306497Y103973D01*
Y114763D01*
G01X325970Y98817D02*
X318860Y105927D01*
X313183D01*
X308859Y110251D01*
Y114763D01*
G01X320374Y292653D02*
X320182Y292461D01*
X314113D01*
X314102Y292472D01*
X313026D01*
X313015Y292461D01*
X306782D01*
G01X307204Y304212D02*
Y304266D01*
G01X313324Y303888D02*
X313288Y303924D01*
X307546D01*
X307204Y304266D01*
G01X316075Y326386D02*
X312287D01*
X311740Y325839D01*
G01X325700Y330871D02*
X321120D01*
X321110Y330861D01*
G01D02*
X315253D01*
X314550Y331564D01*
G01X305880Y339046D02*
X306725D01*
X310097Y342418D01*
X313242D01*
G01D02*
Y346376D01*
G01X325700Y334801D02*
X324910Y334011D01*
X321110D01*
G01D02*
X319508D01*
X318480Y335039D01*
G01X313242Y346376D02*
Y350376D01*
G01Y358376D02*
Y354376D01*
G01D02*
X307420D01*
G01X319288Y350376D02*
X321551D01*
X324506Y347421D01*
X334353D01*
X339420Y352488D01*
Y354934D01*
X357079Y372593D01*
Y381319D01*
G01X316392Y350376D02*
X319288D01*
G01X313222Y374229D02*
Y378983D01*
G01X306809Y381443D02*
X308615D01*
X310484Y383312D01*
G01X313222Y382133D02*
X311663D01*
X310484Y383312D01*
G01X316938Y407069D02*
X324568D01*
X325254Y407755D01*
G01X322599Y421643D02*
Y419498D01*
X321514Y418413D01*
Y415629D01*
G01X310380Y473942D02*
X311610Y472712D01*
Y432528D01*
G01X307800Y467859D02*
X306050Y466109D01*
Y431168D01*
X307905Y429313D01*
X311530D01*
X313530Y431313D01*
Y436460D01*
G01X315940Y438104D02*
Y449268D01*
X314140Y451068D01*
Y470288D01*
X315980Y472128D01*
G01X307670Y473605D02*
X309500Y471775D01*
Y458990D01*
X308220Y457710D01*
Y432552D01*
G01X327739Y509656D02*
X323160D01*
X320080Y512736D01*
G01D02*
X318288Y514528D01*
Y521500D01*
G01X311003Y647144D02*
Y643001D01*
X310453Y642451D01*
G01X322814Y647144D02*
Y644267D01*
X320822Y642275D01*
X320360D01*
G01X345580Y638109D02*
X342310Y634839D01*
X321364D01*
X317820Y638383D01*
Y643009D01*
X316908Y643921D01*
Y647144D01*
G01X312972D02*
Y642669D01*
X312133Y641830D01*
Y641420D01*
X311382Y640669D01*
Y635432D01*
G01X313230Y702465D02*
X310465D01*
X309034Y703896D01*
Y708168D01*
G01X307113Y713003D02*
X307066Y712956D01*
Y708168D01*
G01X311440Y727581D02*
Y724211D01*
X313433Y722218D01*
X318367D01*
X320260Y720325D01*
Y717043D01*
X319620Y716403D01*
G01X325560Y713391D02*
X327641Y715472D01*
Y720477D01*
X326553Y721565D01*
X322066D01*
X316050Y727581D01*
X315940D01*
G01X311003Y708168D02*
Y712826D01*
X309531Y714298D01*
G01X312972Y708168D02*
Y712693D01*
G01X316908Y708168D02*
Y711171D01*
X318090Y712353D01*
Y712846D01*
G01X311440Y730731D02*
X309640Y732531D01*
Y741353D01*
X310518Y742231D01*
X311440D01*
G01X315940Y730731D02*
X313580Y733091D01*
Y740944D01*
X314867Y742231D01*
X315940D01*
G01X320440Y730731D02*
X317850Y733321D01*
Y740633D01*
X319448Y742231D01*
X320440D01*
G01X307280Y733705D02*
X307360D01*
G01D02*
X307180Y733525D01*
Y730971D01*
X306940Y730731D01*
G01Y739081D02*
X306240Y738381D01*
Y735735D01*
X306500Y735475D01*
Y734565D01*
X307360Y733705D01*
G01X320440Y727581D02*
Y726385D01*
X321930Y724895D01*
G01X311440Y742231D02*
Y776979D01*
X315020Y780559D01*
G01X315940Y742231D02*
Y773833D01*
X320657Y778550D01*
Y779595D01*
G01X320440Y771967D02*
Y742231D01*
G01X307146Y769416D02*
Y766886D01*
X306940Y766680D01*
Y742231D01*
G01X307146Y805904D02*
Y769416D01*
G01X315020Y807872D02*
Y780559D01*
G01X320657Y779595D02*
Y794120D01*
X318957Y795820D01*
Y807872D01*
G01X322894D02*
Y774421D01*
X320440Y771967D01*
G01X332481Y114763D02*
Y118915D01*
X334943Y121377D01*
Y124867D01*
X331583Y128227D01*
Y128717D01*
G01X336495Y290569D02*
X326484D01*
X324441Y292612D01*
Y292614D01*
G01X332348Y310902D02*
Y312735D01*
X333540Y313927D01*
Y315590D01*
G01X325700Y330871D02*
X327114D01*
X329480Y328505D01*
X332490D01*
G01Y338347D02*
X330648D01*
X327102Y334801D01*
X325700D01*
G01X327058Y353801D02*
Y358376D01*
G01X327008Y349221D02*
X325357D01*
X323040Y351538D01*
Y354485D01*
G01X336850Y380332D02*
Y385940D01*
X333620Y389170D01*
Y403497D01*
X329362Y407755D01*
X325254D01*
G01X336850Y380332D02*
X332439D01*
Y380334D01*
G01X326522Y386129D02*
Y385518D01*
X331706Y380334D01*
X332439D01*
G01X331900Y419317D02*
Y412857D01*
X341986Y402771D01*
X355740D01*
X357079Y404110D01*
Y408896D01*
G01X347079Y382282D02*
Y393526D01*
X329579Y411026D01*
X322797D01*
X321910Y410139D01*
G01X322599Y421643D02*
Y425585D01*
G01X331090Y424304D02*
Y421338D01*
X328994Y419242D01*
Y415629D01*
G01X362079Y409953D02*
Y427425D01*
X360519Y428985D01*
X337341D01*
X333960Y425604D01*
Y423271D01*
X336740Y420491D01*
Y417069D01*
G01X322599Y425585D02*
Y429583D01*
G01D02*
Y432505D01*
G01X331302Y426770D02*
Y424516D01*
X331090Y424304D01*
G01X322986Y467109D02*
X323002Y467093D01*
X329986D01*
G01X338762Y479636D02*
X337500D01*
X336264Y480872D01*
X329986D01*
G01Y482841D02*
X339506D01*
G01X329986Y484809D02*
X326170D01*
X325320Y485659D01*
Y494343D01*
X326740Y495763D01*
G01X338057Y492880D02*
Y499337D01*
X335162Y502232D01*
X335160D01*
Y502791D01*
G01X326740Y495763D02*
X326499Y496004D01*
Y505266D01*
X327739Y506506D01*
G01X332512Y506294D02*
X329672Y503454D01*
Y502057D01*
G01X336088Y492880D02*
Y495472D01*
X329672Y501888D01*
Y502057D01*
G01X329986Y486778D02*
Y490174D01*
X330115Y490303D01*
G01X335162Y502791D02*
X335160D01*
G01X337012Y506294D02*
X335160Y504442D01*
Y502791D01*
G01X326170Y518386D02*
Y516752D01*
X332512Y510410D01*
Y509444D01*
G01X330182Y521508D02*
Y520605D01*
X333645Y517142D01*
X335204D01*
X335860Y516486D01*
G01D02*
X337012Y515334D01*
Y509444D01*
G01X336182Y521508D02*
Y520052D01*
X341510Y514724D01*
Y512429D01*
X341512D01*
G01X324182Y521508D02*
Y520374D01*
X326170Y518386D01*
G01X334362Y550203D02*
Y548129D01*
X336688Y545803D01*
Y540978D01*
G01D02*
X339377D01*
X340330Y541931D01*
G01X334362Y562409D02*
Y563868D01*
X336267Y565773D01*
Y569527D01*
G01X340388Y569570D02*
X340345Y569527D01*
X336267D01*
G01X323583Y636439D02*
X327298D01*
X330363Y639504D01*
X330440D01*
G01X328032Y642674D02*
X329413D01*
X330688Y643949D01*
Y647144D01*
G01X337070Y639759D02*
X335977Y640852D01*
X331640D01*
X331288Y641204D01*
X328975D01*
X328745Y640974D01*
X327320D01*
X326332Y641962D01*
Y643458D01*
X326751Y643877D01*
Y647144D01*
G01X324783D02*
Y641645D01*
X326350Y640078D01*
Y638968D01*
G01D02*
X324949D01*
X324328Y639589D01*
X323583D01*
G01X332710Y642694D02*
X334625Y644609D01*
Y647144D01*
G01X335610Y658177D02*
Y656710D01*
X336590Y655730D01*
Y650930D01*
X336594D01*
Y647144D01*
G01X332657D02*
Y655546D01*
X332747Y655636D01*
G01X332190Y659883D02*
X331131Y656320D01*
Y656316D01*
X328720Y650739D01*
Y647144D01*
G01X333180Y665611D02*
Y668482D01*
X332390Y669272D01*
Y683282D01*
X329820Y685852D01*
Y702725D01*
X332650Y705555D01*
Y708168D01*
X332657D01*
G01X334625D02*
Y705053D01*
X333220Y703648D01*
Y700937D01*
X332225Y699942D01*
X332087D01*
X331020Y698875D01*
Y686350D01*
X333590Y683780D01*
Y672284D01*
X335130Y670744D01*
G01X330688Y708168D02*
Y705293D01*
X328620Y703225D01*
Y685354D01*
X331100Y682874D01*
Y664830D01*
X332636Y663294D01*
X334132D01*
X334313Y663113D01*
G01X326751Y708168D02*
Y704769D01*
X326220Y704238D01*
Y683359D01*
X328590Y680989D01*
Y675454D01*
X327244Y674108D01*
X326552D01*
X325555Y673111D01*
Y671705D01*
X327500Y669760D01*
Y667244D01*
G01X324970Y665128D02*
X327789D01*
X329900Y667239D01*
Y682376D01*
X327420Y684856D01*
Y703723D01*
X328720Y705023D01*
Y708168D01*
G01X326890Y676159D02*
X324520Y678529D01*
Y702714D01*
X324120Y703114D01*
G01X324783Y708168D02*
Y703777D01*
X324120Y703114D01*
G01X336110Y693934D02*
X338603Y691441D01*
X345452D01*
Y691436D01*
G01X332720Y698170D02*
X338385Y703835D01*
X339086D01*
X343930Y708679D01*
Y711649D01*
X342980Y712599D01*
Y712994D01*
X341895Y714079D01*
X338385D01*
X335295Y717169D01*
G01X339010Y700406D02*
X337226Y698622D01*
Y695390D01*
X339045Y693571D01*
X340811D01*
X342613Y695373D01*
X345452D01*
G01X335295Y717169D02*
X329974Y722490D01*
X328680D01*
X324940Y726230D01*
Y727581D01*
G01X336594Y708168D02*
Y710708D01*
X338265Y712379D01*
X341190D01*
G01X329440Y727581D02*
Y724433D01*
X329590Y724283D01*
G01X333940Y727581D02*
Y725735D01*
X334640Y725035D01*
G01X324940Y730731D02*
X322870Y732801D01*
Y741122D01*
X323979Y742231D01*
X324940D01*
G01X329440Y730731D02*
X327400Y732771D01*
Y741411D01*
X328220Y742231D01*
X329440D01*
G01X333940Y730731D02*
X331840Y732831D01*
Y741411D01*
X332660Y742231D01*
X333940D01*
G01X324940D02*
Y774640D01*
X326280Y775980D01*
G01X329440Y742231D02*
Y758229D01*
X337800Y766589D01*
Y774677D01*
G01X344710Y785782D02*
Y763348D01*
X333940Y752578D01*
Y742231D01*
G01X326280Y775980D02*
X325970Y776290D01*
Y797870D01*
X326831Y798731D01*
Y807872D01*
G01X349490Y60647D02*
Y57698D01*
G01D02*
X350411Y56777D01*
Y46920D01*
G01X352578Y69305D02*
Y74292D01*
G01X352560Y82480D02*
Y74310D01*
X352578Y74292D01*
G01X349490Y63797D02*
X351349D01*
X353060Y62086D01*
Y61504D01*
G01X364580Y391273D02*
X356841D01*
X352079Y386511D01*
Y382282D01*
G01Y409953D02*
Y408896D01*
G01Y409953D02*
Y419841D01*
X351650Y420270D01*
G01D02*
X351032Y420888D01*
Y424560D01*
G01X345931Y459022D02*
Y456431D01*
X343200Y453700D01*
Y449700D01*
X367300Y425600D01*
X375900D01*
X385700Y415800D01*
Y406800D01*
X380200Y401300D01*
Y387500D01*
X381500Y386200D01*
Y360300D01*
X415800Y326000D01*
X437400D01*
X459700Y303700D01*
X463100D01*
X464810Y305410D01*
Y311253D01*
G01X345270Y452745D02*
X346249D01*
X349868Y456364D01*
Y459022D01*
G01X347899D02*
Y465392D01*
X346759Y466532D01*
X346750D01*
G01X347899Y492880D02*
Y486805D01*
X348220Y486484D01*
G01X350512Y506294D02*
Y503213D01*
X348870Y501571D01*
G01D02*
X347590Y500291D01*
Y499801D01*
X345260Y497471D01*
Y496756D01*
X343962Y495458D01*
Y492880D01*
G01X340025D02*
Y497151D01*
X340902Y498028D01*
Y503742D01*
G01X341994Y492880D02*
Y496540D01*
X343420Y497966D01*
G01X346012Y506294D02*
Y500558D01*
X343420Y497966D01*
G01X376540Y498385D02*
X376235Y498690D01*
X370490D01*
X367412Y501768D01*
X356540D01*
X352555Y497783D01*
X348374D01*
X345931Y495340D01*
Y492880D01*
G01X348182Y521508D02*
Y518884D01*
X350690Y516376D01*
G01X341512Y506294D02*
Y504352D01*
X340902Y503742D01*
G01X341512Y512429D02*
Y509444D01*
G01X350902Y512520D02*
Y512522D01*
X352032Y513652D01*
X354489D01*
X360182Y519345D01*
Y521508D01*
G01X350512Y509444D02*
X350510D01*
Y512130D01*
X350900Y512520D01*
X350902D01*
G01X342182Y521508D02*
Y521454D01*
X346350Y517286D01*
G01X346012Y509444D02*
Y516948D01*
X346350Y517286D01*
G01X352940Y518025D02*
X354182Y519267D01*
Y521508D01*
G01X342190Y565848D02*
Y567768D01*
X340388Y569570D01*
G01X348480Y638558D02*
X344630Y642408D01*
Y646781D01*
X346039Y648190D01*
Y650031D01*
X345452Y650618D01*
Y654034D01*
G01X340669Y644827D02*
X338562Y646934D01*
Y647144D01*
G01X345452Y656002D02*
X341539D01*
X340630Y655093D01*
G01X351730Y649206D02*
Y649214D01*
X349102Y651842D01*
Y656842D01*
X347973Y657971D01*
X345452D01*
G01X365380Y668972D02*
X363321Y666913D01*
X356092D01*
X354607Y665428D01*
X353197D01*
X352275Y666350D01*
X348730D01*
Y666345D01*
X348230Y665845D01*
X345452D01*
G01X355955Y663128D02*
X352052D01*
X351730Y663450D01*
G01X345452Y663876D02*
X351304D01*
X351730Y663450D01*
G01X345452Y673719D02*
X341530D01*
X340530Y674719D01*
Y675658D01*
G01X365160Y672922D02*
X365076Y673006D01*
X350597D01*
X349341Y671750D01*
X345452D01*
G01X351720Y670018D02*
X351484Y669782D01*
X345452D01*
G01X361760Y668716D02*
X361648Y668828D01*
X353190D01*
X352175Y667813D01*
X345459D01*
X345452Y667806D01*
Y667813D01*
G01Y677656D02*
X339715D01*
X337780Y675721D01*
Y672319D01*
X338970Y671129D01*
Y670776D01*
G01X345452Y675688D02*
X352528D01*
X353449Y674767D01*
X355590D01*
X355953Y675130D01*
G01X337798Y686721D02*
Y685890D01*
X340126Y683562D01*
X345452D01*
G01X364649Y684022D02*
X363600Y682973D01*
X360439D01*
X357469Y685943D01*
X355555D01*
X354726Y685114D01*
X351648D01*
X348127Y681593D01*
X345452D01*
G01Y679624D02*
X350787D01*
X354906Y683743D01*
X356515D01*
G01X364765Y687963D02*
X363930Y687128D01*
X357985D01*
X357970Y687143D01*
X355049D01*
X354338Y686432D01*
X350075D01*
X349173Y685530D01*
X345452D01*
G01X364115Y692990D02*
X364053Y692928D01*
X348625D01*
X348149Y693404D01*
X345452D01*
G01Y697341D02*
X348136D01*
X353923Y703128D01*
X355955D01*
G01X339750Y695271D02*
X340501D01*
X342571Y697341D01*
X345452D01*
G01Y695373D02*
X348039D01*
X351794Y699128D01*
X355955D01*
G01X338926Y697752D02*
X341284D01*
X342842Y699310D01*
X345452D01*
G01X367520Y701710D02*
X360303Y708927D01*
X356921D01*
X356770Y709078D01*
X351330D01*
X345452Y703200D01*
Y701278D01*
G01X357096Y723537D02*
X353805D01*
X352400Y722132D01*
G01X339300Y716800D02*
X360542D01*
X364810Y721068D01*
Y724327D01*
X365805Y725322D01*
X371501D01*
X372486Y726307D01*
Y727459D01*
G01X342230Y720936D02*
X343197D01*
X347440Y725179D01*
Y727581D01*
G01X355955Y711128D02*
X355980D01*
X353145Y713963D01*
X352010D01*
G01D02*
Y713968D01*
G01X338562Y708168D02*
Y708497D01*
X339449Y709384D01*
X342230D01*
G01X347606Y710199D02*
X347980D01*
X351744Y713963D01*
X352010D01*
G01X338440Y742231D02*
X340360Y740311D01*
Y740281D01*
X340640Y740001D01*
Y734874D01*
X340360Y734594D01*
Y732802D01*
X338440Y730882D01*
Y730731D01*
G01X347440D02*
Y734750D01*
X344740Y737450D01*
Y739993D01*
X345670Y740923D01*
Y740961D01*
X346940Y742231D01*
G01X338440Y727581D02*
X338460Y727561D01*
Y724585D01*
G01X342940Y739081D02*
Y736652D01*
X345610Y733982D01*
G01X342940Y730731D02*
Y731312D01*
X345610Y733982D01*
G01X351940Y730731D02*
Y731417D01*
X354060Y733537D01*
Y734790D01*
G01X350940Y739081D02*
X351648D01*
X354060Y736669D01*
Y734790D01*
G01X338440Y742231D02*
Y751151D01*
X348820Y761531D01*
Y783352D01*
X350450Y784982D01*
G01X354870Y771388D02*
X353960Y770478D01*
Y761564D01*
X342940Y750544D01*
Y742231D01*
G01X360160Y775523D02*
Y764990D01*
X346560Y751390D01*
Y742611D01*
X346940Y742231D01*
G01X350940D02*
X348700Y744471D01*
Y750031D01*
X362260Y763591D01*
Y780263D01*
X363300Y781303D01*
G01X357096Y739537D02*
X356979D01*
X350794Y745722D01*
X350720D01*
G01X337800Y774677D02*
X339900Y776777D01*
Y797908D01*
X338642Y799166D01*
Y807872D01*
G01X350450Y784982D02*
Y787040D01*
X350453D01*
Y807872D01*
G01X342579D02*
Y787913D01*
X344710Y785782D01*
G01X363025Y15721D02*
Y12926D01*
G01X366159Y30188D02*
Y21822D01*
G01X366175Y15721D02*
X366159Y15737D01*
Y21822D01*
G01X361930Y60031D02*
X361314Y60647D01*
X358940D01*
G01X358285Y46920D02*
Y53262D01*
X361930Y56907D01*
Y60031D01*
G01X370053Y60823D02*
X367681D01*
X367300Y60442D01*
G01X366159Y46920D02*
Y54427D01*
X367300Y55568D01*
Y60442D01*
G01X358940Y63797D02*
X365010D01*
X365670Y64457D01*
Y64458D01*
G01X369934Y326749D02*
X367150D01*
X366874Y326473D01*
X365026D01*
G01X368743Y370508D02*
Y377331D01*
X370110Y378698D01*
Y385743D01*
X364580Y391273D01*
G01X357079Y382282D02*
Y381319D01*
G01Y408896D02*
Y409953D01*
G01X362079Y408896D02*
Y409953D01*
G01X358210Y449494D02*
X356633D01*
X354565Y451562D01*
G01X353805Y459022D02*
Y452322D01*
X354565Y451562D01*
G01X354750Y445325D02*
X355769Y446344D01*
X358210D01*
G01X363844Y467093D02*
X370737D01*
X373834Y463996D01*
X375190D01*
G01X363844Y465124D02*
X368774D01*
X369507Y464391D01*
G01X371080Y481589D02*
X367860Y484809D01*
X363844D01*
G01X371412Y524166D02*
Y522380D01*
X370371Y521339D01*
Y517833D01*
X368916Y516378D01*
X368238D01*
G01X368943Y512473D02*
X366051Y509581D01*
Y506370D01*
X370870Y501551D01*
X387629D01*
X388982Y500198D01*
Y496939D01*
G01X368238Y516378D02*
Y515053D01*
X368943Y514348D01*
Y512473D01*
G01X361298Y638032D02*
Y640993D01*
X358125Y644166D01*
X356817D01*
G01X373218Y634217D02*
X371728Y635707D01*
X367531D01*
G01D02*
X367477Y635653D01*
Y630813D01*
G01X357298Y629232D02*
X358598D01*
X361499Y632133D01*
X364724D01*
X366044Y630813D01*
X367477D01*
G01X370283Y646156D02*
X366870D01*
X365990Y645276D01*
Y645272D01*
G01X367870Y650239D02*
X369397D01*
X369480Y650156D01*
X370283D01*
G01X363340Y650512D02*
X360347Y647519D01*
X359900D01*
X356817Y644436D01*
Y644166D01*
G01X370283Y674214D02*
X370282D01*
X368200Y672132D01*
G01X370283Y670156D02*
X370123D01*
X368100Y668133D01*
G01X361810Y675011D02*
X361712Y675109D01*
X360339D01*
X360318Y675130D01*
X359103D01*
G01X359105Y663128D02*
X365561D01*
X365620Y663069D01*
G01X365090Y676923D02*
X356640D01*
X355953Y676236D01*
Y675130D01*
G01X370283Y682248D02*
X368804D01*
X367650Y681094D01*
X367066D01*
G01X364320Y680434D02*
X362657Y678771D01*
X360506D01*
X360144Y679133D01*
X359103D01*
G01X355953D02*
Y679977D01*
X357486Y681510D01*
Y682772D01*
X356515Y683743D01*
G01X359105Y707128D02*
Y706186D01*
X358291Y705372D01*
X357190D01*
X355955Y704137D01*
Y703128D01*
G01X355962Y695128D02*
Y699121D01*
X355955Y699128D01*
G01X357096Y727537D02*
X355684D01*
X354520Y728701D01*
G01X360246Y735537D02*
X363311D01*
X363460Y735388D01*
G01X366860Y739956D02*
Y738015D01*
X369336Y735539D01*
Y735459D01*
G01X370138Y807872D02*
Y786941D01*
X365150Y781953D01*
Y749625D01*
X364090Y748565D01*
G01D02*
X365150Y747505D01*
Y744177D01*
X369336Y739991D01*
Y739459D01*
G01Y743459D02*
Y746361D01*
X367904Y747793D01*
Y778327D01*
G01X357610Y748302D02*
Y747966D01*
X357096Y747452D01*
Y743537D01*
G01X354870Y771388D02*
Y787737D01*
X356090Y788957D01*
Y792218D01*
X354390Y793918D01*
Y807872D01*
G01X358327D02*
Y785499D01*
X360160Y783666D01*
Y775523D01*
G01X362264Y807872D02*
Y782339D01*
X363300Y781303D01*
G01X367904Y778327D02*
Y782454D01*
X374075Y788625D01*
Y807872D01*
G01X381907Y30188D02*
Y21507D01*
G01X383280Y59940D02*
X384526Y61186D01*
X386999D01*
G01X381907Y46920D02*
Y54491D01*
X383280Y55864D01*
Y59940D01*
G01X379051Y60991D02*
X376006D01*
G01D02*
Y56110D01*
X374033Y54137D01*
Y46920D01*
G01X379051Y64141D02*
X383247D01*
G01X370053Y63973D02*
X373560D01*
G01X370276Y114763D02*
Y120069D01*
X375297Y125090D01*
X378003D01*
X378183Y124910D01*
Y124904D01*
G01X377414Y326749D02*
Y324286D01*
X382543Y319157D01*
X384248D01*
G01X369934Y322946D02*
Y326749D01*
G01X373674Y334623D02*
Y332168D01*
X372080Y330574D01*
G01X382680Y408202D02*
X371896Y397418D01*
Y370511D01*
X371893Y370508D01*
G01X375190Y463996D02*
Y466805D01*
X374920Y467075D01*
X374911D01*
G01X378061D02*
X381143D01*
X381239Y467171D01*
G01X373218Y629998D02*
Y634217D01*
G01X377218Y638798D02*
X381195D01*
X382580Y637413D01*
G01X386464Y637117D02*
X382876D01*
X382580Y637413D01*
G01X384758Y650239D02*
X379492D01*
G01X373433Y650156D02*
X379409D01*
X379492Y650239D01*
G01X373433Y646156D02*
X376089D01*
G01X384758Y647739D02*
X377672D01*
X376089Y646156D01*
G01X370283Y666156D02*
Y665814D01*
X373680Y662417D01*
G01X373433Y670156D02*
X376087D01*
G01X384758Y672942D02*
X381462D01*
X378676Y670156D01*
X376087D01*
G01X384758Y677942D02*
X382157D01*
X379461Y675246D01*
G01X373433Y674214D02*
X374465Y675246D01*
X379461D01*
G01X373433Y666156D02*
X379462D01*
G01X384758Y670442D02*
X382215D01*
X379462Y667689D01*
Y666156D01*
G01X384758Y685442D02*
X380155D01*
X378628Y683915D01*
X378092D01*
G01X373433Y682248D02*
X375099D01*
X376766Y683915D01*
X378092D01*
G01X373433Y686248D02*
Y690248D01*
G01D02*
Y691238D01*
X375439Y693244D01*
X376681D01*
X377681Y694244D01*
G01D02*
X379593Y696156D01*
X385118D01*
G01X373433Y698248D02*
X374492D01*
X377412Y701168D01*
X377679D01*
G01X373433Y694248D02*
Y698248D01*
G01X377679Y701168D02*
X377878Y700969D01*
X384938D01*
X385118Y701149D01*
Y701156D01*
G01X373433Y702248D02*
Y706247D01*
G01D02*
X373443Y706237D01*
X377669D01*
G01X373433Y706248D02*
Y706247D01*
G01X377669Y706237D02*
X377868Y706038D01*
X385008D01*
X385118Y706148D01*
Y706156D01*
G01X369428Y723622D02*
Y722990D01*
X372110Y720308D01*
G01X372486Y731459D02*
X375548D01*
G01X372486Y727459D02*
X375834D01*
G01X372578Y723622D02*
X377074D01*
X377840Y724388D01*
G01X376770Y734898D02*
Y734899D01*
X376210Y735459D01*
X372486D01*
G01X373500Y748457D02*
X373496D01*
X372486Y747447D01*
Y743459D01*
G01X397655Y30188D02*
Y21336D01*
G01X392250Y59899D02*
Y59074D01*
X389781Y56605D01*
Y46920D01*
G01X389690Y60665D02*
Y62729D01*
X388083Y64336D01*
X386999D01*
G01X397790Y61360D02*
Y58796D01*
X397655Y58661D01*
Y46920D01*
G01X390355Y82480D02*
Y75775D01*
G01X390221Y69643D02*
Y75641D01*
X390355Y75775D01*
G01X395080Y64510D02*
X398239D01*
X401310Y61439D01*
G01X395080Y61360D02*
X397790D01*
G01X408790Y317049D02*
X386448Y294707D01*
Y257130D01*
X397988Y245590D01*
X403763D01*
X407804Y249631D01*
X412330D01*
G01Y251599D02*
X406988D01*
X402879Y247490D01*
X398781D01*
X388348Y257923D01*
Y292452D01*
X411240Y315344D01*
Y316482D01*
G01X412330Y287032D02*
X406489D01*
X397468Y278011D01*
Y273271D01*
X396258Y272061D01*
Y265621D01*
X399598Y262281D01*
Y260251D01*
G01X412330Y290969D02*
X407956D01*
X396158Y279171D01*
Y273801D01*
X394958Y272601D01*
Y264481D01*
X396758Y262681D01*
Y253841D01*
X398258Y252341D01*
G01X434882Y298843D02*
X427076D01*
X420718Y305201D01*
X405738D01*
X390248Y289711D01*
Y267311D01*
X394378Y263181D01*
Y260501D01*
G01X412330Y273253D02*
X407726D01*
X406148Y274831D01*
X404378D01*
X399488Y269941D01*
Y266511D01*
X404738Y261261D01*
Y260421D01*
G01X412330Y275222D02*
X407697D01*
X406788Y276131D01*
X403838D01*
X398188Y270481D01*
Y265771D01*
X402508Y261451D01*
Y253691D01*
X402948Y253251D01*
G01X412330Y285064D02*
X406431D01*
X399628Y278261D01*
Y275231D01*
X399608Y275211D01*
G01X412330Y292938D02*
X408075D01*
X402177Y287040D01*
X401183D01*
X398222Y290001D01*
X397228D01*
X396524Y289297D01*
Y288303D01*
X399485Y285342D01*
Y284348D01*
X393658Y278521D01*
Y276731D01*
X392508Y275581D01*
G01X412330Y298843D02*
X403640D01*
X398038Y293241D01*
Y292571D01*
G01X434882Y296875D02*
X426964D01*
X420558Y303281D01*
X405778D01*
X393458Y290961D01*
Y282931D01*
G01X400026Y524091D02*
X398398D01*
X396558Y522251D01*
G01X399837Y519447D02*
Y521138D01*
X399454Y521521D01*
X397288D01*
X396558Y522251D01*
G01X396470Y527847D02*
X396638Y528015D01*
X400064D01*
G01D02*
X403304Y531255D01*
Y532016D01*
G01X395656Y519447D02*
X394555Y520548D01*
Y525932D01*
X396470Y527847D01*
G01X396520Y567444D02*
Y564539D01*
X394890Y562909D01*
Y548605D01*
X399885Y543610D01*
X400599D01*
X403387Y540822D01*
Y540127D01*
G01X393596Y567630D02*
Y567506D01*
X391147Y565057D01*
Y556693D01*
X392720Y555120D01*
Y540235D01*
X394655Y538300D01*
X402168D01*
X403187Y537281D01*
Y536127D01*
G01X397743Y628233D02*
Y624115D01*
X397749Y624109D01*
G01X401353Y624007D02*
X401251Y624109D01*
X397749D01*
G01X395227Y640615D02*
Y642542D01*
X394380Y643389D01*
G01X390482Y640267D02*
Y641459D01*
X392412Y643389D01*
X394380D01*
G01X395227Y633135D02*
X401689D01*
X402973Y631851D01*
X406100D01*
G01X406358Y645239D02*
X403683D01*
X401579Y643135D01*
X398070D01*
X395146Y646059D01*
X390210D01*
X389856Y645705D01*
G01X390482Y637117D02*
X386464D01*
G01X406358Y655239D02*
X400117D01*
X400068Y655288D01*
X398658D01*
X398609Y655239D01*
X398376D01*
X396366Y653229D01*
G01X406358Y652739D02*
X401205D01*
X399223Y650757D01*
Y644930D01*
G01X384758Y655239D02*
X388524D01*
X389856Y653907D01*
Y645705D01*
G01X384758Y662739D02*
X390615D01*
X392066Y664190D01*
X408044D01*
X409228Y665374D01*
X414084D01*
X415189Y664269D01*
Y664203D01*
X415218D01*
G01X406358Y682942D02*
X403621D01*
X402148Y681469D01*
Y678998D01*
X399873Y676723D01*
Y666411D01*
G01X405918Y696156D02*
X402581D01*
X399829Y693404D01*
Y690191D01*
G01X391857Y711280D02*
Y706074D01*
X391740Y705957D01*
G01X392080Y692796D02*
X394040Y694756D01*
Y703657D01*
X391740Y705957D01*
G01X387650Y715442D02*
Y709221D01*
X389218Y707653D01*
Y703654D01*
X390950Y701922D01*
G01X399337Y711280D02*
X398504D01*
X396150Y708926D01*
G01X394840Y711437D02*
X394880Y711477D01*
Y712492D01*
X398786Y716398D01*
X399337D01*
G01X387650Y715442D02*
X388606Y716398D01*
X391857D01*
G01X407303Y95117D02*
X405703Y96717D01*
Y114763D01*
X405709D01*
G01X404813Y93887D02*
X403353Y95347D01*
Y114763D01*
X403347D01*
G01X400985D02*
Y120557D01*
X403965Y123537D01*
X421893D01*
G01X412330Y245694D02*
X418905D01*
G01X412330Y255537D02*
X416882D01*
X418448Y253971D01*
X422088D01*
X422528Y253531D01*
G01X412330Y263410D02*
X418294D01*
X418575Y263691D01*
G01X412330Y261442D02*
X420747D01*
X420858Y261331D01*
G01X412330Y267347D02*
X408034D01*
X406108Y265421D01*
X403548D01*
X401618Y267351D01*
G01X412330Y269316D02*
X407283D01*
X406578Y270021D01*
X403318D01*
X403148Y270191D01*
G01X412330Y296875D02*
X405362D01*
X403628Y295141D01*
Y292201D01*
G01X406150Y510810D02*
Y507118D01*
X405348Y506316D01*
G01X413175Y531881D02*
X411339D01*
X407776Y528318D01*
Y527426D01*
G01X403176Y524091D02*
X404441D01*
X407776Y527426D01*
G01X403214Y528015D02*
X404457D01*
X405954Y529512D01*
Y532502D01*
G01X413175Y533456D02*
X406908D01*
X405954Y532502D01*
G01X416029Y541105D02*
Y542395D01*
X415222Y543202D01*
X407367D01*
X404292Y540127D01*
X403387D01*
G01X413175Y535031D02*
X410788D01*
X408486Y537333D01*
G01X413105Y538181D02*
X410870D01*
X409438Y539613D01*
X407348D01*
X403862Y536127D01*
X403187D01*
G01X403922Y620857D02*
Y618351D01*
X403904Y618333D01*
G01D02*
Y615157D01*
G01X403922Y624007D02*
X401353D01*
G01X409942Y631847D02*
Y631851D01*
X406100D01*
G01X406358Y650239D02*
X409389D01*
X410213Y651063D01*
X411623D01*
X412618Y650068D01*
Y647720D01*
X413535Y646804D01*
G01D02*
X415430Y648699D01*
X416419D01*
G01Y656883D02*
X415334D01*
X413718Y655267D01*
G01X406358Y657739D02*
X408973D01*
X411445Y655267D01*
X413718D01*
G01X416504Y644754D02*
X411644D01*
X411159Y645239D01*
X406358D01*
G01Y675442D02*
X413784D01*
X413966Y675624D01*
G01X406358Y662739D02*
X408935D01*
X410355Y661319D01*
X410948D01*
X411982Y660285D01*
G01X406358Y672942D02*
X411387D01*
X411675Y672654D01*
G01X416419Y673094D02*
X412115D01*
X411675Y672654D01*
G01X416419Y669027D02*
X412576D01*
X411065Y667516D01*
G01X406358Y667942D02*
X410639D01*
X411065Y667516D01*
G01X406358Y685442D02*
X413474D01*
X414183Y686151D01*
G01D02*
X414194Y686140D01*
X417781D01*
G01X412878Y693183D02*
X412100D01*
X410073Y691156D01*
X405918D01*
G01D02*
X403283D01*
X400968Y688841D01*
Y686699D01*
G01X417781Y689290D02*
X415466D01*
X412878Y691878D01*
Y693183D01*
G01X416419Y681122D02*
X414761D01*
X413643Y680004D01*
G01X406358Y680442D02*
X413205D01*
X413643Y680004D01*
G01X406358Y677942D02*
X410704D01*
X411149Y678387D01*
G01X414318Y700979D02*
X414141Y701156D01*
X405918D01*
G01X414318Y700979D02*
X414628Y700669D01*
X417427D01*
G01X477710Y722299D02*
X472526D01*
X469753Y719526D01*
X445977D01*
X443503Y717052D01*
X436893D01*
X435435Y715594D01*
X428426D01*
X423729Y710897D01*
X415730D01*
G01X418440Y742231D02*
Y743219D01*
X415780Y745879D01*
Y747078D01*
G01D02*
Y760045D01*
X412972Y762853D01*
Y786901D01*
X409510Y790363D01*
Y807872D01*
G01X417880Y786361D02*
X413447Y790794D01*
Y805904D01*
G01X434882Y245694D02*
X428905D01*
X428405Y245194D01*
G01X434882Y247662D02*
X427147D01*
X424961Y245476D01*
Y241203D01*
G01X426992Y250016D02*
X427377Y249631D01*
X434882D01*
G01Y267347D02*
X428405D01*
X428120Y267062D01*
X426335D01*
G01X434882Y269316D02*
X428623D01*
X424538Y273401D01*
Y275281D01*
X421728Y278091D01*
Y279141D01*
G01X434882Y273253D02*
X429490D01*
X429359Y273122D01*
X427197D01*
X426248Y274071D01*
Y278141D01*
X419978Y284411D01*
Y285291D01*
X418588Y286681D01*
G01X434882Y275222D02*
X428748D01*
G01X421128Y292601D02*
X422914Y294387D01*
X429212D01*
X430661Y292938D01*
X434882D01*
G01X423178Y284601D02*
X428728D01*
X429188Y285061D01*
X434882D01*
Y285064D01*
G01Y287032D02*
Y287031D01*
X428181D01*
X427909Y286759D01*
G01X434882Y290969D02*
X430090D01*
X428772Y292287D01*
X427468D01*
G01X424904Y598298D02*
X427916D01*
X429340Y596874D01*
G01D02*
X431340Y598874D01*
Y599929D01*
G01X428301Y604520D02*
X432169D01*
G01X430315Y611073D02*
Y608244D01*
X431520Y607039D01*
G01D02*
X432169Y606390D01*
Y604520D01*
G01X425161Y640680D02*
Y640270D01*
X425160D01*
Y632197D01*
X425880Y631477D01*
X425881D01*
G01D02*
X436290D01*
X437881Y633068D01*
Y639631D01*
X437100Y640412D01*
Y643793D01*
G01X434681Y635477D02*
X429461D01*
X428311Y636627D01*
Y640680D01*
G01X416419Y648699D02*
Y652732D01*
G01X429420Y646100D02*
X430822D01*
X432180Y647458D01*
G01X424700Y651833D02*
Y655785D01*
X425334Y656419D01*
G01X428440Y651833D02*
Y655329D01*
X429820Y656709D01*
G01X419569Y669027D02*
Y667456D01*
X421080Y665945D01*
G01X416419Y677128D02*
Y673094D01*
G01X417427Y700669D02*
Y696713D01*
G01X426391Y701173D02*
Y701285D01*
X430100Y704994D01*
X433035D01*
X437830Y709789D01*
Y713184D01*
X439298Y714652D01*
X444499D01*
X446973Y717126D01*
X463631D01*
X466620Y714137D01*
G01X460822Y712620D02*
Y714143D01*
X459039Y715926D01*
X450583D01*
X447605Y712948D01*
X444210D01*
X434006Y702744D01*
X432660D01*
X431372Y701456D01*
X430513D01*
X425590Y696533D01*
Y695895D01*
G01X447440Y709109D02*
X445008D01*
X435566Y699667D01*
Y697504D01*
X430918Y692856D01*
X430150D01*
X429228Y691934D01*
X427210D01*
G01X454070Y714226D02*
X450702D01*
X447885Y711409D01*
X445276D01*
X430976Y697109D01*
X429613D01*
X426507Y694003D01*
X421350D01*
G01X439940Y727581D02*
Y724277D01*
X440900Y723317D01*
Y721388D01*
X438885Y719373D01*
X436774D01*
X435272Y717871D01*
X427130D01*
G01X429240Y721014D02*
X429250D01*
Y721015D01*
X429230D01*
Y721034D01*
X428710Y721554D01*
Y724629D01*
X430940Y726859D01*
Y727581D01*
G01X435440D02*
X436338D01*
X438140Y725779D01*
Y724005D01*
X433449Y719314D01*
X428093D01*
X427836Y719571D01*
X426417D01*
X425275Y718429D01*
X424410D01*
G01X423242Y707949D02*
X424251Y708958D01*
X426127D01*
X431563Y714394D01*
X436918D01*
X438376Y715852D01*
X444001D01*
X446475Y718326D01*
X469798D01*
X473940Y714184D01*
G01X426440Y730731D02*
Y730908D01*
X428810Y733278D01*
Y739861D01*
X426440Y742231D01*
G01X430940Y730731D02*
Y732990D01*
X432980Y735030D01*
Y740191D01*
X430940Y742231D01*
G01X424200Y733399D02*
X421940Y731139D01*
Y730731D01*
G01X424200Y733399D02*
X423244Y734355D01*
X423195D01*
X422200Y735350D01*
Y738841D01*
X422440Y739081D01*
G01X426440Y727581D02*
Y724240D01*
G01X421690Y779548D02*
X423640Y777598D01*
Y758988D01*
X426440Y756188D01*
Y742231D01*
G01X422440D02*
Y756292D01*
X416180Y762552D01*
Y784661D01*
X417880Y786361D01*
G01X426900Y779752D02*
X426540Y779392D01*
Y773452D01*
X426548D01*
Y759544D01*
X430940Y755152D01*
Y742231D01*
G01X435440D02*
Y756368D01*
X428050Y763758D01*
Y771854D01*
X428250Y772054D01*
G01X421321Y807872D02*
Y796078D01*
X423021Y794378D01*
Y786916D01*
X421690Y785585D01*
Y779548D01*
G01X429195Y807872D02*
Y772999D01*
X428250Y772054D01*
G01X426900Y779752D02*
X427430Y780282D01*
Y793874D01*
X425258Y796046D01*
Y807872D01*
G01X559140Y448752D02*
Y446448D01*
X571420Y434168D01*
Y401971D01*
X550771Y381322D01*
Y336300D01*
X543771Y329300D01*
X538800D01*
X533900Y324400D01*
Y308400D01*
X515000Y289500D01*
Y281200D01*
X509000Y275200D01*
X490300D01*
X463700Y248600D01*
Y233986D01*
X448685Y218971D01*
Y209310D01*
X440820Y201445D01*
Y171128D01*
X442460Y169488D01*
Y152661D01*
X444621Y150500D01*
X461880D01*
Y150596D01*
G01X447760Y249404D02*
X445930D01*
X439797Y255537D01*
X434882D01*
G01X447426Y245162D02*
X447148D01*
X441580Y250730D01*
G01X447426Y241162D02*
Y241343D01*
X439138Y249631D01*
X434882D01*
G01Y243725D02*
X440444D01*
X443212Y240957D01*
G01X447426Y237162D02*
X447007D01*
X443212Y240957D01*
G01X456530Y256034D02*
X456316D01*
X455026Y254744D01*
X443282D01*
X440521Y257505D01*
X434882D01*
G01Y251599D02*
X440711D01*
X441580Y250730D01*
G01X435319Y604520D02*
Y600123D01*
G01D02*
X435513Y599929D01*
X438820D01*
G01X443190Y605071D02*
Y610128D01*
X444135Y611073D01*
G01X447975Y604522D02*
X443739D01*
X443190Y605071D01*
G01X437120Y612933D02*
X438980Y611073D01*
X444135D01*
G01X434315Y619873D02*
Y615738D01*
X437120Y612933D01*
G01X434681Y627477D02*
X440639D01*
X442207Y629045D01*
G01X435420Y647117D02*
X436285D01*
X439642Y643760D01*
Y642843D01*
G01X442792D02*
X443832D01*
X445414Y641261D01*
X447165D01*
X449227Y639199D01*
X451840D01*
G01X445604Y629045D02*
X442207D01*
G01X434681Y642639D02*
Y635477D01*
G01X439636Y646871D02*
X439634D01*
X437509Y648996D01*
G01X432180Y651833D02*
Y647458D01*
G01X442786Y646871D02*
X444704D01*
X446500Y645075D01*
G01X442013Y655595D02*
X445362D01*
X448962Y651995D01*
X451840D01*
G01X444700Y651900D02*
X444395Y651595D01*
X442013D01*
G01X444700Y651900D02*
X446343Y650257D01*
Y649044D01*
X447974Y647413D01*
Y645933D01*
X449590Y644317D01*
X451840D01*
G01Y674495D02*
X448092D01*
X447161Y673564D01*
G01X442015Y671628D02*
X447722D01*
X448030Y671936D01*
X451840D01*
G01Y664258D02*
X448916D01*
X445490Y660832D01*
X445270D01*
G01X451840Y666817D02*
X448419D01*
X445886Y669350D01*
X444458D01*
G01X442015Y667628D02*
X443737Y669350D01*
X444458D01*
G01X442015Y679628D02*
X442030Y679613D01*
X451840D01*
G01X442015Y675628D02*
X447239D01*
X448665Y677054D01*
X451840D01*
G01X451940Y692231D02*
X451809D01*
X447440Y696600D01*
Y696900D01*
G01Y703203D02*
Y696900D01*
G01Y709109D02*
X448719D01*
X451820Y712210D01*
G01X439940Y730731D02*
Y731439D01*
X441910Y733409D01*
Y740261D01*
X439940Y742231D01*
G01X444530Y723917D02*
Y733723D01*
X446140Y735333D01*
Y739921D01*
X443940Y742121D01*
Y742231D01*
G01X435440Y730731D02*
X437600Y732891D01*
Y741361D01*
X436730Y742231D01*
X435440D01*
G01X434540Y778500D02*
X434450Y778410D01*
Y764370D01*
X439940Y758880D01*
Y742231D01*
G01X443940D02*
Y759397D01*
X441000Y762337D01*
Y785297D01*
X441006D01*
G01X444370Y770152D02*
X444270Y770052D01*
Y763676D01*
X448440Y759506D01*
Y742231D01*
G01X433132Y807872D02*
Y779908D01*
X434540Y778500D01*
G01X441006Y807872D02*
Y796155D01*
X442840Y794321D01*
Y788480D01*
X441006Y786646D01*
Y785297D01*
G01X444943Y807872D02*
Y770725D01*
X444370Y770152D01*
G01X450682Y74840D02*
Y76693D01*
X452294Y78305D01*
Y81713D01*
G01X450682Y74840D02*
X454420Y71102D01*
Y69202D01*
X454428Y69194D01*
X454433D01*
G01D02*
Y69193D01*
X455880Y67745D01*
Y65682D01*
X456878Y64684D01*
X467479D01*
X470870Y68075D01*
X487030D01*
G01X456232Y81713D02*
Y76424D01*
X454582Y74774D01*
G01D02*
Y73760D01*
X456410Y71932D01*
X487753D01*
X502015Y57670D01*
X502900D01*
G01X470623Y154085D02*
X468438D01*
X464949Y150596D01*
X461880D01*
G01X461921Y157140D02*
X463302D01*
X465928Y159766D01*
X467473D01*
G01X450650Y203785D02*
X460970Y193465D01*
X465117D01*
X467420Y191162D01*
Y163503D01*
G01X457201Y249696D02*
Y251274D01*
X459108Y253181D01*
G01X447760Y249404D02*
X447792D01*
X450392Y252004D01*
X454893D01*
X457201Y249696D01*
G01X450367Y543286D02*
Y540720D01*
G01X474884Y604326D02*
Y604184D01*
X471300Y600600D01*
X467135D01*
X465490Y602245D01*
Y605225D01*
X463455Y607260D01*
X456258D01*
X455235Y608283D01*
Y614740D01*
X457150Y616655D01*
Y637281D01*
X464878Y645009D01*
Y648883D01*
X463697Y650064D01*
Y655215D01*
X461320Y657592D01*
Y661728D01*
X462843Y663251D01*
X464330D01*
G01X462270Y612911D02*
X460432Y611073D01*
X457935D01*
G01X448460Y625960D02*
X448135Y625635D01*
Y619873D01*
G01X466842Y613207D02*
X462566D01*
X462270Y612911D01*
G01X461935Y619873D02*
Y624178D01*
X459690Y626423D01*
G01X451840Y639199D02*
X455623D01*
X463178Y646754D01*
Y647483D01*
G01X451840Y641758D02*
X455777D01*
X458903Y644884D01*
G01X461997Y654507D02*
Y652356D01*
X456517Y646876D01*
X451840D01*
G01X466980Y667053D02*
X462802D01*
X458840Y663091D01*
Y657892D01*
X455502Y654554D01*
X451840D01*
G01Y657113D02*
X455617D01*
X457138Y658634D01*
Y663251D01*
G01X463020Y661023D02*
Y657857D01*
X464910Y655967D01*
Y650551D01*
X466080Y649381D01*
Y644800D01*
X467580Y643300D01*
Y638900D01*
X467529Y638849D01*
Y637430D01*
X468524Y636435D01*
X474247D01*
X474934Y637122D01*
X476692D01*
X479018Y634796D01*
X483656D01*
G01X451840Y651995D02*
X454646D01*
X460120Y657469D01*
Y662673D01*
X462440Y664993D01*
X467640D01*
X468260Y664373D01*
Y664366D01*
G01X474840Y669376D02*
X474768Y669448D01*
X460611D01*
X460587Y669424D01*
G01X451840Y669376D02*
X455587D01*
X456584Y668379D01*
Y663805D01*
X457138Y663251D01*
G01X458820Y674137D02*
X456619Y671936D01*
X451840D01*
G01Y679613D02*
X455041D01*
X455744Y678910D01*
X468462D01*
X469467Y679915D01*
G01X469977Y676496D02*
X468763Y677710D01*
X455541D01*
X454885Y677054D01*
X451840D01*
G01X460940Y703203D02*
Y697186D01*
X461244Y696882D01*
G01X461440Y692231D02*
Y696686D01*
X461244Y696882D01*
G01X453940Y703203D02*
Y697445D01*
G01X456440Y692231D02*
Y694945D01*
X453940Y697445D01*
G01X459950Y722720D02*
X460970Y723740D01*
Y733397D01*
X459740Y734627D01*
Y739925D01*
X461940Y742125D01*
Y742231D01*
G01X457060Y722427D02*
Y722761D01*
X455240Y724581D01*
Y729859D01*
X456112Y730731D01*
X457440D01*
G01X460940Y709109D02*
Y712502D01*
X460822Y712620D01*
G01X454070Y714226D02*
Y709239D01*
X453940Y709109D01*
G01X453960Y723142D02*
Y724042D01*
X453050Y724952D01*
Y733580D01*
X450740Y735890D01*
Y739993D01*
X452028Y741281D01*
X452096D01*
X452940Y742125D01*
Y742231D01*
G01X457440Y730731D02*
Y739081D01*
G01X448440Y730731D02*
Y731712D01*
X450410Y733682D01*
G01D02*
X448440Y735652D01*
Y739081D01*
G01X461940Y742231D02*
Y744257D01*
X460740Y745457D01*
Y784981D01*
X461565Y785806D01*
G01X454120Y785923D02*
Y762390D01*
X457440Y759070D01*
Y742231D01*
G01X448880Y807872D02*
Y763570D01*
X452940Y759510D01*
Y742231D01*
G01X461565Y785806D02*
X462750Y786991D01*
Y795369D01*
X460691Y797428D01*
Y807872D01*
G01X454120Y785923D02*
X452817Y787226D01*
Y807872D01*
G01X475310Y59746D02*
X481195D01*
X483580Y57361D01*
X489028D01*
X496619Y49770D01*
X542560D01*
X549537Y56747D01*
X616394D01*
X643570Y83923D01*
Y136678D01*
X639559Y140689D01*
X623118D01*
G01Y127893D02*
X628748D01*
X637300Y119341D01*
Y82747D01*
X615560Y61007D01*
X547768D01*
X540131Y53370D01*
X499001D01*
X489886Y62485D01*
X480624D01*
X480160Y62021D01*
X469755D01*
X464170Y56436D01*
G01X623118Y122775D02*
X629820D01*
X634900Y117695D01*
Y83743D01*
X614904Y63747D01*
X545951D01*
X537974Y55770D01*
X501082D01*
X491431Y65421D01*
X476572D01*
X475030Y63879D01*
G01X482093Y139330D02*
X474170D01*
X473200Y140300D01*
G01X468400Y135800D02*
X474300D01*
X475861Y137361D01*
X482093D01*
G01X470324Y133424D02*
X482093D01*
G01Y160983D02*
X476050D01*
X474813Y162220D01*
G01X470570Y163503D02*
X473530D01*
X474813Y162220D01*
G01X467473Y157235D02*
Y159766D01*
G01X482093Y157046D02*
X474140D01*
X473951Y157235D01*
G01X470623D02*
X473951D01*
G01X475770Y186451D02*
X476050Y186171D01*
Y176780D01*
X478067Y174763D01*
X482093D01*
G01X471221Y194784D02*
Y191000D01*
X475770Y186451D01*
G01X471221Y197934D02*
X468452D01*
G01X471300Y201900D02*
X473300Y203900D01*
Y240600D01*
X484700Y252000D01*
Y263800D01*
X492291Y271391D01*
X511106D01*
X521206Y281491D01*
X521291D01*
X523509Y283709D01*
Y290625D01*
X538100Y305216D01*
Y316716D01*
X549484Y328100D01*
X592900D01*
X603200Y317800D01*
Y294512D01*
X626112Y271600D01*
X671932D01*
X748200Y347868D01*
Y372268D01*
X771100Y395168D01*
Y484200D01*
X766800Y488500D01*
X752075D01*
G01X466200Y207300D02*
X471400Y212500D01*
Y241700D01*
X483000Y253300D01*
Y264100D01*
X491600Y272700D01*
X510000D01*
X522200Y284900D01*
Y291600D01*
X536500Y305900D01*
Y317804D01*
X548696Y330000D01*
X594100D01*
X605600Y318500D01*
Y295507D01*
X627107Y274000D01*
X668250D01*
X743900Y349650D01*
Y374050D01*
X762400Y392550D01*
Y475600D01*
X759000Y479000D01*
X755075D01*
G01X476400Y203100D02*
X475500Y204000D01*
Y238400D01*
X486300Y249200D01*
Y263500D01*
X492300Y269500D01*
X511700D01*
X525500Y283300D01*
Y290200D01*
X539700Y304400D01*
Y315500D01*
X550309Y326109D01*
X591392D01*
X601000Y316501D01*
Y293600D01*
X625200Y269400D01*
X672278D01*
X750000Y347122D01*
Y371522D01*
X772900Y394422D01*
Y489900D01*
X761800Y501000D01*
X745075D01*
G01X471120Y589272D02*
Y588277D01*
X468740Y585897D01*
G01D02*
X467067Y587570D01*
X463867D01*
G01X481340Y593296D02*
X480672Y593964D01*
X478411D01*
G01X478600Y589272D02*
X478772D01*
X481340Y591840D01*
Y593296D01*
G01X474397Y597114D02*
X470424D01*
X469890Y596580D01*
G01D02*
X468570Y595260D01*
X465165D01*
G01X474884Y604326D02*
X477606D01*
X477900Y604032D01*
X483648D01*
G01X469165Y604060D02*
Y608839D01*
X466842Y611162D01*
Y613207D01*
G01X478411Y597114D02*
X474397D01*
G01X474884Y607476D02*
Y608068D01*
X479648Y612832D01*
G01X473436Y626379D02*
X470115D01*
X464050Y632444D01*
Y633877D01*
G01X483832Y620041D02*
X480660D01*
X474322Y626379D01*
X473436D01*
G01X467353Y617880D02*
Y613718D01*
X466842Y613207D01*
G01X474840Y657113D02*
X470840D01*
X470454Y657499D01*
X467835D01*
X466110Y655774D01*
Y651054D01*
X467480Y649684D01*
Y645107D01*
X469229Y643358D01*
Y638135D01*
G01X474840Y641758D02*
X479844D01*
X480310Y642224D01*
G01X474840Y639199D02*
X478500D01*
X480620Y637079D01*
X490639D01*
X490640Y637078D01*
X492110D01*
X493760Y638728D01*
Y640193D01*
X493350Y640603D01*
Y646371D01*
X493020Y646701D01*
G01X479648Y612832D02*
Y612834D01*
X483318Y616504D01*
X485785D01*
X486532Y617251D01*
Y623158D01*
X485060Y624630D01*
Y629103D01*
X481618Y632545D01*
X478697D01*
X475820Y635422D01*
G01X479832Y628841D02*
X476759D01*
X476320Y629280D01*
G01D02*
X476071Y629529D01*
X473436D01*
G01X469444Y629940D02*
X473025D01*
X473436Y629529D01*
G01X474840Y654554D02*
X471184D01*
X468810Y652180D01*
G01X479512Y649436D02*
X474840D01*
G01Y651995D02*
X478411D01*
X481253Y654837D01*
G01X468540Y655799D02*
X467110Y654369D01*
Y651475D01*
X468480Y650105D01*
Y645528D01*
X469691Y644317D01*
X474840D01*
G01Y674495D02*
X479303D01*
X480711Y673087D01*
X482398D01*
G01X474840Y671936D02*
X479556D01*
X482544Y668948D01*
Y668042D01*
G01X474840Y661699D02*
X471325D01*
X470760Y662264D01*
Y664577D01*
X468284Y667053D01*
X466980D01*
G01D02*
Y667059D01*
G01X492770Y665090D02*
X480474D01*
X478747Y666817D01*
X474840D01*
G01X484700Y660355D02*
X481754D01*
X477851Y664258D01*
X474840D01*
G01Y677054D02*
X479354D01*
G01X480440Y703203D02*
Y700149D01*
X477209Y696918D01*
G01X474940Y692231D02*
Y694649D01*
X477209Y696918D01*
G01X465940Y692231D02*
Y696311D01*
X466683Y697054D01*
G01X467440Y703203D02*
Y697811D01*
X466683Y697054D01*
G01X473940Y703203D02*
Y699063D01*
X471768Y696891D01*
G01X470440Y692231D02*
Y695563D01*
X471768Y696891D01*
G01X477710Y722299D02*
X480440Y719569D01*
Y709109D01*
G01X467440D02*
Y713317D01*
X466620Y714137D01*
G01X473940Y714184D02*
Y709109D01*
G01X470550Y724034D02*
X468640Y725944D01*
Y729418D01*
X468230Y729828D01*
Y739415D01*
X470940Y742125D01*
Y742231D01*
G01X474930Y730748D02*
X475538D01*
X478920Y734130D01*
Y735603D01*
X480880Y737563D01*
Y740171D01*
X482940Y742231D01*
G01X473560Y724951D02*
Y724958D01*
X472209Y726309D01*
X471710D01*
X470430Y727589D01*
Y727598D01*
G01X481227Y691366D02*
X479527Y693066D01*
Y697243D01*
X482740Y700456D01*
Y719674D01*
X474930Y727484D01*
Y727598D01*
G01X466440Y730731D02*
Y732838D01*
X465850Y733428D01*
G01D02*
X464740Y734538D01*
Y737381D01*
X466440Y739081D01*
G01X478940D02*
Y738554D01*
X476980Y736594D01*
G01X474940Y739081D02*
Y738634D01*
X476980Y736594D01*
G01X463750Y780452D02*
X464308Y779894D01*
Y762600D01*
X466440Y760468D01*
Y742231D01*
G01X468565Y807872D02*
Y763515D01*
X470940Y761140D01*
Y742231D01*
G01X478940D02*
Y756747D01*
X472502Y763185D01*
Y785578D01*
X471780Y786300D01*
G01X464628Y807872D02*
X464308Y807552D01*
Y781010D01*
X463750Y780452D01*
G01X471780Y786300D02*
X472502Y787022D01*
Y807872D01*
G01X623118Y135571D02*
X639249D01*
X641170Y133650D01*
Y84919D01*
X615768Y59517D01*
X548388D01*
X541041Y52170D01*
X497624D01*
X489009Y60785D01*
X486810D01*
G01X483240Y60546D02*
X485040Y58746D01*
X489343D01*
X497119Y50970D01*
X541651D01*
X548918Y58237D01*
X616186D01*
X642370Y84421D01*
Y135138D01*
X639378Y138130D01*
X623118D01*
G01Y125334D02*
X628963D01*
X636100Y118197D01*
Y83245D01*
X615132Y62277D01*
X546560D01*
X538853Y54570D01*
X499502D01*
X490351Y63721D01*
X479450D01*
G01X484350Y112811D02*
X483538Y111999D01*
Y106198D01*
G01X492955Y106179D02*
Y107274D01*
X494355Y108674D01*
G01X484350Y112811D02*
X484918Y112243D01*
X492080D01*
X493415Y113578D01*
X496693D01*
X497093Y113978D01*
Y118424D01*
G01X493156D02*
Y122307D01*
X492484Y122979D01*
X490245D01*
X487020Y119754D01*
G01X502999Y118424D02*
Y115142D01*
X498810Y110953D01*
X496634D01*
X494355Y108674D01*
G01X482093Y153109D02*
X486895D01*
X487857Y152147D01*
G01X482093Y147204D02*
X488288D01*
X488570Y147486D01*
G01X482093Y141298D02*
X491488D01*
X492424Y142234D01*
G01X500215Y136449D02*
Y136848D01*
X493129Y143934D01*
X489667D01*
X489000Y143267D01*
X482093D01*
G01X494467Y148867D02*
X493831Y149503D01*
X487480D01*
X485842Y151141D01*
X482093D01*
G01X488220Y157515D02*
X486720Y159015D01*
X482093D01*
G01Y164920D02*
X488296D01*
X490130Y163086D01*
G01X493670Y171871D02*
X488106D01*
X487061Y170826D01*
X482093D01*
G01Y168857D02*
X488414D01*
X489040Y169483D01*
G01X482093Y166889D02*
X496028D01*
X496360Y167221D01*
G01X493156Y185826D02*
Y190878D01*
X491052Y192982D01*
X488999D01*
X487839Y194142D01*
G01X486370Y189279D02*
X488137Y191046D01*
X490080D01*
X491188Y189938D01*
Y185826D01*
G01X482980Y181071D02*
X482093Y180184D01*
Y176731D01*
G01X488850Y175419D02*
Y174823D01*
X486821Y172794D01*
X482093D01*
G01X494210Y175035D02*
X495125Y175950D01*
Y185826D01*
G01X491171Y195574D02*
X489271D01*
X487839Y194142D01*
G01X488017Y203716D02*
X491171Y200562D01*
Y198724D01*
G01X484280Y195416D02*
Y191369D01*
X486370Y189279D01*
G01X484992Y223746D02*
X482613Y221367D01*
Y218434D01*
G01D02*
Y216423D01*
X484005Y215031D01*
X486705D01*
X487168Y214568D01*
G01X493954Y265584D02*
X510500D01*
X516330Y271414D01*
X521432D01*
X530119Y280101D01*
G01X493954Y255584D02*
X504160D01*
G01X493954Y260584D02*
X508515D01*
X516890Y268959D01*
X525480D01*
G01X479795Y272867D02*
X484169D01*
G01X485719Y276271D02*
Y274417D01*
X484169Y272867D01*
G01X495228Y540849D02*
X489962D01*
G01X487013Y539525D02*
X488337Y540849D01*
X489962D01*
G01X494238Y600441D02*
Y598525D01*
X494767Y597996D01*
Y593444D01*
X495228Y592983D01*
Y589667D01*
G01X494238Y603450D02*
Y600441D01*
G01X498282Y620036D02*
X496393D01*
X491080Y625349D01*
Y631404D01*
X490326Y632158D01*
X486294D01*
X483656Y634796D01*
G01X487648Y612832D02*
X494740D01*
X495506Y613598D01*
X500763D01*
G01X487832Y628841D02*
Y624429D01*
G01X485363Y639623D02*
X482911D01*
X480310Y642224D01*
G01X498350Y627580D02*
X497094Y628836D01*
X494282D01*
G01X486806Y634796D02*
X490430D01*
X490623Y634603D01*
G01X494282Y628836D02*
Y630944D01*
X490623Y634603D01*
G01X485465Y647604D02*
Y651604D01*
G01D02*
X481680D01*
X479512Y649436D01*
G01X485465Y655604D02*
X482020D01*
X481253Y654837D01*
G01X490120Y662703D02*
Y660222D01*
X488615Y658717D01*
Y655604D01*
G01X485465Y671604D02*
X483881D01*
X482398Y673087D01*
G01X485465Y667604D02*
X482982D01*
X482544Y668042D01*
G01X490120Y662703D02*
X490345Y662478D01*
X505936D01*
X507271Y663813D01*
X510928D01*
G01X485465Y675604D02*
X481973D01*
X480523Y677054D01*
X479354D01*
G01X496577Y684553D02*
X494460Y682436D01*
Y675952D01*
X497432Y672980D01*
X504430D01*
X505106Y673656D01*
X510928D01*
G01X497350Y699767D02*
X493870D01*
X486140Y707497D01*
Y725781D01*
X487940Y727581D01*
G01X490900Y706145D02*
Y706146D01*
X491330Y706576D01*
X493447D01*
Y706582D01*
G01X481227Y696366D02*
X483740Y698879D01*
Y721128D01*
X479430Y725438D01*
Y727598D01*
G01X483440Y727581D02*
Y724513D01*
X485070Y722883D01*
Y703248D01*
X490362Y697956D01*
X492385D01*
X495560Y694781D01*
G01X493447Y718582D02*
X488842D01*
X488180Y719244D01*
G01X493447Y714582D02*
X491206D01*
X490890Y714898D01*
G01X488090Y710545D02*
Y710582D01*
X493447D01*
G01X487240Y742231D02*
X485180Y740171D01*
Y735923D01*
X480005Y730748D01*
X479430D01*
G01X491540Y742231D02*
X490120D01*
X489740Y741851D01*
Y734935D01*
X488686Y733881D01*
X485658D01*
X483440Y731663D01*
Y730731D01*
G01X487940D02*
X489375Y732166D01*
X490721D01*
X493910Y735355D01*
Y741231D01*
X494910Y742231D01*
X495840D01*
G01X492440Y727581D02*
X496940D01*
G01X480770Y778125D02*
Y767042D01*
X483440Y764372D01*
Y742731D01*
X482940Y742231D01*
G01X485870Y776087D02*
Y745001D01*
X487940Y742931D01*
X487240Y742231D01*
G01X491720Y776713D02*
Y743851D01*
X492440Y743131D01*
X491540Y742231D01*
G01X480770Y778125D02*
X482076Y779431D01*
Y794168D01*
X480376Y795868D01*
Y807872D01*
G01X485870Y776087D02*
X484313Y777644D01*
Y807872D01*
G01X491720Y776713D02*
X488250Y780183D01*
Y807872D01*
G01X495110Y771733D02*
X494822Y772021D01*
Y783571D01*
X492187Y786206D01*
Y807872D01*
G01X496955Y106179D02*
Y108237D01*
X497929Y109211D01*
X500310D01*
G01X500955Y106179D02*
Y107338D01*
X504750Y111133D01*
Y111749D01*
G01X504955Y106179D02*
Y108202D01*
X509691Y112938D01*
G01X508955Y106179D02*
Y107159D01*
X510431Y108635D01*
X512878D01*
G01X501030Y118424D02*
Y123012D01*
X500018Y124024D01*
X497430D01*
G01X504967Y118424D02*
Y114905D01*
X500310Y110248D01*
Y109211D01*
G01X506936Y118424D02*
Y113935D01*
X504750Y111749D01*
G01X510873Y118424D02*
Y114120D01*
X509691Y112938D01*
G01X534495Y118424D02*
Y124429D01*
X531655Y127269D01*
X509710D01*
G01X501040Y177297D02*
Y180905D01*
X501030Y180915D01*
Y185826D01*
G01X498940Y179744D02*
Y180032D01*
X499062Y180154D01*
Y185826D01*
G01X510000Y173500D02*
Y177379D01*
X508904Y178475D01*
Y185826D01*
G01X504967D02*
Y191942D01*
X505580Y192555D01*
G01X502999Y185826D02*
Y196793D01*
X504052Y197846D01*
Y202146D01*
G01X502999Y185826D02*
Y180541D01*
G01X509100Y191900D02*
X510800Y190200D01*
X510873D01*
Y185826D01*
G01X509100Y191900D02*
X508300Y192700D01*
Y198725D01*
G01X500764Y222122D02*
X502809Y220077D01*
Y213635D01*
X504769Y211675D01*
X508405D01*
X509500Y210580D01*
Y204300D01*
X508300Y203100D01*
Y201875D01*
G01X505580Y192555D02*
Y194980D01*
X506000Y195400D01*
Y203600D01*
X508100Y205700D01*
X508120D01*
Y205848D01*
X508126Y205854D01*
Y208870D01*
X507238Y209758D01*
X506279D01*
G01X506234Y207368D02*
X506102Y207500D01*
X503100D01*
X502000Y208600D01*
Y210625D01*
X500308Y212317D01*
X498701D01*
G01X506356Y219563D02*
X512400D01*
X514766Y217197D01*
Y208222D01*
G01X498867Y227773D02*
X499727D01*
X502211Y225289D01*
Y223569D01*
X500764Y222122D01*
G01X499273Y230820D02*
Y229375D01*
X498867Y228969D01*
Y227773D01*
G01X498778Y222122D02*
X500764D01*
G01X504160Y255584D02*
X506608D01*
X511608Y260584D01*
X522588D01*
G01X504505Y422944D02*
X509486Y427925D01*
Y433829D01*
G01D02*
Y434218D01*
X508580Y435124D01*
Y436725D01*
G01D02*
X509230Y437375D01*
Y441125D01*
G01D02*
Y442815D01*
X513204Y446789D01*
Y448680D01*
G01X506456Y446928D02*
X504822Y445294D01*
X500968D01*
G01X509464Y453995D02*
X507126D01*
X506456Y453325D01*
Y446928D01*
G01X500968Y445294D02*
X500895Y445367D01*
Y449761D01*
G01X497818Y445294D02*
Y440265D01*
G01X509464Y469743D02*
X498387D01*
X498119Y470011D01*
G01X501331Y528932D02*
X502038Y528225D01*
Y525900D01*
G01D02*
X499823D01*
X497848Y527875D01*
Y529155D01*
X501331Y532638D01*
Y534746D01*
G01X495228Y588093D02*
X500106D01*
X500538Y588525D01*
G01X498238Y603450D02*
Y592525D01*
X500538Y590225D01*
Y588525D01*
G01X502905Y595770D02*
Y598558D01*
X500538Y600925D01*
G01X502238Y603450D02*
X500538Y601750D01*
Y600925D01*
G01X512238Y620174D02*
X507698D01*
X505200Y622672D01*
Y633467D01*
X504401Y634266D01*
Y634818D01*
G01X500763Y613598D02*
Y615561D01*
X502080Y616878D01*
Y622999D01*
G01X502282Y628836D02*
X502280Y628834D01*
Y623199D01*
X502080Y622999D01*
G01X504401Y634818D02*
X503374D01*
X502801Y635391D01*
Y640070D01*
X505274Y642543D01*
X505780D01*
G01X497024Y646569D02*
Y645611D01*
X500540Y642095D01*
Y633829D01*
X501120Y633249D01*
G01X497035Y650626D02*
Y650030D01*
X495424Y648419D01*
Y645279D01*
X499390Y641313D01*
Y636289D01*
X496690Y633589D01*
G01X501940Y644073D02*
X502110Y644243D01*
X506485D01*
X507480Y643248D01*
Y641838D01*
X506168Y640526D01*
X506141D01*
X504401Y638786D01*
Y638780D01*
G01X508238Y628974D02*
X507551Y629661D01*
Y634818D01*
G01X504401Y638780D02*
Y637530D01*
X505360Y636571D01*
X506968D01*
X507551Y635988D01*
Y634818D01*
G01X510928Y653971D02*
X506138D01*
X505690Y654419D01*
G01X500174Y646569D02*
X502318D01*
X502431Y646456D01*
X506986D01*
X508061Y645381D01*
G01X510928Y650034D02*
Y648248D01*
X508061Y645381D01*
G01X510928Y652002D02*
X507036D01*
X504646Y649612D01*
X504295D01*
G01X500185Y650626D02*
X503281D01*
X504295Y649612D01*
G01X510928Y671688D02*
X504972D01*
X504114Y670830D01*
G01X510928Y669719D02*
X506942D01*
X505724Y668501D01*
X502052D01*
X499677Y670876D01*
X496453D01*
G01X510928Y667750D02*
X507251D01*
X505310Y665809D01*
X504241D01*
G01X510928Y665782D02*
X507260D01*
X505518Y664040D01*
X498496D01*
X497320Y665216D01*
G01X506470Y683512D02*
X506483Y683499D01*
X510928D01*
G01X501914Y675624D02*
X510928D01*
G01Y679562D02*
X506037D01*
X505580Y679105D01*
G01X510928Y677593D02*
X508566D01*
X507958Y676985D01*
X504648D01*
X503448Y678185D01*
X496277D01*
G01X501540Y681970D02*
X501980Y681530D01*
X510928D01*
G01Y695310D02*
X508382D01*
X506117Y697575D01*
X506092D01*
G01X510928Y691373D02*
X506409D01*
G01X512548Y722093D02*
X512234Y722407D01*
X509150D01*
X508150Y723407D01*
Y725199D01*
X507970Y725379D01*
Y732358D01*
X510040Y734428D01*
Y740131D01*
X512140Y742231D01*
G01X514620Y713193D02*
X512418D01*
X502530Y723081D01*
Y729447D01*
X499780Y732197D01*
Y735139D01*
X497940Y736979D01*
Y740654D01*
X499517Y742231D01*
X500140D01*
G01X496940Y730731D02*
Y732112D01*
X498080Y733252D01*
G01X509670Y730633D02*
X514842D01*
X514940Y730731D01*
G01X509670Y727483D02*
Y724292D01*
X509855Y724107D01*
G01X496940Y727581D02*
X498747D01*
X500260Y729094D01*
G01X501604Y733003D02*
X502068Y733467D01*
X503587D01*
X508140Y738020D01*
Y739081D01*
G01X504940Y730731D02*
X503408D01*
X501604Y732535D01*
Y733003D01*
G01X495840Y742231D02*
Y771003D01*
X495110Y771733D01*
G01X512140Y742231D02*
Y743248D01*
X510440Y744948D01*
Y771898D01*
X507935Y774403D01*
Y785704D01*
G01X501890Y746663D02*
X504140Y744413D01*
Y742231D01*
G01X500140D02*
Y775561D01*
X499270Y776431D01*
G01X508140Y742231D02*
Y768848D01*
X504440Y772548D01*
G01X499270Y776431D02*
X498324Y777377D01*
Y792144D01*
X500061Y793881D01*
Y807872D01*
G01X503998D02*
Y772990D01*
X504440Y772548D01*
G01X507935Y785704D02*
Y807872D01*
G01X512955Y106179D02*
X513985D01*
X515162Y107356D01*
Y112137D01*
X516146Y113121D01*
G01X519620Y108543D02*
X517955D01*
X516955Y107543D01*
Y106179D01*
G01X524955D02*
Y106434D01*
X526835Y108314D01*
G01X522111Y113310D02*
X522110D01*
Y108176D01*
X520955Y107021D01*
Y106179D01*
G01X518640Y125539D02*
X516840D01*
X514810Y123509D01*
Y118424D01*
G01X512841D02*
Y108672D01*
X512878Y108635D01*
G01X516778Y118424D02*
Y113753D01*
X516146Y113121D01*
G01X519620Y108543D02*
Y113610D01*
X520715Y114705D01*
Y118424D01*
G01X519625Y108543D02*
X519620D01*
G01X524652Y118424D02*
Y110497D01*
X526835Y108314D01*
G01X522684Y118424D02*
Y113883D01*
X522111Y113310D01*
G01X515600Y172800D02*
Y169900D01*
X518600Y166900D01*
X538700D01*
X544000Y172200D01*
Y180800D01*
X542369Y182431D01*
Y185826D01*
G01X514810D02*
Y190913D01*
X515231Y191334D01*
G01X520715Y185826D02*
Y193884D01*
X520015Y194584D01*
G01X523593Y198171D02*
Y190614D01*
X524652Y189555D01*
Y185826D01*
G01X512200Y196000D02*
X511200Y195000D01*
Y193900D01*
X512841Y192259D01*
Y185826D01*
G01X516100Y178100D02*
X518916Y180916D01*
X522684D01*
Y185826D01*
G01X514500Y194300D02*
Y207956D01*
X514766Y208222D01*
G01X528589Y185826D02*
Y189744D01*
X526628Y191705D01*
X525293D01*
G01X516657Y200990D02*
Y192737D01*
X515254Y191334D01*
X515231D01*
G01X520500Y200925D02*
Y198770D01*
X520015Y198285D01*
Y194584D01*
G01X524500Y200925D02*
X522300Y203125D01*
Y208200D01*
X521800Y208700D01*
Y211525D01*
G01X524500Y200925D02*
Y199078D01*
X523593Y198171D01*
G01X512200Y198625D02*
Y196000D01*
G01X520500Y204075D02*
Y206710D01*
X520068Y207142D01*
G01X516657Y204140D02*
X516773Y204256D01*
Y214765D01*
X516551Y214987D01*
G01X528500Y204075D02*
X529000Y204575D01*
Y210500D01*
X527000Y212500D01*
X524436D01*
X524405Y212531D01*
G01X534208Y227832D02*
X522709D01*
X519670Y230871D01*
Y234272D01*
X519675Y234277D01*
Y238308D01*
G01Y241458D02*
X515675D01*
G01D02*
Y244811D01*
X515010Y245476D01*
Y253438D01*
X515670Y254098D01*
X515675D01*
G01X522588Y250584D02*
X518030D01*
X517670Y250224D01*
Y247527D01*
G01X524675Y241458D02*
Y244809D01*
X528460Y248594D01*
Y259434D01*
X527310Y260584D01*
X522588D01*
G01Y255584D02*
X517161D01*
X515675Y254098D01*
G01X547395Y292524D02*
X537286D01*
X535869Y291107D01*
Y289508D01*
X536455Y288922D01*
X544892D01*
X545460Y288354D01*
Y287526D01*
X544856Y286922D01*
X536455D01*
X535869Y286336D01*
Y285508D01*
X536455Y284922D01*
X541555D01*
X542141Y284336D01*
Y283508D01*
X541555Y282922D01*
X536455D01*
X535869Y282336D01*
Y281508D01*
X536455Y280922D01*
X541555D01*
X542141Y280336D01*
Y279508D01*
X541555Y278922D01*
X536455D01*
X535869Y278336D01*
Y277508D01*
X536455Y276922D01*
X541555D01*
X542141Y276336D01*
Y275508D01*
X541555Y274922D01*
X533195D01*
X527232Y268959D01*
X525480D01*
G01X519840Y430981D02*
Y430869D01*
X523307Y427402D01*
Y417736D01*
X552090Y388953D01*
G01X513167Y429636D02*
X512630Y430173D01*
Y436725D01*
G01X512380Y441125D02*
Y436975D01*
X512630Y436725D01*
G01X519840Y434131D02*
Y435330D01*
X518520Y436650D01*
Y439085D01*
X517929Y439676D01*
G01X524227Y448680D02*
Y446134D01*
X525838Y444523D01*
Y438333D01*
X526440Y437731D01*
G01X521078Y448680D02*
Y445383D01*
X521838Y444623D01*
Y440281D01*
X523667Y438452D01*
G01X522379Y431974D02*
Y436228D01*
X520738Y437869D01*
Y444023D01*
X519503Y445258D01*
Y448680D01*
G01X512867Y443679D02*
X512380Y443192D01*
Y441125D01*
G01X514779Y448680D02*
Y445591D01*
X512867Y443679D01*
G01X517928Y448680D02*
Y444933D01*
X518838Y444023D01*
Y440585D01*
X517929Y439676D01*
G01X525802Y448680D02*
Y446059D01*
X526938Y444923D01*
Y442060D01*
X528782Y440216D01*
X529968D01*
G01X524227Y476632D02*
Y478834D01*
X523738Y479323D01*
Y481223D01*
X525638Y483123D01*
Y484023D01*
G01X513929Y595770D02*
Y604926D01*
X514058Y605055D01*
G01X515280Y609042D02*
Y606277D01*
X514058Y605055D01*
G01X523800Y611145D02*
X523855Y611200D01*
X526638D01*
G01X530278Y620795D02*
X527300D01*
X526300Y621795D01*
Y623621D01*
G01X518920Y615387D02*
X521613D01*
G01X522278Y620795D02*
Y616052D01*
X521613Y615387D01*
G01X516238Y628974D02*
X516230D01*
Y618077D01*
X518920Y615387D01*
G01X525692Y643144D02*
Y654862D01*
G01X523723Y643144D02*
Y651352D01*
X522833Y652242D01*
Y661133D01*
X526430Y664730D01*
G01X519786Y643144D02*
Y660990D01*
X523078Y664282D01*
Y671983D01*
X526600Y675505D01*
Y679117D01*
G01X521516Y650576D02*
X521755Y650337D01*
Y643144D01*
G01X513789Y634449D02*
X510849D01*
X510700Y634300D01*
G01X516939Y634449D02*
Y638466D01*
X514320Y641085D01*
G01X517818Y643144D02*
X516379D01*
X514320Y641085D01*
G01X510928Y655939D02*
X516918D01*
X517328Y655529D01*
G01X510928Y661845D02*
X515541D01*
G01X517888Y687901D02*
X516385Y689404D01*
X510928D01*
G01X525692Y704168D02*
Y691867D01*
X518947Y685122D01*
G01X517443Y717011D02*
Y713318D01*
X516075Y711950D01*
Y708906D01*
X517818Y707163D01*
Y704168D01*
G01X510928Y693341D02*
X514366D01*
X515429Y692278D01*
G01X510928Y697278D02*
X515429D01*
G01X517775Y711203D02*
Y709947D01*
X519786Y707936D01*
Y704168D01*
G01X522865Y711178D02*
X523723Y710320D01*
Y704168D01*
G01X521755D02*
Y708206D01*
X520198Y709763D01*
Y716661D01*
X518148Y718711D01*
X516736D01*
X514498Y716473D01*
G01X510608Y717448D02*
X512103D01*
X514905Y720250D01*
X518798D01*
X521140Y722592D01*
Y730917D01*
X520100Y731957D01*
Y733443D01*
X523010Y736353D01*
Y740161D01*
X520940Y742231D01*
G01X514940Y730731D02*
Y731035D01*
X516120Y732215D01*
Y734093D01*
X515240Y734973D01*
Y744485D01*
X512610Y747115D01*
G01X516940Y735683D02*
X517324Y735299D01*
Y733032D01*
X518940Y731416D01*
Y730131D01*
G01X516940Y739081D02*
Y735683D01*
G01X523940Y730731D02*
Y732591D01*
X524576Y733227D01*
G01X525440Y739081D02*
Y734091D01*
X524576Y733227D01*
G01X511770Y779940D02*
X513650Y778060D01*
Y755293D01*
X516940Y752003D01*
Y742231D01*
G01X525440D02*
Y743732D01*
X523940Y745232D01*
Y773225D01*
X525110Y774395D01*
G01X519440Y772861D02*
Y746926D01*
X520940Y745426D01*
Y742231D01*
G01X511770Y779940D02*
X511872Y780042D01*
Y807872D01*
G01X523683D02*
Y782190D01*
X523940Y781933D01*
Y775565D01*
X525110Y774395D01*
G01X519440Y772861D02*
Y776569D01*
X522010Y779139D01*
Y794525D01*
X519746Y796789D01*
Y807872D01*
G01X536955Y106179D02*
Y107609D01*
X538088Y108742D01*
X539510D01*
G01X532955Y106179D02*
Y108669D01*
G01X528955Y106179D02*
X528950Y106184D01*
Y110113D01*
X527613Y111450D01*
Y113373D01*
G01X539510Y108742D02*
X540400Y109632D01*
Y118424D01*
G01X532955Y108669D02*
X530558Y111066D01*
Y118424D01*
G01X526621D02*
Y114365D01*
X527613Y113373D01*
G01X539500Y196500D02*
X538432Y195432D01*
Y185826D01*
G01X534495D02*
Y190349D01*
X536232Y192086D01*
G01X530558Y185826D02*
Y190905D01*
X529592Y191871D01*
Y192999D01*
G01X526621Y185826D02*
Y177079D01*
G01X532526Y185826D02*
Y195552D01*
X533474Y196500D01*
G01X544500Y197500D02*
X540400Y193400D01*
Y185826D01*
G01X528500Y204075D02*
X526443Y202018D01*
Y194116D01*
G01X540500Y200925D02*
Y197500D01*
X539500Y196500D01*
G01X536657Y200990D02*
Y192511D01*
X536232Y192086D01*
G01X528500Y200925D02*
X530200Y202625D01*
Y214938D01*
X531500Y216238D01*
X531929D01*
G01X529592Y192999D02*
Y195824D01*
X528500Y196916D01*
Y200925D01*
G01X533474Y196500D02*
Y197000D01*
X532500Y197974D01*
Y200925D01*
G01X541660Y211632D02*
Y207648D01*
X541657Y207645D01*
G01X540500Y204075D02*
Y206488D01*
X541657Y207645D01*
G01X536657Y204140D02*
Y205133D01*
X532320Y209470D01*
G01X535929Y216238D02*
X531929D01*
G01X547095Y301124D02*
X545131D01*
X544487Y301768D01*
Y302680D01*
X545131Y303324D01*
X557384D01*
X558028Y303968D01*
Y304880D01*
X557384Y305524D01*
X545131D01*
X544487Y306168D01*
Y307080D01*
X545131Y307724D01*
X555644D01*
X556288Y308368D01*
Y309280D01*
X555644Y309924D01*
X542931D01*
X542287Y309280D01*
Y299313D01*
X541487Y298513D01*
X538068D01*
X530119Y290564D01*
Y280101D01*
G01X547095Y296824D02*
X539065D01*
X532794Y290553D01*
Y282068D01*
G01X530940Y425081D02*
Y422207D01*
G01X545940Y428231D02*
X545440Y428731D01*
Y436731D01*
X544440Y437731D01*
X541440D01*
G01D02*
Y441695D01*
X540141Y442994D01*
G01X535940Y428231D02*
X533646Y430525D01*
Y435550D01*
X531465Y437731D01*
X531440D01*
G01D02*
Y438744D01*
X529968Y440216D01*
G01X530940Y428231D02*
Y428557D01*
X529028Y430469D01*
G01X526440Y437731D02*
X527471D01*
X528600Y436602D01*
Y432107D01*
X529028Y431679D01*
Y430469D01*
G01X526440Y428231D02*
X530940D01*
G01X540940D02*
X538509Y430662D01*
Y436618D01*
X537396Y437731D01*
X536440D01*
G01D02*
Y439326D01*
X535352Y440414D01*
G01X532101Y448680D02*
Y445460D01*
X534567Y442994D01*
X540141D01*
G01X527377Y448680D02*
Y446184D01*
X528038Y445523D01*
Y443649D01*
X529250Y442437D01*
X531630D01*
X533653Y440414D01*
X535352D01*
G01X537416Y453995D02*
X539866D01*
X541138Y452723D01*
X543138D01*
X545224Y450637D01*
Y446267D01*
X546384Y445107D01*
G01X547488Y452373D02*
X545938Y453923D01*
X541938D01*
X540292Y455569D01*
X537416D01*
G01Y461869D02*
X541392D01*
X542038Y461223D01*
X543938D01*
X545071Y462356D01*
X547638D01*
G01X537416Y458719D02*
X540734D01*
X541930Y457523D01*
X546038D01*
G01X531252Y595770D02*
Y601641D01*
X529408Y603485D01*
G01X540540Y601008D02*
Y600151D01*
X539126Y598737D01*
Y595770D01*
G01X537551D02*
Y598838D01*
X538828Y600115D01*
Y602945D01*
G01X534401Y595770D02*
Y602238D01*
X535048Y602885D01*
G01X530738Y607950D02*
Y604815D01*
X529408Y603485D01*
G01X530738Y611100D02*
X530638Y611200D01*
X526638D01*
G01X532420Y615484D02*
X533962Y613942D01*
X533968D01*
X534638Y613272D01*
Y611100D01*
G01Y607950D02*
Y603295D01*
X535048Y602885D01*
G01X571790Y646799D02*
X569060Y644069D01*
Y624450D01*
X565523Y620913D01*
X546364D01*
X543050Y624227D01*
X538781D01*
G01X526278Y629595D02*
X529407D01*
X532296Y626706D01*
X537789D01*
X538781Y625714D01*
Y624227D01*
G01X535631D02*
Y620227D01*
G01D02*
X530846D01*
X530278Y620795D01*
G01X527660Y643144D02*
Y662665D01*
X529525Y664530D01*
Y669349D01*
G01X529629Y643144D02*
Y648626D01*
X529899Y648896D01*
Y661020D01*
G01X537503Y643144D02*
Y654552D01*
X536557Y655498D01*
G01X531597Y643144D02*
Y638172D01*
X530779Y637354D01*
G01X539472Y643144D02*
Y666974D01*
X539830Y667332D01*
G01X557188Y643144D02*
Y653166D01*
X553410Y656944D01*
Y671280D01*
X549670Y675020D01*
X539734D01*
G01X531599Y689838D02*
Y691892D01*
X535534Y695827D01*
Y704168D01*
G01X529629D02*
Y686497D01*
X533270Y682856D01*
Y679351D01*
G01X527660Y704168D02*
Y686601D01*
X527111Y686052D01*
G01X533566Y704168D02*
Y707770D01*
X533362Y707974D01*
Y709384D01*
X535195Y711217D01*
X535272D01*
G01X531570Y713195D02*
Y710918D01*
X531712Y710776D01*
Y707359D01*
X531597Y707244D01*
Y704168D01*
G01Y697509D02*
Y704168D01*
G01X537503D02*
Y710088D01*
G01X539472Y704168D02*
Y708189D01*
X540062Y708779D01*
G01X541940Y730731D02*
Y733125D01*
X539938Y735127D01*
Y740229D01*
X541940Y742231D01*
G01X528440Y730731D02*
Y732623D01*
X529320Y733503D01*
Y733847D01*
X532180Y736707D01*
Y739991D01*
X529940Y742231D01*
G01X541940Y727581D02*
Y726491D01*
X544082Y724349D01*
Y724460D01*
G01X528440Y727581D02*
Y722903D01*
X528388D01*
G01X532940Y734810D02*
Y730731D01*
G01X534440Y739081D02*
Y736310D01*
X532940Y734810D01*
G01X539650Y780942D02*
Y776774D01*
X541940Y774484D01*
Y742231D01*
G01X529300Y771341D02*
Y747921D01*
X529940Y747281D01*
Y742231D01*
G01X534440D02*
Y758243D01*
X532940Y759743D01*
Y778120D01*
X533600Y778780D01*
G01X539431Y807872D02*
Y796321D01*
X541940Y793812D01*
Y783232D01*
X539650Y780942D01*
G01X527620Y807872D02*
Y778974D01*
X528440Y778154D01*
Y772201D01*
X529300Y771341D01*
G01X533600Y778780D02*
X531557Y780823D01*
Y807872D01*
G01X550490Y112989D02*
X551450Y112029D01*
Y103198D01*
X551454D01*
G01X546306Y118424D02*
Y110193D01*
G01X550243Y118424D02*
Y113236D01*
X550490Y112989D01*
G01X542700Y112881D02*
X544337Y114518D01*
Y118424D01*
G01X639200Y170100D02*
X601800D01*
X598200Y173700D01*
Y180200D01*
X594800Y183600D01*
X571600D01*
X558600Y170600D01*
X549100D01*
X542369Y163869D01*
Y118424D01*
G01X573117Y141298D02*
X566961D01*
X564191Y138528D01*
X552173D01*
G01X573117Y139330D02*
X566984D01*
X564349Y136695D01*
X554689D01*
X550599Y132605D01*
Y132596D01*
G01X573117Y151141D02*
X567675D01*
X566790Y152026D01*
X555805D01*
X550370Y157461D01*
G01X550550Y151682D02*
X553710Y148522D01*
X565370D01*
X566020Y149172D01*
X573117D01*
G01X551464Y143862D02*
X552196D01*
X555247Y140811D01*
X564116D01*
X566572Y143267D01*
X573117D01*
G01Y176731D02*
X568131D01*
X559463Y168063D01*
X550604D01*
Y168072D01*
G01X560085Y185826D02*
Y179733D01*
X557668Y177316D01*
Y176534D01*
G01X555510Y173872D02*
X554136Y175246D01*
Y180461D01*
X556148Y182473D01*
Y185826D01*
G01X553909Y201089D02*
Y195595D01*
X556148Y193356D01*
Y185826D01*
G01X554180D02*
Y182409D01*
X552730Y180959D01*
Y175502D01*
X551400Y174172D01*
X551395D01*
G01X546000Y192000D02*
X544337Y190337D01*
Y185826D01*
G01X549909Y201089D02*
X553909D01*
G01X544500Y200925D02*
Y197500D01*
G01X543282Y242993D02*
Y246993D01*
G01X553895Y242354D02*
X550833D01*
X550474Y241995D01*
X549433D01*
X545703Y245725D01*
G01X543282Y246993D02*
X544435D01*
X545703Y245725D01*
G01X553895Y240780D02*
X550474D01*
X545981Y236287D01*
G01X543282Y238993D02*
Y234993D01*
G01D02*
X544687D01*
X545981Y236287D01*
G01X551129Y280528D02*
X557007D01*
X557207Y280328D01*
G01X561931Y270863D02*
Y273779D01*
X557207Y278503D01*
Y280328D01*
G01X550545Y292524D02*
X552111D01*
X555072Y289563D01*
G01X568231Y270863D02*
Y273952D01*
X568974Y274695D01*
Y275895D01*
X566774Y278095D01*
Y287586D01*
X564797Y289563D01*
X555072D01*
G01X564354Y286277D02*
X563716D01*
X562287Y287706D01*
X559819D01*
X557222Y285109D01*
G01X550245Y296824D02*
X560157D01*
X561525Y298192D01*
G01X550245Y301124D02*
X558457D01*
X559140Y301807D01*
X565781D01*
X565953Y301635D01*
G01X549940Y425081D02*
X551658D01*
X564039Y412700D01*
X565310D01*
G01X549940Y428231D02*
X545940D01*
G01X550690Y439007D02*
Y443029D01*
X550671Y443048D01*
G01X546384Y445107D02*
X548443Y443048D01*
X550671D01*
G01X555140Y451902D02*
X559140D01*
G01X551140D02*
X555140D01*
G01X551140D02*
X547959D01*
X547488Y452373D01*
G01X560465Y460956D02*
X558680Y462741D01*
X553050D01*
X550965Y460656D01*
G01D02*
X549338D01*
X547638Y462356D01*
G01X560365Y456156D02*
X558072Y458449D01*
X553158D01*
X550865Y456156D01*
G01D02*
X548305D01*
X546938Y457523D01*
X546038D01*
G01X550149Y534746D02*
X551815D01*
X554860Y531701D01*
G01X561063Y528325D02*
X558236D01*
X554860Y531701D01*
G01X547000Y534746D02*
Y530162D01*
X549920Y527242D01*
G01X561063Y524325D02*
X552837D01*
X549920Y527242D01*
G01X562308Y536895D02*
X560972Y538231D01*
X551172D01*
X550957Y538446D01*
X549159D01*
X548575Y537862D01*
Y534746D01*
G01X556252Y548723D02*
X559240D01*
X563138Y544825D01*
Y541975D01*
X563188Y541925D01*
G01X556252Y550297D02*
X559466D01*
X566968Y542795D01*
X575818D01*
X576208Y542405D01*
G01X556252Y556597D02*
X560578D01*
X567440Y549735D01*
X575038D01*
X575838Y548935D01*
G01X556252Y555022D02*
X559741D01*
X566298Y548465D01*
G01X556252Y558171D02*
X560099D01*
X560130Y558140D01*
X561716D01*
X565621Y554235D01*
X566338D01*
G01X568963Y555925D02*
X568138D01*
X564023Y560040D01*
X560129D01*
X559835Y559746D01*
X556252D01*
G01X561174Y564471D02*
X556252D01*
G01Y580219D02*
X559484D01*
X560938Y578765D01*
X563288D01*
X565858Y576195D01*
G01X556252Y566045D02*
X559858D01*
X561538Y567725D01*
X566378D01*
G01X556252Y567620D02*
X559433D01*
X561098Y569285D01*
Y571265D01*
X561608Y571775D01*
G01X556252Y583368D02*
X559551D01*
X560948Y584765D01*
X565398D01*
G01X561198Y581793D02*
X556252D01*
G01Y589667D02*
X557680D01*
X563128Y595115D01*
X568163D01*
G01X550149Y595770D02*
Y604639D01*
G01X542275Y595770D02*
Y602402D01*
X542848Y602975D01*
G01X556252Y588093D02*
X560306D01*
X561568Y589355D01*
G01X552350Y614028D02*
Y611936D01*
X553082Y611204D01*
X559199D01*
G01X550149Y604639D02*
X547940D01*
X546938Y605641D01*
Y607850D01*
G01X542438D02*
Y603385D01*
X542848Y602975D01*
G01X548793Y624762D02*
X544601D01*
X543400Y625963D01*
G01Y629306D02*
Y625963D01*
G01X548784Y617102D02*
X549276D01*
X552350Y614028D01*
G01D02*
X554526Y616204D01*
X559199D01*
G01X549314Y643144D02*
Y647594D01*
G01X551030Y637200D02*
X551798D01*
X555220Y640622D01*
Y643144D01*
G01X551283D02*
Y648775D01*
X549310Y650748D01*
Y654397D01*
X551283Y656370D01*
Y670800D01*
G01X553251Y643144D02*
Y649340D01*
X552196Y650395D01*
Y651878D01*
X551230Y652844D01*
G01X547346Y643144D02*
Y649899D01*
X542424Y654821D01*
G01X543400Y635615D02*
Y632456D01*
G01X543408Y643144D02*
X543400Y643136D01*
Y635615D01*
G01X557454Y631652D02*
Y633082D01*
X558886Y634514D01*
X563789D01*
X565556Y632747D01*
Y632431D01*
G01X551283Y704168D02*
Y699243D01*
G01X557188Y704168D02*
Y707044D01*
X556986Y707246D01*
Y710200D01*
X555283Y711903D01*
Y715693D01*
X553725Y717251D01*
G01X553251Y704168D02*
Y707652D01*
X551344Y709559D01*
X550004D01*
G01X555062Y708679D02*
X555220Y708521D01*
Y704168D01*
G01X543408D02*
Y707025D01*
X545062Y708679D01*
G01X550940Y727581D02*
Y722308D01*
X550535Y721903D01*
G01X559157Y704168D02*
Y706738D01*
X558256Y707639D01*
Y712330D01*
X557488Y713098D01*
Y713709D01*
G01X546440Y730731D02*
Y732625D01*
X544438Y734627D01*
Y740123D01*
X546438Y742123D01*
Y742229D01*
X546440Y742231D01*
G01X550940Y730731D02*
Y732625D01*
X548938Y734627D01*
Y740229D01*
X550940Y742231D01*
G01X555440Y730731D02*
Y731401D01*
X553168Y733673D01*
Y739959D01*
X555440Y742231D01*
G01X546440Y727581D02*
Y724245D01*
X546566Y724119D01*
G01X555440Y727581D02*
Y726422D01*
X557426Y724436D01*
G01X545300Y783152D02*
X546440Y782012D01*
Y742231D01*
G01X550940D02*
Y771858D01*
G01X555440Y742231D02*
Y778868D01*
X554870Y779438D01*
G01X545300Y783152D02*
X543368Y785084D01*
Y805904D01*
G01X550940Y771858D02*
Y782066D01*
X547305Y785701D01*
Y807872D01*
G01X554870Y779438D02*
X553610Y780698D01*
Y784732D01*
X551242Y787100D01*
Y807872D01*
G01X573117Y145235D02*
X566914D01*
X566777Y145372D01*
X564076D01*
G01X558059Y154254D02*
X566546D01*
X567691Y153109D01*
X573117D01*
G01Y147204D02*
X562594D01*
X558348Y142958D01*
Y142511D01*
G01X573117Y170826D02*
X568947D01*
X563410Y165289D01*
G01X573117Y166889D02*
X567994D01*
X563274Y162169D01*
G01X586769Y166461D02*
X586041Y165733D01*
X583058D01*
X582245Y164920D01*
X573117D01*
G01Y162952D02*
X578300D01*
X579897Y161355D01*
G01X581565Y154969D02*
X580150Y156384D01*
Y156393D01*
X578839Y157704D01*
Y159243D01*
X577099Y160983D01*
X573117D01*
G01Y168857D02*
X577564D01*
X578789Y167632D01*
X582792D01*
G01X573117Y159015D02*
X562195D01*
G01X563129Y178369D02*
X564022Y179262D01*
Y185826D01*
G01D02*
Y197561D01*
X565812Y199351D01*
Y209854D01*
X564984Y210682D01*
G01X559646Y174476D02*
Y177429D01*
X562054Y179837D01*
Y185826D01*
G01D02*
Y196005D01*
X561909Y196150D01*
Y201089D01*
G01X573117Y174763D02*
X576723D01*
X581915Y179955D01*
G01X557909Y201089D02*
X561909D01*
G01X564984Y214682D02*
Y210682D01*
G01X569805Y270863D02*
Y273726D01*
X570374Y274295D01*
Y276095D01*
X567974Y278495D01*
Y288792D01*
X566876Y289890D01*
G01X571380Y270863D02*
Y273801D01*
X571674Y274095D01*
Y276395D01*
X569174Y278895D01*
Y293795D01*
X565564Y297405D01*
X562312D01*
X561525Y298192D01*
G01X572955Y270863D02*
Y277014D01*
X570274Y279695D01*
Y297314D01*
X565953Y301635D01*
G01X564354Y283127D02*
Y282620D01*
X564274Y282540D01*
Y279395D01*
G01X565081Y270863D02*
Y274088D01*
X564674Y274495D01*
Y278995D01*
X564274Y279395D01*
G01X563506Y270863D02*
Y274063D01*
X560865Y276704D01*
Y285434D01*
G01X561063Y532225D02*
Y535650D01*
X562308Y536895D01*
G01X583890Y537093D02*
X577689D01*
X573957Y540825D01*
X572113D01*
G01X568963Y545425D02*
Y545800D01*
X566298Y548465D01*
G01X568963Y540825D02*
X564288D01*
X563188Y541925D01*
G01X572113Y555925D02*
X573838D01*
X575038Y554725D01*
G01X572213Y559825D02*
X575138D01*
G01X568963Y552025D02*
X566753Y554235D01*
X566338D01*
G01X577778Y556355D02*
X576308Y557825D01*
X570863D01*
X568963Y555925D01*
G01X581263Y559445D02*
X578370D01*
X576090Y561725D01*
X571038D01*
X569138Y559825D01*
X569063D01*
G01D02*
X568238D01*
X563803Y564260D01*
X561385D01*
X561174Y564471D01*
G01X568263Y575625D02*
X566428D01*
X565858Y576195D01*
G01X568263Y579525D02*
X564538D01*
X562270Y581793D01*
X561198D01*
G01X566378Y567725D02*
X568963D01*
G01D02*
X569163Y567525D01*
Y567523D01*
X569583Y567103D01*
X569842D01*
X571562Y565383D01*
X577578D01*
X578873Y566678D01*
Y567253D01*
G01X568963Y571725D02*
X561658D01*
X561608Y571775D01*
G01X568363Y583525D02*
X566638D01*
X565398Y584765D01*
G01X568463Y591325D02*
Y594815D01*
X568163Y595115D01*
G01X568363Y587425D02*
X565938D01*
X564008Y589355D01*
X561568D01*
G01X559199Y606204D02*
X564574D01*
X565350Y606980D01*
Y610604D01*
X564750Y611204D01*
X559199D01*
G01X568930Y607754D02*
X575480Y601204D01*
X579999D01*
G01X561125Y643144D02*
Y649226D01*
X559584Y650767D01*
X559440D01*
G01X563094Y643144D02*
Y640228D01*
X565617Y637705D01*
X565647D01*
G01X565062Y643144D02*
Y651345D01*
X563840Y652567D01*
Y653515D01*
G01X559157Y643144D02*
Y638666D01*
X558331Y637840D01*
X558281D01*
G01X562812Y630659D02*
X563784D01*
X565556Y632431D01*
G01X571952Y653971D02*
X575290D01*
X575490Y653771D01*
X578400D01*
X579729Y655100D01*
X583674D01*
X585389Y653385D01*
X588768D01*
G01X566950Y659439D02*
X567387Y659876D01*
X571952D01*
G01X577217Y652002D02*
X571952D01*
G01X563850Y659575D02*
Y659584D01*
X565925Y661659D01*
X566490D01*
X568644Y663813D01*
X571952D01*
G01X580740Y653286D02*
Y651626D01*
X579148Y650034D01*
X571952D01*
G01Y665782D02*
X578484D01*
X580637Y663629D01*
G01X571952Y677593D02*
X568147D01*
X565168Y674614D01*
G01X571952Y673656D02*
X569210D01*
X565168Y669614D01*
G01X571952Y669719D02*
X578960D01*
X579076Y669603D01*
G01X571952Y661845D02*
X575322D01*
X576987Y660180D01*
G01X571952Y667750D02*
X576520D01*
G01X594170Y719290D02*
X592859Y717979D01*
Y714020D01*
X593690Y713189D01*
Y705533D01*
X594660Y704563D01*
Y681579D01*
X585364Y672283D01*
X578102D01*
X577507Y671688D01*
X571952D01*
G01Y679562D02*
X576644D01*
G01X571952Y689404D02*
X576070D01*
X576902Y690236D01*
X578030D01*
G01X571952Y675624D02*
X576485D01*
X576846Y675985D01*
G01X571952Y681530D02*
X575822D01*
X577010Y682718D01*
G01X571952Y687436D02*
X576290D01*
X576519Y687665D01*
G01X563094Y704168D02*
Y712521D01*
X562540Y713075D01*
Y713454D01*
G01X561125Y704168D02*
Y707616D01*
X560062Y708679D01*
G01X570614Y713237D02*
X570104Y712727D01*
Y701090D01*
X568041Y699027D01*
Y692373D01*
X569041Y691373D01*
X571952D01*
G01X581385Y690080D02*
Y691204D01*
X580246Y692343D01*
X577190D01*
X576220Y691373D01*
X571952D01*
G01Y693341D02*
X575725D01*
X576460Y694076D01*
X581385D01*
G01X565062Y708679D02*
Y704168D01*
G01X571952Y695310D02*
X575950D01*
X576920Y696280D01*
X584391D01*
X585400Y697289D01*
G01X571952Y697278D02*
X574988D01*
X577239Y699529D01*
X589198D01*
X592960Y703291D01*
G01X574190Y717805D02*
Y720140D01*
X571085Y723245D01*
Y725436D01*
X568940Y727581D01*
G01X559940D02*
Y724138D01*
X562491Y721587D01*
X564319D01*
G01X565074Y713018D02*
Y708691D01*
X565062Y708679D01*
G01X559940Y730731D02*
Y732025D01*
X562550Y734635D01*
Y739621D01*
X559940Y742231D01*
G01X568940Y730731D02*
Y732805D01*
X571228Y735093D01*
Y739943D01*
X568940Y742231D01*
G01X564440Y730731D02*
Y731665D01*
X566798Y734023D01*
G01X564440Y739081D02*
X565395D01*
X566418Y738058D01*
Y734403D01*
X566798Y734023D01*
G01X573440Y730731D02*
Y732511D01*
X573750Y732821D01*
X576273D01*
X577570Y734118D01*
G01X559940Y742231D02*
Y751540D01*
X558970Y752510D01*
Y780167D01*
X560150Y781347D01*
G01X562700Y772391D02*
X564440Y770651D01*
Y742231D01*
G01X569680Y771106D02*
Y764136D01*
X568940Y763396D01*
Y742231D01*
G01X572720Y777184D02*
Y751570D01*
X573440Y750850D01*
Y742231D01*
G01Y739081D02*
X574899D01*
X575951Y738029D01*
Y735737D01*
X577570Y734118D01*
G01X560150Y781347D02*
X560938Y782135D01*
Y794358D01*
X559116Y796180D01*
Y807872D01*
G01X563053D02*
Y772744D01*
X562700Y772391D01*
G01X569680Y771106D02*
X566990Y773796D01*
Y807872D01*
G01X572720Y777184D02*
X570928Y778976D01*
Y807872D01*
G01X600118Y143248D02*
X606595D01*
X607450Y144103D01*
Y151255D01*
X605877Y152828D01*
X583706D01*
X581565Y154969D01*
G01X590769Y166461D02*
X586769D01*
G01X590842Y155799D02*
X586842D01*
G01D02*
X585453D01*
X579897Y161355D01*
G01X582792Y167632D02*
X584286D01*
X584715Y168061D01*
X594780D01*
X603828Y159013D01*
X621601D01*
X628170Y152444D01*
Y147187D01*
X626790Y145807D01*
X623118D01*
G01X582792Y167632D02*
Y170052D01*
X584646Y171906D01*
X586661D01*
G01D02*
Y175906D01*
G01X581915Y179955D02*
X586586D01*
G01X579707Y229395D02*
Y226968D01*
G01X582404Y235893D02*
Y233525D01*
X579707Y230828D01*
Y229395D01*
G01Y226968D02*
X583707D01*
G01X585553Y235893D02*
Y233416D01*
X588074Y230895D01*
X590974D01*
X591707Y230162D01*
G01X583979Y235893D02*
Y231695D01*
X585579Y230095D01*
G01X587707Y226968D02*
Y227967D01*
X585579Y230095D01*
G01X588865Y242354D02*
X591882D01*
X592985Y243457D01*
X608640D01*
X610474Y241623D01*
Y239290D01*
X610415Y239231D01*
Y237441D01*
G01X588865Y239205D02*
X591264D01*
X593674Y236795D01*
X595374D01*
G01X588865Y264402D02*
X588872Y264395D01*
X590874D01*
X593702Y267223D01*
Y270723D01*
X594374Y271395D01*
G01X588865Y262827D02*
X591306D01*
X593621Y265142D01*
X594041D01*
X594067Y265168D01*
G01X588865Y265976D02*
X590838D01*
X591776Y266914D01*
Y271897D01*
X596272Y276393D01*
X596574D01*
G01X589070Y423525D02*
X591090Y425545D01*
X626132D01*
X629708Y421969D01*
Y418774D01*
G01X578830Y448192D02*
X592403D01*
X603500Y459289D01*
Y464106D01*
X604851Y465457D01*
X610521D01*
X622004Y453974D01*
X632911D01*
X633839Y453046D01*
X638415D01*
X647471Y443990D01*
X660530D01*
X668913Y452373D01*
X678623D01*
X683140Y456890D01*
Y460129D01*
X685080Y462069D01*
G01X583890Y537093D02*
Y515953D01*
X591673Y508170D01*
X598670D01*
G01X581863Y540625D02*
X577988D01*
X576208Y542405D01*
G01X581863Y545225D02*
X579548D01*
X575838Y548935D01*
G01X588437Y564120D02*
X592437D01*
G01X581333Y555235D02*
X578898D01*
X577778Y556355D01*
G01X586369Y593167D02*
Y602904D01*
X586809Y603344D01*
G01X579999Y606204D02*
X583453D01*
X584540Y605117D01*
Y598115D01*
X582399Y595974D01*
Y593087D01*
G01X579999Y601204D02*
Y596190D01*
X578399Y594590D01*
Y593087D01*
G01X586809Y603344D02*
X586369Y603784D01*
Y607222D01*
X582387Y611204D01*
X579999D01*
G01X586810Y603344D02*
X586809D01*
G01X579999Y606204D02*
X574071D01*
G01X588950Y650070D02*
X588768Y650252D01*
Y653385D01*
G01X589500Y690546D02*
X588016Y692030D01*
X583427D01*
X583337Y692121D01*
X581385Y694073D01*
Y694076D01*
G01Y694080D02*
Y694076D01*
G01X585693Y722428D02*
Y729970D01*
X586454Y730731D01*
X587940D01*
G01X583440D02*
Y732464D01*
X581124Y734780D01*
Y739915D01*
X583440Y742231D01*
G01X587940Y739081D02*
X586116Y737257D01*
Y734445D01*
X587940Y732621D01*
Y730731D01*
G01X583440Y727581D02*
Y724927D01*
G01X587170Y773768D02*
X587940Y772998D01*
Y742231D01*
G01X579240Y775147D02*
Y751024D01*
X583440Y746824D01*
Y742231D01*
G01X587170Y773768D02*
Y780793D01*
X582739Y785224D01*
Y807872D01*
G01X578802D02*
Y796430D01*
X581010Y794222D01*
Y776917D01*
X579240Y775147D01*
G01X592480Y771514D02*
Y779032D01*
X586676Y784836D01*
Y807872D01*
G01X600118Y112568D02*
X603043Y109643D01*
Y104732D01*
G01X600118Y115098D02*
Y112568D01*
G01Y117657D02*
X592938D01*
G01X590193Y117732D02*
X590268Y117657D01*
X592938D01*
G01X600118Y138130D02*
X595438D01*
G01X600118Y130452D02*
X595718D01*
X592938Y133232D01*
G01X590193Y132232D02*
X591938D01*
X592938Y133232D01*
G01X606193Y104732D02*
Y122868D01*
X605070Y123991D01*
G01X600118Y125334D02*
X603727D01*
X605070Y123991D01*
G01X600118Y127893D02*
X594938D01*
G01X590193Y128232D02*
X593431D01*
X593770Y127893D01*
X594938D01*
G01X600118Y140689D02*
X592938D01*
G01X613432Y153528D02*
X609736Y157224D01*
X602263D01*
X593900Y165587D01*
X591643D01*
X590769Y166461D01*
G01X623118Y143248D02*
X618852D01*
X606301Y155799D01*
X590842D01*
G01X595707Y226968D02*
X591707D01*
G01D02*
Y230162D01*
G01X598999Y236295D02*
X595874D01*
X595374Y236795D01*
G01X599132Y271893D02*
X594872D01*
X594374Y271395D01*
G01X596574Y276393D02*
X599132D01*
G01X600770Y358702D02*
Y332705D01*
X601450Y332025D01*
Y326509D01*
G01X594860Y395088D02*
Y379603D01*
X597810Y376653D01*
Y330282D01*
X598551Y329541D01*
G01X604091Y352754D02*
Y357588D01*
X604493Y357990D01*
G01D02*
X610054D01*
X611848Y359784D01*
G01X604091Y349604D02*
X604854D01*
X607591Y352341D01*
X607855D01*
G01X604338Y344760D02*
X607613D01*
X607671Y344818D01*
G01X643071Y386361D02*
X640779D01*
X632754Y378336D01*
X620375D01*
X617479Y375440D01*
X601416D01*
X600713Y374737D01*
Y373743D01*
X601416Y373040D01*
X615199D01*
X615902Y372337D01*
Y371343D01*
X615199Y370640D01*
X601416D01*
X600713Y369937D01*
Y368943D01*
X601416Y368240D01*
X614626D01*
X615329Y367537D01*
Y366543D01*
X614626Y365840D01*
X601416D01*
X600713Y365137D01*
Y364143D01*
X601416Y363440D01*
X611145D01*
X611848Y362737D01*
Y359784D01*
G01X633005Y383132D02*
X629936Y380063D01*
X609632D01*
X598005Y391690D01*
X597440D01*
G01X611988Y407850D02*
X605610D01*
X600680Y412780D01*
G01X591100Y450128D02*
X601210Y460238D01*
Y465055D01*
X603902Y467747D01*
X614038D01*
X622097Y459688D01*
X640318D01*
X642114Y457892D01*
G01X590720Y456076D02*
X603391Y468747D01*
X634848D01*
X635300Y468295D01*
X640832D01*
X642114Y467013D01*
Y465888D01*
G01X622199Y516986D02*
X595427D01*
G01D02*
Y520325D01*
X603010Y527908D01*
G01X602976Y532108D02*
Y536108D01*
G01Y532108D02*
Y527942D01*
X603010Y527908D01*
G01X602976Y540108D02*
Y544108D01*
G01X609300Y538263D02*
X606134D01*
X604289Y540108D01*
X602976D01*
G01X599826Y544108D02*
Y544869D01*
X601504Y546547D01*
X609246D01*
X618946Y536847D01*
Y534523D01*
G01X602976Y536108D02*
Y536782D01*
X599826Y539932D01*
Y540108D01*
G01X592437Y564120D02*
Y566543D01*
G01X596437Y564120D02*
X600437D01*
G01D02*
Y567175D01*
X601043Y567781D01*
G01X604437Y564120D02*
X608437D01*
G01X606300Y551844D02*
X597809D01*
X592437Y557216D01*
Y560970D01*
G01X600437D02*
Y557433D01*
X602830Y555040D01*
X604820D01*
G01X621142Y584832D02*
Y581571D01*
X617193Y577622D01*
X615213D01*
X609238Y571647D01*
X596241D01*
X592437Y567843D01*
Y566543D01*
G01X623110Y584832D02*
Y581597D01*
X611260Y569747D01*
X603009D01*
X601043Y567781D01*
G01X609026Y579132D02*
X608797Y578903D01*
X602640D01*
G01X617270Y580443D02*
X614468D01*
X608928Y574903D01*
X602640D01*
G01Y586903D02*
X603592D01*
X605396Y588707D01*
Y590552D01*
G01X602640Y582903D02*
X604037D01*
X605286Y584152D01*
G01X602607Y591105D02*
Y593249D01*
X603524Y594166D01*
X605290D01*
G01X605010Y641435D02*
X602600Y643845D01*
Y658353D01*
X604819Y660572D01*
X606894D01*
G01X608310Y641603D02*
X603750Y646163D01*
Y654789D01*
X604533Y655572D01*
X606894D01*
G01X600727Y681876D02*
X598620Y683983D01*
Y687565D01*
X597820Y688365D01*
Y709505D01*
X598779Y710464D01*
Y716463D01*
X601440Y719124D01*
Y727581D01*
G01X628160Y722343D02*
X627492Y721675D01*
X626337D01*
X624746Y720084D01*
X618836D01*
X608546Y709794D01*
X607835D01*
X602427Y704386D01*
Y680525D01*
X602020Y680118D01*
Y679156D01*
G01X600727Y686876D02*
X598830Y688773D01*
Y708801D01*
X599783Y709754D01*
Y716052D01*
X605940Y722209D01*
Y727581D01*
G01X589800Y687059D02*
Y690246D01*
X589500Y690546D01*
G01X610440Y727581D02*
X606940Y724081D01*
Y714760D01*
X607846Y713854D01*
Y711826D01*
X600970Y704950D01*
Y692176D01*
X600690Y691896D01*
G01X598880Y719232D02*
X599179Y719531D01*
Y729720D01*
X598168Y730731D01*
X596940D01*
G01X594170Y719290D02*
X594160Y719300D01*
Y725770D01*
X592440Y727490D01*
Y727581D01*
G01X601440Y730731D02*
Y732621D01*
X599438Y734623D01*
Y740229D01*
X601440Y742231D01*
G01X605940Y730731D02*
Y732621D01*
X603938Y734623D01*
Y740229D01*
X605940Y742231D01*
G01X592440Y730731D02*
Y732988D01*
X589961Y735467D01*
Y739752D01*
X592440Y742231D01*
G01X596940Y739081D02*
X595099Y737240D01*
Y735101D01*
X596940Y733260D01*
Y730731D01*
G01X606270Y774615D02*
Y752181D01*
X603521Y749432D01*
Y744312D01*
X601440Y742231D01*
G01X597530Y780191D02*
Y749800D01*
X596940Y749210D01*
Y742231D01*
G01X592440D02*
X592480Y742271D01*
Y771514D01*
G01X603938Y753623D02*
X601030Y756531D01*
Y793554D01*
X598487Y796097D01*
Y807872D01*
G01X606270Y774615D02*
X605638Y775247D01*
Y778827D01*
X602424Y782041D01*
Y807872D01*
G01X597530Y780191D02*
X591047Y786674D01*
X591043D01*
X590613Y787104D01*
Y807872D01*
G01X610543Y104732D02*
Y107678D01*
G01X623118Y117657D02*
X616472D01*
X610543Y111728D01*
Y107678D01*
G01X613693Y104732D02*
Y109878D01*
X617925Y114110D01*
G01X623118Y115098D02*
X618913D01*
X617925Y114110D01*
G01Y114064D02*
Y114110D01*
G01X623118Y148366D02*
X618594D01*
X613432Y153528D01*
G01X613640Y349818D02*
X610378D01*
X607855Y352341D01*
G01X613640Y354818D02*
X618581D01*
G01X641236Y367877D02*
X637835D01*
X637132Y367174D01*
Y359357D01*
X636429Y358654D01*
X635435D01*
X634732Y359357D01*
Y375628D01*
X634029Y376331D01*
X633035D01*
X632332Y375628D01*
Y359428D01*
X631629Y358725D01*
X630635D01*
X629932Y359428D01*
Y375628D01*
X629229Y376331D01*
X628235D01*
X627532Y375628D01*
Y360789D01*
X626829Y360086D01*
X625835D01*
X625132Y360789D01*
Y375039D01*
X624108Y376063D01*
X623067D01*
X622208Y375204D01*
Y356389D01*
X620637Y354818D01*
X618581D01*
G01X607671Y344818D02*
X613640D01*
G01X618368Y415680D02*
X616758Y414070D01*
X611425D01*
X609430Y416065D01*
Y418633D01*
X611050Y420253D01*
Y423087D01*
G01X611988Y411000D02*
X615928D01*
G01D02*
X616431Y411503D01*
X626837D01*
X628189Y412855D01*
X634641D01*
X636586Y410910D01*
G01X614338Y415670D02*
X612407D01*
X611130Y416947D01*
Y417928D01*
G01X614338Y418820D02*
Y420291D01*
X616258Y422211D01*
G01X618368Y418830D02*
X620703Y416495D01*
X635484D01*
X639623Y412356D01*
Y409667D01*
X640881Y408409D01*
X643071D01*
G01X616258Y422211D02*
X617202D01*
X618368Y421045D01*
Y418830D01*
G01X610580Y448662D02*
X626203Y433039D01*
X695587D01*
X710368Y447820D01*
Y460404D01*
X708703Y462069D01*
G01X610010Y456581D02*
X610599Y455992D01*
X611504D01*
X629057Y438439D01*
X671118D01*
X671450Y438107D01*
X685363D01*
X698556Y451300D01*
Y460404D01*
X696891Y462069D01*
G01X704766D02*
X706431Y460404D01*
Y453483D01*
X686987Y434039D01*
X628305D01*
X609370Y452974D01*
G01X700829Y458132D02*
Y452158D01*
X685778Y437107D01*
X671030D01*
X670698Y437439D01*
X628139D01*
X610831Y454747D01*
X609148D01*
X608190Y455705D01*
Y460777D01*
X605800Y463167D01*
G01X610392Y526967D02*
X613810Y530385D01*
Y537155D01*
X613470Y537495D01*
G01D02*
X612702Y538263D01*
X609300D01*
G01X618946Y534523D02*
X624806D01*
X625130Y534199D01*
G01X617437Y564320D02*
Y565710D01*
X624870Y573143D01*
G01X612937Y564320D02*
Y565810D01*
X622970Y575843D01*
X624670D01*
X627084Y578257D01*
G01X608437Y564120D02*
X608447D01*
X610821Y566494D01*
G01X608437Y560970D02*
Y559221D01*
X610070Y557588D01*
G01X625079Y584832D02*
Y580752D01*
X610821Y566494D01*
G01X609026Y579132D02*
X609020Y579138D01*
Y585993D01*
X612977Y589950D01*
X616024D01*
G01X619173Y584832D02*
Y582346D01*
X617270Y580443D01*
G01X605396Y590552D02*
X610080D01*
X613414Y593887D01*
X616024D01*
G01Y591918D02*
X613052D01*
X605286Y584152D01*
G01X605290Y594166D02*
X611693D01*
X613382Y595855D01*
X616024D01*
G01X619302Y633065D02*
Y627533D01*
X621142Y625693D01*
Y620658D01*
G01X616024Y617509D02*
Y620115D01*
X611572Y624567D01*
Y629894D01*
G01X615690Y625536D02*
X618345D01*
X619173Y624708D01*
Y620658D01*
G01X616730Y633290D02*
X616955Y633065D01*
X619302D01*
G01X611249Y633125D02*
Y630217D01*
X611572Y629894D01*
G01X631930Y655254D02*
Y651381D01*
X623471Y642922D01*
X622580D01*
X622057Y642399D01*
X617373D01*
X611249Y636275D01*
G01X620131Y650072D02*
X615163D01*
X613796Y648705D01*
G01D02*
X611929Y650572D01*
X610044D01*
G01Y655572D02*
X612382D01*
X612950Y656140D01*
G01X620131Y655072D02*
X614018D01*
X612950Y656140D01*
G01X610044Y660572D02*
X612195D01*
X613200Y661577D01*
G01X620131Y660072D02*
X614705D01*
X613200Y661577D01*
G01X627463Y678159D02*
X623710D01*
X621620Y676069D01*
Y672054D01*
X620160Y670594D01*
G01X618059Y675183D02*
Y671309D01*
X618773Y670594D01*
X620160D01*
G01X627463Y675600D02*
Y671062D01*
X623263Y666862D01*
X615940D01*
G01X607292Y678250D02*
X607150Y678108D01*
Y674060D01*
X614348Y666862D01*
X615940D01*
G01X627463Y685836D02*
X615655D01*
X613791Y683972D01*
Y682559D01*
X612670Y681438D01*
G01X607292Y681400D02*
Y681397D01*
X611466D01*
X611556Y681307D01*
X612539D01*
X612670Y681438D01*
G01X627463Y688395D02*
X621780D01*
X620721Y687336D01*
X613897D01*
X612811Y688422D01*
G01X606972Y688804D02*
Y688808D01*
X607020Y688856D01*
X612377D01*
X612811Y688422D01*
G01X614172Y705076D02*
X613554D01*
X612230Y703752D01*
Y702227D01*
X611929Y701926D01*
X610172D01*
G01D02*
X607819D01*
X607380Y701487D01*
Y699671D01*
G01X614172Y701926D02*
X616336D01*
X617930Y703520D01*
G01X627463Y698632D02*
X622818D01*
X617930Y703520D01*
G01X627463Y690954D02*
X624084D01*
X621211Y693827D01*
X620480D01*
G01X613882Y691668D02*
X617460D01*
X619619Y693827D01*
X620480D01*
G01X614940Y727581D02*
Y727453D01*
X614606D01*
X609070Y721917D01*
G01X619440Y727581D02*
Y725079D01*
X616070Y721709D01*
Y720838D01*
G01X623940Y727581D02*
X622541D01*
X620670Y725710D01*
Y722216D01*
G01X619440Y730731D02*
X619799D01*
X621470Y732402D01*
Y740201D01*
X619440Y742231D01*
G01X614940Y730731D02*
Y731718D01*
X616740Y733518D01*
Y741152D01*
X615661Y742231D01*
X614940D01*
G01X610440Y730731D02*
Y734854D01*
X612438Y736852D01*
Y740233D01*
X610440Y742231D01*
G01X619080Y772610D02*
X619000D01*
Y750233D01*
X619400Y749833D01*
X619440D01*
Y742231D01*
G01X614940D02*
Y774592D01*
X619030Y778682D01*
G01X610440Y742231D02*
Y744078D01*
X612260Y745898D01*
Y783106D01*
G01X609347Y778624D02*
Y748162D01*
X605940Y744755D01*
Y742231D01*
G01X622109Y807872D02*
Y775639D01*
X619080Y772610D01*
G01X619030Y778682D02*
X619872Y779524D01*
Y794436D01*
X618172Y796136D01*
Y807872D01*
G01X612260Y783106D02*
Y785210D01*
X608598Y788872D01*
Y794759D01*
X610298Y796459D01*
Y805904D01*
G01X606361Y807872D02*
Y788046D01*
X609347Y785060D01*
Y778624D01*
G01X621773Y104704D02*
X626009D01*
X628838Y107533D01*
Y120216D01*
G01X623118D02*
X628838D01*
G01X628738Y133012D02*
X623118D01*
G01X628738D02*
X630139D01*
X630910Y132241D01*
X633074D01*
G01D02*
Y130263D01*
X631988Y129177D01*
X630346D01*
X629071Y130452D01*
X623118D01*
G01X635000Y265400D02*
X670400D01*
X751500Y346500D01*
Y370900D01*
X774400Y393800D01*
Y495900D01*
X761100Y509200D01*
X737100D01*
X734377Y506477D01*
Y504054D01*
G01X634440Y339818D02*
X640683D01*
X640647Y339854D01*
G01X634440Y349818D02*
X639838D01*
G01X628141Y344818D02*
X634440D01*
G01X643071Y389511D02*
X639035D01*
X638858Y389334D01*
X637366D01*
X633005Y384973D01*
Y383132D01*
G01X631528Y387178D02*
X632533D01*
X634511Y389156D01*
G01X643071Y391086D02*
X640291D01*
X639716Y390511D01*
X638620D01*
X638443Y390334D01*
X635689D01*
X634511Y389156D01*
G01X642721Y409983D02*
Y412977D01*
X636924Y418774D01*
X629708D01*
G01X643071Y406834D02*
X640662D01*
X636586Y410910D01*
G01X689017Y462069D02*
X687128Y460180D01*
Y451290D01*
X683453Y447615D01*
X668086D01*
X662171Y441700D01*
X646518D01*
X638667Y449551D01*
X636179D01*
X635840Y449890D01*
G01X631280Y446007D02*
X636587Y440700D01*
X669663D01*
X671870Y442907D01*
X683363D01*
X692955Y452499D01*
Y458132D01*
G01X630570Y451450D02*
Y449267D01*
X629580Y448277D01*
Y445302D01*
X635443Y439439D01*
X671538D01*
X671870Y439107D01*
X684948D01*
X696891Y451050D01*
Y458132D01*
G01X622600Y488753D02*
X633343Y478010D01*
X633352D01*
X634852Y476510D01*
Y474939D01*
G01X630420Y491511D02*
X633661Y488270D01*
X634887D01*
G01X634787Y501470D02*
Y494411D01*
X636170Y493028D01*
G01X632157Y511230D02*
X635408D01*
G01X635286Y516730D02*
X635408Y516608D01*
Y511230D01*
G01X632769Y527813D02*
X659541D01*
G01X625130Y534199D02*
Y526162D01*
X631862Y519430D01*
X643681D01*
X656629Y506482D01*
X681517D01*
X686980Y501019D01*
Y491666D01*
X689017Y489629D01*
G01X659933Y520347D02*
X645972D01*
X644989Y521330D01*
X634765D01*
X634530Y521565D01*
G01X629669Y559245D02*
X635512Y565088D01*
Y568745D01*
G01X621937Y567143D02*
Y564320D01*
G01X635512Y568745D02*
X636890Y570123D01*
Y571351D01*
G01X630984Y584832D02*
Y579257D01*
X624870Y573143D01*
G01X629016Y584832D02*
Y580189D01*
X627084Y578257D01*
G01X632953Y584832D02*
Y578526D01*
X621937Y567510D01*
Y567143D01*
G01X622510Y635544D02*
X622240Y635274D01*
Y626991D01*
X623110Y626121D01*
Y620658D01*
G01X634137Y631342D02*
X634921Y630558D01*
Y620658D01*
G01X625079D02*
Y627581D01*
X623940Y628720D01*
G01X632953Y620658D02*
Y625387D01*
X629781Y628559D01*
G01X627146Y638932D02*
X626916Y638702D01*
Y628036D01*
X626286Y627406D01*
Y624036D01*
X627047Y623275D01*
Y620658D01*
G01X634137Y631342D02*
Y633742D01*
G01X623940Y628720D02*
X625220Y630000D01*
Y639851D01*
X637241Y651872D01*
X653408D01*
X654376Y650904D01*
Y650072D01*
G01X630137Y633742D02*
Y628915D01*
X629781Y628559D01*
G01X654376Y645072D02*
X652552Y646896D01*
X634204D01*
X627140Y639832D01*
Y638932D01*
X627146D01*
G01X627463Y701191D02*
X631270D01*
X632080Y700381D01*
Y692689D01*
X640330Y684439D01*
G01X639920Y753526D02*
Y742480D01*
X641700Y740700D01*
Y737600D01*
X640700Y736600D01*
Y734284D01*
X637451Y731035D01*
X635465D01*
X634470Y730040D01*
Y728630D01*
X635670Y727430D01*
Y695657D01*
X648050Y683277D01*
X650463D01*
G01X628440Y727581D02*
X629916D01*
X633970Y723527D01*
Y723033D01*
G01X623940Y730731D02*
Y731582D01*
X626130Y733772D01*
Y740041D01*
X623940Y742231D01*
G01X628440Y730731D02*
Y732834D01*
X630240Y734634D01*
Y741932D01*
X629941Y742231D01*
X628440D01*
G01X623940D02*
Y743707D01*
X622310Y745337D01*
Y772010D01*
X625100Y774800D01*
Y778281D01*
X625010D01*
G01X633130Y742055D02*
Y748917D01*
X632300Y749747D01*
Y749755D01*
G01X624010Y746351D02*
X627210D01*
X627940Y745621D01*
Y742731D01*
X628440Y742231D01*
G01X641794Y807872D02*
Y785576D01*
X634690Y778472D01*
Y765992D01*
X638470Y762212D01*
G01X646500Y746300D02*
X643400Y749400D01*
Y754400D01*
X632000Y765800D01*
Y775400D01*
G01X643500Y742075D02*
X641700Y743875D01*
Y754600D01*
X629912Y766388D01*
Y769200D01*
G01D02*
Y783603D01*
X636440Y790131D01*
Y795811D01*
X633920Y798331D01*
Y807872D01*
G01X626046D02*
Y779317D01*
X625010Y778281D01*
G01X637857Y807872D02*
Y784964D01*
X632030Y779137D01*
G01X639963Y38803D02*
X643957Y42797D01*
Y47525D01*
G01X639957D02*
X643957D01*
G01X639957Y50675D02*
Y53849D01*
G01X649236Y367877D02*
Y361620D01*
X653238Y357618D01*
Y349488D01*
X653941Y348785D01*
X677332D01*
X678035Y348082D01*
Y347088D01*
X677332Y346385D01*
X653941D01*
X653238Y345682D01*
Y344688D01*
X653941Y343985D01*
X677332D01*
X678035Y343282D01*
Y342288D01*
X677332Y341585D01*
X643467D01*
X641736Y339854D01*
X640647D01*
G01X642963Y349785D02*
X642930Y349818D01*
X639838D01*
G01X641236Y381616D02*
Y371027D01*
G01X645236Y377858D02*
Y371027D01*
G01Y367877D02*
Y365611D01*
X646171Y364676D01*
G01X647414Y382018D02*
Y374485D01*
X648425Y373474D01*
G01X649236Y371027D02*
Y372663D01*
X648425Y373474D01*
G01X642721Y384787D02*
X641218D01*
X640366Y383935D01*
Y382486D01*
X641236Y381616D01*
G01X645840Y381668D02*
Y378462D01*
X645236Y377858D01*
G01X655288Y412752D02*
Y416818D01*
X655377Y416907D01*
Y418520D01*
X650822Y423075D01*
Y425295D01*
G01X677206Y462069D02*
X676603Y461466D01*
X661895D01*
X647280Y446851D01*
G01X654855Y470065D02*
Y467983D01*
X652110Y465238D01*
G01X685080Y473881D02*
X683174Y475787D01*
X674711D01*
X673929Y475005D01*
X652233D01*
X644463Y467235D01*
Y466923D01*
X643428Y465888D01*
X642114D01*
G01X681143Y473881D02*
X680877D01*
X679212Y472216D01*
X665318D01*
X664902Y472632D01*
X654532D01*
X652309Y470409D01*
Y469675D01*
X650045Y467411D01*
Y463981D01*
X647732Y461668D01*
X645070D01*
X644850Y461888D01*
X642114D01*
G01Y457888D02*
Y457892D01*
G01Y461888D02*
Y457892D01*
G01X677206Y473881D02*
X653514D01*
X648956Y469323D01*
G01X654786Y482930D02*
X650521D01*
G01X642761Y484530D02*
X648921D01*
X650521Y482930D01*
G01X654786Y478630D02*
X650773D01*
X647921Y475778D01*
G01X642726Y471199D02*
X643342D01*
X647921Y475778D01*
G01X642661Y497730D02*
X650790D01*
G01X654855Y491665D02*
Y493802D01*
X650927Y497730D01*
X650790D01*
G01X650150Y494337D02*
Y491720D01*
X652428Y489442D01*
X655728D01*
X657905Y487265D01*
G01X653800Y505331D02*
X647901Y511230D01*
X641314D01*
G01X664024Y520141D02*
Y521849D01*
X663414Y522459D01*
X641270D01*
X640470Y523259D01*
Y523266D01*
G01X668573Y520164D02*
X664293Y524444D01*
X645040D01*
G01X646205Y559245D02*
X639862Y565588D01*
Y568745D01*
G01X636890Y584832D02*
Y571351D01*
G01X638858Y584832D02*
Y579805D01*
X639673Y578990D01*
Y576888D01*
G01X639862Y568745D02*
X639673Y568934D01*
Y576888D01*
G01X651437Y575720D02*
Y578943D01*
G01X648701Y584832D02*
Y582712D01*
X651437Y579976D01*
Y578943D01*
G01X642795Y584832D02*
Y582518D01*
X643570Y581743D01*
Y572743D01*
X646870Y569443D01*
G01X644764Y584832D02*
Y578349D01*
X646870Y576243D01*
G01X651850Y607666D02*
X656603D01*
X658980Y610043D01*
G01X646737Y633842D02*
Y629316D01*
X644678Y627257D01*
X644636D01*
G01X640827Y620658D02*
Y625715D01*
X642369Y627257D01*
X644636D01*
G01X646732Y620658D02*
Y625409D01*
X647963Y626640D01*
X649436D01*
X654221Y631425D01*
G01X638470Y633740D02*
Y633209D01*
X636864Y631603D01*
Y627121D01*
X636890Y627095D01*
G01D02*
Y620658D01*
G01X638858D02*
Y628988D01*
X641263Y631393D01*
G01X644764Y620658D02*
Y624955D01*
X649173Y629364D01*
Y629876D01*
G01X646940Y643452D02*
X645320Y645072D01*
X640931D01*
G01X646940Y643452D02*
Y643448D01*
G01X651226Y645072D02*
X648560D01*
X646940Y643452D01*
G01X642737Y633842D02*
Y632867D01*
X641263Y631393D01*
G01X650970Y633740D02*
Y631673D01*
X649173Y629876D01*
G01X640931Y650072D02*
X647582D01*
X647870Y649784D01*
G01X651226Y650072D02*
X648158D01*
X647870Y649784D01*
G01X640931Y655072D02*
X646283D01*
X646580Y654775D01*
G01X651226Y655072D02*
X646877D01*
X646580Y654775D01*
G01X650463Y675600D02*
Y671235D01*
X655424Y666274D01*
X659978D01*
G01X650463Y688395D02*
X655449D01*
X657340Y690286D01*
G01X650463Y693514D02*
X646222D01*
X645870Y693162D01*
Y691315D01*
X646231Y690954D01*
X650463D01*
G01D02*
X656672D01*
X657340Y690286D01*
G01X650463Y678159D02*
X654289D01*
X658050Y674398D01*
Y672117D01*
G01X650463Y680718D02*
X655425D01*
X658369Y677774D01*
G01X650463Y685836D02*
X647854D01*
X637810Y695880D01*
Y728586D01*
X643000Y733776D01*
Y734200D01*
G01X650463Y706309D02*
X655610D01*
G01X650463Y703750D02*
X647312D01*
X642610Y708452D01*
Y723087D01*
X643610Y724087D01*
G01X650463Y701191D02*
X647296D01*
X641410Y707077D01*
Y725363D01*
X650700Y734653D01*
Y734600D01*
X652100Y736000D01*
Y746900D01*
X650700Y748300D01*
Y756400D01*
X649640Y757460D01*
Y757527D01*
G01X650463Y696073D02*
X647571D01*
X639010Y704634D01*
Y726810D01*
X649700Y737500D01*
Y745700D01*
X644980Y750420D01*
Y757802D01*
X646370Y759192D01*
Y759252D01*
G01X646680Y755009D02*
Y750620D01*
X650900Y746400D01*
Y736828D01*
X640210Y726138D01*
Y705534D01*
X647112Y698632D01*
X650463D01*
G01X648076Y720674D02*
Y719449D01*
X649130Y718395D01*
X650355D01*
X651226Y717524D01*
Y716674D01*
G01D02*
X654835Y713065D01*
X656650D01*
Y713057D01*
G01X651226Y724674D02*
Y723553D01*
X650389Y722716D01*
X646780D01*
X645890Y721826D01*
Y720050D01*
X644950Y719110D01*
G01X650463Y708868D02*
X658455D01*
X659029Y709442D01*
Y710048D01*
G01X648076Y716674D02*
X650620Y714130D01*
Y712775D01*
X652208Y711187D01*
X658299D01*
X659029Y710457D01*
Y710048D01*
G01X648076Y728674D02*
Y727777D01*
X649076Y726777D01*
X650180D01*
X651226Y725731D01*
Y724674D01*
G01X648076D02*
X644197D01*
X643610Y724087D01*
G01X643000Y734200D02*
X643500Y734700D01*
Y738925D01*
G01X637130Y742055D02*
Y745595D01*
X636910Y745815D01*
G01X657542Y807872D02*
Y792515D01*
X655234Y790207D01*
Y772951D01*
X649458Y767175D01*
X647532D01*
X647410Y767053D01*
G01X646680Y755009D02*
X646900Y755229D01*
Y757351D01*
X649850Y760301D01*
Y762333D01*
X646830Y765353D01*
X646705D01*
X645710Y766348D01*
X638310Y773749D01*
Y780394D01*
X645731Y787815D01*
Y807872D01*
G01X651690Y778099D02*
Y776764D01*
X650400Y775474D01*
Y770522D01*
G01X649668Y807872D02*
Y789731D01*
X645660Y785723D01*
Y783865D01*
X640010Y778215D01*
G01X652212Y786700D02*
Y788822D01*
X653605Y790215D01*
Y807872D01*
G01X659963Y38803D02*
X659947Y38819D01*
Y47606D01*
G01Y50756D02*
Y53722D01*
G01X655947Y47606D02*
X659947D01*
G01X658936Y359552D02*
X663632Y364248D01*
Y366698D01*
G01X668925Y364887D02*
Y364963D01*
X667861Y366027D01*
Y369552D01*
G01D02*
Y373695D01*
X666312Y375244D01*
Y382018D01*
G01X663632Y366698D02*
X664011Y367077D01*
Y369552D01*
G01D02*
Y374286D01*
X664737Y375012D01*
Y382018D01*
G01X656863Y412752D02*
Y415673D01*
X656418Y416118D01*
Y420707D01*
X655812Y421313D01*
Y424106D01*
G01X664450Y435739D02*
X687272D01*
X704766Y453233D01*
Y458132D01*
G01X681143D02*
X677674Y454663D01*
X666733D01*
X658680Y446610D01*
G01X653360Y446280D02*
X667034Y459954D01*
X679028D01*
X681143Y462069D01*
G01X658005Y470065D02*
X659591D01*
X660458Y470932D01*
G01X677206Y469943D02*
X661447D01*
X660458Y470932D01*
G01X681143Y469943D02*
X679332Y468132D01*
X676528D01*
X674328Y465932D01*
X660598D01*
X659828Y465162D01*
G01X677206Y477817D02*
X667949D01*
X667774Y477992D01*
G01X657936Y482930D02*
X659196D01*
X660948Y484682D01*
Y485942D01*
X661158Y486152D01*
G01X681143Y481755D02*
X679561D01*
X677784Y483532D01*
X674036D01*
X670295Y487273D01*
X662279D01*
X661158Y486152D01*
G01X657936Y478630D02*
X658916D01*
X663032Y482746D01*
X666208D01*
X667070Y483608D01*
G01X677206Y481755D02*
X672679D01*
X670826Y483608D01*
X667070D01*
G01X681143Y477817D02*
X679174Y479786D01*
X665527D01*
X662780Y477039D01*
G01X681143Y485692D02*
Y486317D01*
X679828Y487632D01*
X674020D01*
X669387Y492265D01*
X661115D01*
X660518Y492862D01*
G01X658005Y491665D02*
X659321D01*
X660518Y492862D01*
G01X677206Y493566D02*
X669950Y500823D01*
X662630D01*
G01X677206Y485692D02*
X674173D01*
X670132Y489733D01*
X662005D01*
X659537Y487265D01*
X657905D01*
G01X653800Y505331D02*
X660252Y498879D01*
X666231D01*
X675481Y489629D01*
X677206D01*
G01X675009Y519375D02*
Y514685D01*
X670622Y510298D01*
X655503D01*
X654240Y511562D01*
Y511568D01*
G01X659933Y517197D02*
Y513927D01*
G01X664024Y516991D02*
X664030D01*
Y513420D01*
X664024Y513414D01*
G01X672248Y548752D02*
X669330D01*
X668810Y548232D01*
Y542543D01*
X657967Y531700D01*
X652690D01*
Y531693D01*
G01X659541Y527813D02*
X663661D01*
X664661Y528813D01*
Y532935D01*
X667050Y535324D01*
G01X672248Y536752D02*
X668478D01*
X667050Y535324D01*
G01X658980Y610043D02*
Y613940D01*
X661844Y616804D01*
Y617427D01*
X661848Y617431D01*
G01X655170Y633840D02*
Y632374D01*
X654221Y631425D01*
G01X664870Y669424D02*
X659251D01*
X658050Y670625D01*
Y672117D01*
G01X664870Y673830D02*
X662313D01*
X658369Y677774D01*
G01X664870Y666274D02*
X659978D01*
G01X659678Y684907D02*
X658178D01*
X657410Y685675D01*
Y690216D01*
X657340Y690286D01*
G01X660660Y739360D02*
Y735479D01*
X659300Y734119D01*
G01X654000Y736400D02*
Y738416D01*
X654660Y739360D01*
G01X652660Y749000D02*
X654660Y747000D01*
Y742510D01*
G01X696912Y807872D02*
Y799342D01*
X698170Y798084D01*
Y789370D01*
X684400Y775600D01*
X665600D01*
X652600Y762600D01*
Y749060D01*
X652660Y749000D01*
G01X660660Y742510D02*
Y758340D01*
X657500Y761500D01*
G01X700849Y807872D02*
Y789249D01*
X686000Y774400D01*
X669400D01*
X657500Y762500D01*
Y761500D01*
G01X664460Y785890D02*
X667116Y788546D01*
Y794187D01*
X665416Y795887D01*
Y805904D01*
G01X669963Y38803D02*
X669987Y38827D01*
Y47536D01*
G01X679963Y38803D02*
X679927Y38839D01*
Y47536D01*
G01X675927D02*
X679927D01*
G01X675927Y50686D02*
Y53779D01*
G01X669987Y50686D02*
Y53672D01*
G01X673897Y359552D02*
X668925Y364524D01*
Y364887D01*
G01X675114Y369598D02*
Y371815D01*
X677083Y373784D01*
Y375124D01*
G01X669462Y382018D02*
Y379889D01*
X672826Y376525D01*
X675682D01*
X677083Y375124D01*
G01X673805Y386361D02*
X676265D01*
X677691Y384935D01*
X686024D01*
X687869Y386780D01*
G01X674155Y384787D02*
X675444D01*
X677591Y382640D01*
X686521D01*
X688118Y381043D01*
G01X673805Y395810D02*
X676707D01*
X677090Y395427D01*
X686286D01*
X686686Y395827D01*
Y397522D01*
G01X673805Y394235D02*
X676813D01*
X677195Y394617D01*
X686286D01*
X686686Y394217D01*
Y392522D01*
G01X673805Y400535D02*
X677868D01*
X678018Y400685D01*
X680348D01*
X683633Y403970D01*
X685859D01*
G01X673805Y398960D02*
X677708D01*
X678433Y399685D01*
X682945D01*
X684999Y401739D01*
X691037D01*
G01X669462Y412752D02*
Y415003D01*
X671056Y416597D01*
Y426300D01*
G01X671036Y413102D02*
Y414128D01*
X673368Y416460D01*
Y416621D01*
G01X696891Y466006D02*
X694923Y464038D01*
Y451790D01*
X694860Y451727D01*
Y451711D01*
X684160Y441011D01*
Y441007D01*
X672660D01*
G01X673740Y449887D02*
X674555Y449072D01*
X683340D01*
X685080Y450812D01*
Y458132D01*
G01X692955Y462069D02*
X690828Y459942D01*
Y451787D01*
X683873Y444832D01*
X682764D01*
G01X689017Y458132D02*
Y451391D01*
X684241Y446615D01*
X678860D01*
X677070Y444825D01*
Y444820D01*
G01X681143Y466006D02*
X679175Y464038D01*
G01X677206Y458132D02*
X673106D01*
X672190Y457216D01*
G01X677206Y466006D02*
X676517D01*
X674353Y463842D01*
G01X685080Y466006D02*
X683112Y464038D01*
G01X685080Y481755D02*
X683112Y483723D01*
G01X685080Y469943D02*
Y469974D01*
X683113Y471941D01*
G01X685080Y477817D02*
Y477818D01*
X683112Y479786D01*
G01X681143Y493566D02*
Y496675D01*
X674156Y503662D01*
G01X681143Y489629D02*
X679299Y491473D01*
G01X685080Y489629D02*
X683073Y491636D01*
Y496518D01*
X680790Y498801D01*
Y504521D01*
G01X685080Y485692D02*
X683112Y487660D01*
G01X678450Y508438D02*
Y514457D01*
X684430Y520437D01*
Y531139D01*
X685030Y531739D01*
X691359D01*
X693868Y529230D01*
X698881D01*
G01X668573Y517014D02*
Y514155D01*
G01X675009Y519375D02*
X672306Y522078D01*
Y524568D01*
G01X677160Y529422D02*
X675398Y531184D01*
Y532470D01*
G01X680949Y532016D02*
X679754D01*
X677160Y529422D01*
G01X675044Y524581D02*
X675089Y524536D01*
G01D02*
X680949D01*
G01X675089D02*
Y523921D01*
X678159Y520851D01*
Y519375D01*
G01X682880Y547065D02*
Y549543D01*
X681542Y550881D01*
X672929D01*
X672248Y550200D01*
Y548752D01*
G01Y544752D02*
Y540752D01*
G01D02*
Y536752D01*
G01X675398Y548752D02*
Y544752D01*
G01D02*
X678006D01*
X679433Y543325D01*
X686770D01*
G01X727830Y641829D02*
Y641837D01*
X719068D01*
X713728Y647177D01*
X693531D01*
X683386Y657322D01*
Y661386D01*
G01X673290Y807872D02*
Y782855D01*
G01X681164Y783461D02*
X679370Y785255D01*
Y798278D01*
X681164Y800072D01*
Y807872D01*
G01X677227D02*
Y786454D01*
G01X669353Y807872D02*
X669350D01*
Y787174D01*
X669803Y786721D01*
X669810D01*
G01X689017Y466006D02*
X689004D01*
X687130Y464132D01*
G01X692955Y466006D02*
Y465943D01*
X691070Y464058D01*
G01X692955Y485692D02*
X692954D01*
X690986Y487660D01*
G01X689017Y485692D02*
X687049Y487660D01*
G01X696891Y485692D02*
Y486621D01*
X694855Y488657D01*
Y498900D01*
X694823Y498932D01*
G01X696494Y513677D02*
X698591Y511580D01*
Y492517D01*
X696891Y490817D01*
Y489629D01*
G01X692955D02*
Y490005D01*
X691161Y491799D01*
Y505703D01*
X689729Y507135D01*
Y509580D01*
G01X696891Y507279D02*
Y493566D01*
G01X685080D02*
Y497181D01*
X684876Y497385D01*
G01X689017Y493566D02*
Y497282D01*
G01X692955Y493566D02*
X692403Y494118D01*
Y501560D01*
X692955Y502112D01*
G01X700829Y489629D02*
X700795D01*
X698683Y487517D01*
G01X694823Y498932D02*
Y501288D01*
X694855Y501320D01*
Y508062D01*
X693966Y508951D01*
Y520562D01*
G01X689729Y509580D02*
X691161Y511012D01*
Y512755D01*
G01D02*
X686661D01*
G01X693966Y520562D02*
X693516Y521012D01*
X692767D01*
X688823Y524956D01*
Y528276D01*
G01X686770Y543325D02*
X692526D01*
G01D02*
X697750D01*
X698333Y543908D01*
X703105D01*
G01X733210Y645829D02*
X719610D01*
X713921Y651518D01*
X695360D01*
X688386Y658492D01*
Y661386D01*
G01X713661Y20708D02*
Y39361D01*
X711676Y41346D01*
Y43845D01*
G01X708661Y30708D02*
Y34399D01*
X707176Y35884D01*
Y43845D01*
G01X711676Y46995D02*
Y51019D01*
G01X708703Y458132D02*
X708700Y458129D01*
Y452729D01*
X705214Y449243D01*
Y445071D01*
X704550Y444407D01*
G01X704766Y469943D02*
Y469945D01*
X706734Y471913D01*
G01X712640Y462069D02*
X720150D01*
X726580Y455639D01*
Y455637D01*
G01X712640Y458132D02*
X714328D01*
X715528Y459332D01*
G01X702730Y455483D02*
Y460168D01*
X700829Y462069D01*
G01X708703Y469943D02*
Y469945D01*
X710671Y471913D01*
G01X700829Y466006D02*
X702797Y464038D01*
G01X704766Y466006D02*
X705762D01*
X707588Y467832D01*
X727389D01*
X731178Y464043D01*
X731570D01*
G01X712640Y466006D02*
X725795D01*
X726430Y465371D01*
G01X708703Y466006D02*
X710677Y464032D01*
X723620D01*
X726830Y460822D01*
Y460815D01*
G01X712640Y469943D02*
X727940D01*
G01X708703Y473881D02*
Y473907D01*
X710768Y475972D01*
G01X715328Y481122D02*
X713273D01*
X712640Y481755D01*
G01Y477817D02*
X719624D01*
X720140Y478333D01*
G01X708703Y481755D02*
X710580Y483632D01*
X718167D01*
X718431Y483368D01*
G01X704766Y481755D02*
X706734Y483723D01*
G01X712640Y485692D02*
X719979D01*
X721290Y484381D01*
G01X708703Y477817D02*
Y477818D01*
X710671Y479786D01*
G01X704766Y473881D02*
Y473882D01*
X706734Y475850D01*
G01X719370Y472436D02*
X717925Y473881D01*
X712640D01*
G01X700719Y516954D02*
Y508033D01*
X702680Y506072D01*
Y504881D01*
X702730Y504831D01*
Y492778D01*
X702729Y492777D01*
Y487592D01*
X700829Y485692D01*
G01X708703D02*
X710856Y487845D01*
X724673D01*
X725730Y486788D01*
G01X704766Y485692D02*
X704528D01*
X702585Y483749D01*
G01X704766Y477817D02*
Y477818D01*
X706734Y479786D01*
G01X704766Y498880D02*
Y493566D01*
G01Y498880D02*
X704760Y498886D01*
Y513060D01*
X704590Y513230D01*
X704586D01*
G01X708703Y493566D02*
Y502057D01*
X715970Y509324D01*
Y513434D01*
G01X700829Y493566D02*
Y504041D01*
G01X712640Y489629D02*
X726859D01*
X729640Y486848D01*
G01X708703Y489629D02*
X710706Y491632D01*
X720150D01*
G01X712640Y493566D02*
Y496737D01*
X713978Y498075D01*
G01X722383Y512607D02*
X713978Y504202D01*
Y498075D01*
G01X704766Y489629D02*
X706800Y491663D01*
Y504455D01*
X707920Y505575D01*
G01X702621Y521356D02*
Y519876D01*
X704586Y517911D01*
Y513230D01*
G01X706361Y529230D02*
Y532632D01*
G01X706301Y535399D02*
X706361Y535339D01*
Y532632D01*
G01X713386Y661386D02*
Y657049D01*
X720606Y649829D01*
X728690D01*
G01X731566Y455778D02*
X726721D01*
X726580Y455637D01*
G01X731507Y460479D02*
X727166D01*
X726830Y460815D01*
G01X731670Y467368D02*
X730515D01*
X727940Y469943D01*
G01X736976Y478975D02*
X733543D01*
X725730Y486788D01*
G01X736954Y483641D02*
X732859D01*
X729640Y486860D01*
Y486848D01*
G01X731425Y496000D02*
Y494725D01*
X730600Y493900D01*
Y487808D01*
X729640Y486848D01*
G01X731227Y504054D02*
X728346D01*
Y504000D01*
X726000D01*
X723009Y501009D01*
Y494491D01*
X720150Y491632D01*
G01X716021Y516945D02*
Y513485D01*
X715970Y513434D01*
G01X716021Y516945D02*
Y521256D01*
G01X726829Y512607D02*
X722383D01*
G01X719761Y529130D02*
Y532432D01*
G01X719736Y535030D02*
X719761Y535005D01*
Y532432D01*
G01X716586Y535030D02*
X716580D01*
X716260Y534710D01*
Y525295D01*
G01X737675Y641829D02*
X727830D01*
G01X728690Y649829D02*
X737675D01*
G01X732540Y653829D02*
X721820D01*
X718386Y657263D01*
Y661386D01*
G01X731566Y452628D02*
Y448618D01*
G01X737223Y446832D02*
Y449861D01*
X736310Y450774D01*
G01X731566Y448618D02*
X732185D01*
X734341Y450774D01*
X736310D01*
G01X734820Y467368D02*
X736808D01*
X737350Y466826D01*
Y464330D01*
G01X734657Y460479D02*
X736700D01*
X737350Y459829D01*
Y459823D01*
G01X758500Y469500D02*
X755500D01*
X752818Y472182D01*
X735881D01*
X731340Y476723D01*
G01X736925Y475000D02*
Y478924D01*
X736976Y478975D01*
G01X746000Y475000D02*
X751925D01*
G01X740075D02*
X746000D01*
G01X736835Y487639D02*
X734613D01*
X732817Y489435D01*
G01X739425Y492500D02*
X736835Y489910D01*
Y487639D01*
G01X741925Y496800D02*
X737900D01*
X737100Y496000D01*
X734575D01*
G01X741925Y501000D02*
Y496800D01*
G01X734575Y496000D02*
Y492575D01*
G01X748925Y492500D02*
X745500D01*
G01D02*
X742575D01*
G01X734377Y504054D02*
Y500100D01*
G01X740825Y645829D02*
Y641829D01*
G01D02*
X740982Y641672D01*
X747439D01*
G01X744000Y647919D02*
X741910Y645829D01*
X740825D01*
G01Y653829D02*
Y649829D01*
G01D02*
X742090D01*
X744000Y647919D01*
G01X737675Y645829D02*
X733210D01*
G01X737675Y653829D02*
X732540D01*
G01X751925Y479000D02*
Y475000D01*
G01X748925Y492500D02*
Y488500D01*
G54D121*
X306809Y390104D03*
Y381443D03*
X299919D03*
Y390104D03*
G54D103*
X196149Y386396D03*
X193590D03*
Y400255D03*
X196149D03*
X201267Y386396D03*
X198708D03*
Y400255D03*
X201267D03*
G54D130*
X384758Y645239D03*
Y647739D03*
Y650239D03*
Y652739D03*
Y655239D03*
Y657739D03*
Y660239D03*
Y662739D03*
Y667942D03*
Y670442D03*
Y672942D03*
Y675442D03*
Y677942D03*
Y680442D03*
Y682942D03*
Y685442D03*
X406358Y660239D03*
Y657739D03*
Y655239D03*
Y652739D03*
Y650239D03*
Y647739D03*
Y645239D03*
Y662739D03*
Y675442D03*
Y672942D03*
Y670442D03*
Y667942D03*
Y685442D03*
Y682942D03*
Y680442D03*
Y677942D03*
G54D112*
X254383Y392464D03*
X251824D03*
X249265D03*
X246706D03*
X268052Y440162D03*
X270611D03*
X273170D03*
X275729D03*
X321404Y386129D03*
X318845D03*
X326522D03*
X323963D03*
G54D10*
G01X136420Y599352D02*
X134610Y601162D01*
X112710D01*
X110900Y599352D01*
X91860D01*
X87584Y595076D01*
X66880D01*
X59970Y588166D01*
Y574194D01*
X60210Y573954D01*
Y571882D01*
X59970Y571642D01*
Y549212D01*
X46723Y535965D01*
X42670D01*
X39067Y532362D01*
X22958D01*
X21543Y533777D01*
X4390D01*
G01X24955Y595792D02*
X21881D01*
G01X17020Y592934D02*
X18540Y594454D01*
Y596740D01*
X19330Y597530D01*
X19338D01*
X21603Y599795D01*
X22935D01*
G01X20020Y658951D02*
X17071D01*
G01X31260Y30414D02*
X28104D01*
G01X28408Y26414D02*
X31260D01*
G01X33677Y34564D02*
X30282D01*
G01X37599Y44149D02*
X34149D01*
G01X39740Y37708D02*
X33683D01*
X33677Y37714D01*
G01X30274D02*
X33677D01*
G01X34140Y544174D02*
Y540345D01*
G01X30140Y544174D02*
Y539692D01*
X30350Y539482D01*
Y539476D01*
X32860Y536966D01*
X34240D01*
G01X26145Y544221D02*
X30093D01*
X30140Y544174D01*
G01X34440Y597285D02*
X37197D01*
G01X36930Y611082D02*
Y608125D01*
X36937D01*
G01X28270Y605265D02*
Y602194D01*
G01X32270Y605265D02*
Y603102D01*
X33140Y602232D01*
G01X32810Y658951D02*
X29964D01*
G01X43480Y28062D02*
Y34592D01*
G01X45578Y47299D02*
Y50478D01*
G01X50981Y62443D02*
Y58681D01*
G01X46981Y62443D02*
Y58690D01*
G01X49559Y47299D02*
Y50577D01*
G01X46811Y118814D02*
Y122928D01*
G01X46140Y544174D02*
Y541712D01*
G01X38807Y547034D02*
Y543539D01*
G01X41957Y543321D02*
Y547034D01*
G01X43850Y602797D02*
X44270Y603217D01*
Y605265D01*
G01X39360Y604593D02*
X39367D01*
X40087Y605313D01*
Y608125D01*
G01X54958Y619407D02*
X51051D01*
G01X54958Y614907D02*
X52230D01*
G01X55256Y625732D02*
Y624853D01*
X52746Y622343D01*
X49174D01*
X48060Y621229D01*
G01X50170Y636895D02*
X50607Y637332D01*
X55256D01*
G01X51038Y643928D02*
X53751D01*
G01D02*
Y648428D01*
G01Y652029D02*
Y648428D01*
G01X62981Y62443D02*
Y59440D01*
G01X66981Y62443D02*
Y59390D01*
G01X62981Y65593D02*
Y69712D01*
G01X60318Y65593D02*
X62981D01*
G01X54703Y119096D02*
Y122796D01*
G01X67831Y141882D02*
X64309D01*
G01X59640Y164548D02*
Y161376D01*
G01X59821Y199565D02*
X55963D01*
G01X60242Y218543D02*
X56383D01*
G01X60255Y223944D02*
X56936D01*
G01X60177Y242872D02*
X56287D01*
G01X79360Y43076D02*
Y46044D01*
G01X85010Y159577D02*
X80560D01*
X78850Y157867D01*
Y157866D01*
G01X85010Y167577D02*
Y171679D01*
G01X77895Y172605D02*
X81030D01*
G01X86744Y185967D02*
X83089D01*
X82553Y185431D01*
G01X72635Y188946D02*
X75236D01*
G01X71880Y201109D02*
X75359D01*
G01X74484Y229920D02*
X78614D01*
G01X82310Y232861D02*
X79217D01*
G01X85460D02*
Y234640D01*
X84435Y235665D01*
X83390D01*
G01X90733Y227734D02*
X88556D01*
X85460Y230830D01*
Y232861D01*
G01X74484Y237920D02*
X79142D01*
G01X80391Y246459D02*
X85981D01*
X88399Y244041D01*
G01X80369Y250679D02*
X85059D01*
X86479Y249259D01*
G01X76924Y385722D02*
X73917D01*
G01X76924Y389621D02*
X74058D01*
G01X76944Y393857D02*
X74031D01*
G01X85951Y404368D02*
Y410263D01*
G01X76944Y397913D02*
X73868D01*
G01X80368Y506020D02*
Y504393D01*
X81174Y503587D01*
G01X70925Y807872D02*
Y791695D01*
G01X82736Y807872D02*
Y791695D01*
G01D02*
Y788695D01*
G01X70925Y791695D02*
Y788695D01*
G01X86744Y177967D02*
X90878D01*
G01X86744Y199733D02*
X90905D01*
G01X90673Y213852D02*
X86172D01*
G01X96168Y231618D02*
Y225836D01*
G01X99968Y371107D02*
Y367705D01*
G01X95968Y371107D02*
Y367814D01*
G01X99968Y374257D02*
X102234D01*
X103151Y373340D01*
G01X100951Y383568D02*
Y378963D01*
X99968Y377980D01*
Y374257D01*
G01X94547Y807872D02*
Y791695D01*
G01D02*
Y788695D01*
G01X102257Y172049D02*
Y167955D01*
G01X113774Y392023D02*
X114960D01*
X116960Y394023D01*
G01X113774Y387978D02*
X115030D01*
X117030Y389978D01*
G01X114372Y515708D02*
Y518898D01*
G01X109972Y515708D02*
Y519508D01*
G01X120953Y665638D02*
X119387D01*
X117790Y667235D01*
G01X114232Y807872D02*
Y791695D01*
G01D02*
Y788695D01*
G01X135403Y19162D02*
X130195D01*
G01X129028Y422320D02*
Y425593D01*
G01X129701Y462738D02*
Y458733D01*
G01D02*
X128360D01*
X127060Y460033D01*
Y460040D01*
G01X126377Y466738D02*
X129701D01*
G01X126377D02*
Y470150D01*
X126260Y470267D01*
G01X129701Y470738D02*
X126730D01*
X126260Y470268D01*
Y470267D01*
G01X136470Y481994D02*
X136360D01*
Y481141D01*
X129701Y474482D01*
Y470738D01*
G01X126072Y483758D02*
Y480864D01*
G01X128240Y666583D02*
X129121Y667464D01*
X133447D01*
G01X120909Y674490D02*
X123087D01*
X124467Y675870D01*
Y675871D01*
G01X132334Y725250D02*
Y722210D01*
X132438Y722106D01*
G01X132334Y729750D02*
Y732982D01*
G01X149403Y74863D02*
X146558D01*
G01D02*
X144833Y76588D01*
X143677D01*
G01X143150Y281123D02*
Y284787D01*
X142950Y284987D01*
X142943D01*
G01Y288987D02*
X139925D01*
X137925Y290987D01*
G01X141551Y296735D02*
X137990D01*
G01X142943Y292987D02*
X140798D01*
X139950Y293835D01*
G01X146093Y292987D02*
X149721D01*
G01X139238Y327933D02*
Y331903D01*
X139381Y332046D01*
G01X138857Y319043D02*
X134768D01*
G01X138857Y314543D02*
X135730D01*
G01X136506Y332193D02*
X136653Y332046D01*
X139381D01*
G01X142247Y671464D02*
X143857D01*
X146116Y669205D01*
X148200D01*
G01X137759Y681175D02*
X139110D01*
X140110Y680175D01*
Y675907D01*
G01X143823Y687539D02*
X147750D01*
G01X143823Y682907D02*
Y687539D01*
G01X133607Y689212D02*
Y686699D01*
G01X140428Y725173D02*
Y723734D01*
X138801Y722107D01*
X137418D01*
X136375Y721064D01*
G01X146364Y726705D02*
X149781D01*
X149860Y726626D01*
G01X137177Y730726D02*
Y728119D01*
X137070Y728012D01*
G01X140428Y725173D02*
Y726375D01*
X144604Y730551D01*
X148356D01*
X150104Y732299D01*
Y734579D01*
G01X137177Y742726D02*
X135064D01*
X134720Y742382D01*
G01X141791Y807872D02*
Y791695D01*
G01D02*
Y788695D01*
G01X151145Y466584D02*
Y469456D01*
G01X158430Y572560D02*
Y568437D01*
G01X162663Y572458D02*
X162786Y572335D01*
Y568599D01*
G01X157963Y640108D02*
Y643289D01*
G01X179361Y404721D02*
X176371D01*
G01X175804Y477790D02*
X179857D01*
G01X172654D02*
X172650D01*
G01X168370D02*
X172650D01*
G01X171053Y569411D02*
Y572437D01*
X170930Y572560D01*
G01X166663Y572458D02*
X166786Y572335D01*
Y569056D01*
G01X175263Y572558D02*
X175386Y572435D01*
Y569589D01*
G01X179263Y572558D02*
Y569428D01*
X179740Y568951D01*
G01X166388Y643933D02*
Y647435D01*
G01X177038Y643933D02*
Y647135D01*
G01X170619Y663816D02*
X174761D01*
G01X179180Y679529D02*
Y675205D01*
G01X164812Y666374D02*
Y662579D01*
G01X178289Y694040D02*
X180955D01*
X181744Y694829D01*
G01X175689Y715673D02*
X171154D01*
G01X164993Y710542D02*
X169531D01*
G01X173287Y791695D02*
Y788695D01*
G01Y807872D02*
Y791695D01*
G01X187410Y646850D02*
Y649715D01*
G01Y656850D02*
Y659705D01*
G01X191910Y646850D02*
Y650055D01*
G01X191163Y672526D02*
X188200D01*
G01X193473Y678356D02*
Y675998D01*
X194313Y675158D01*
Y672526D01*
G01X197889Y671226D02*
X196589Y672526D01*
X194313D01*
G01X184312Y693887D02*
Y695829D01*
X181950Y698191D01*
G01X196144Y712602D02*
X194440Y714306D01*
Y715898D01*
G01X191930Y712624D02*
X189940Y714614D01*
Y715931D01*
G01X185440D02*
Y712499D01*
G01Y739081D02*
Y735681D01*
G01X189940Y739081D02*
Y735681D01*
G01X194440Y739081D02*
Y735623D01*
G01X198845Y373701D02*
Y375932D01*
X197938Y376839D01*
G01X200434Y469953D02*
X197809D01*
G01X200434Y474253D02*
Y478345D01*
G01X207178Y580893D02*
X209590D01*
G01X200910Y646850D02*
Y650155D01*
G01X205410Y646850D02*
Y650035D01*
G01X196410Y646850D02*
Y650155D01*
G01X209238Y674373D02*
X209232D01*
X208882Y674023D01*
Y671772D01*
G01X202518Y673273D02*
X204019Y671772D01*
X205732D01*
G01X210023Y712842D02*
X207940Y714925D01*
Y715931D01*
G01X201663Y712694D02*
Y712683D01*
X203440Y714460D01*
Y715898D01*
G01X198940Y715931D02*
Y712499D01*
G01Y735681D02*
Y739081D01*
G01X203440D02*
Y735681D01*
G01X207940Y739081D02*
Y735681D01*
G01X200846Y791695D02*
Y788695D01*
G01Y807872D02*
Y791695D01*
G01X225228Y393540D02*
Y389273D01*
X224108Y388153D01*
Y388029D01*
G01X221228Y393540D02*
X225228D01*
G01X223953Y466817D02*
Y463550D01*
G01X220428Y583822D02*
Y580271D01*
G01X212449Y625977D02*
X215699D01*
G01X221129Y635939D02*
Y633954D01*
X224269Y630814D01*
Y623433D01*
G01X212449Y621977D02*
X215604D01*
G01X221129Y639089D02*
Y642363D01*
G01X212449Y629977D02*
X215948D01*
G01X212449Y637977D02*
X216107D01*
G01X212449Y633977D02*
X215985D01*
G01X218308Y635939D02*
X221129D01*
G01X225179Y639089D02*
Y642614D01*
G01X225237Y671772D02*
X222379D01*
G01X220845Y678356D02*
Y676067D01*
X222379Y674533D01*
Y671772D01*
G01X226610Y713482D02*
Y711772D01*
X225940Y711102D01*
Y708356D01*
G01Y727581D02*
Y724061D01*
G01X221440Y739081D02*
Y735934D01*
G01X216940Y739081D02*
Y736063D01*
G01X212440Y739081D02*
Y735829D01*
G01X212658Y807872D02*
Y791695D01*
G01D02*
Y788695D01*
G01X241848Y353774D02*
Y367154D01*
X243078Y368384D01*
G01X248729Y379173D02*
Y377797D01*
X243078Y372146D01*
Y368384D01*
G01X228729Y385227D02*
Y382323D01*
G01X228242Y466774D02*
Y463681D01*
G01X233152Y583627D02*
X229809D01*
G01X239269Y602633D02*
Y597128D01*
G01X233052Y589327D02*
Y591932D01*
X234362Y593242D01*
X234370D01*
G01X243666Y581930D02*
X245221Y580375D01*
X248845D01*
X250913Y578307D01*
Y569657D01*
X249909Y568653D01*
G01X237451Y649349D02*
Y652761D01*
G01X229584Y649349D02*
Y652668D01*
G01X233584Y649349D02*
Y652519D01*
G01X241670Y649253D02*
Y652558D01*
G01X234473Y678356D02*
Y675223D01*
X236167Y673529D01*
Y671672D01*
G01X239168D02*
X236167D01*
G01X243900Y724662D02*
Y727541D01*
X243940Y727581D01*
G01X234940D02*
Y724325D01*
G01X230440Y739081D02*
Y736412D01*
G01X239440Y739081D02*
Y736140D01*
G01X232343Y807872D02*
Y791695D01*
G01D02*
Y788695D01*
G01X257270Y29334D02*
X257375Y29229D01*
X259673D01*
G01X256729Y382323D02*
X256532Y382520D01*
Y384895D01*
G01X258798Y420929D02*
Y417594D01*
G01X254798Y420929D02*
Y417728D01*
G01X255327Y443592D02*
X252670D01*
G01X251309Y472553D02*
Y469228D01*
G01X246109Y474978D02*
Y472465D01*
G01X251309Y474978D02*
Y472553D01*
G01X253709Y586128D02*
X257109D01*
G01X246816Y583156D02*
X249541D01*
G01X246816Y587156D02*
X249541D01*
G01X249349Y596382D02*
X253187D01*
G01X243666Y583156D02*
Y587156D01*
G01Y583156D02*
Y581930D01*
G01X246293Y648383D02*
X249462D01*
G01X249625Y671772D02*
X252486D01*
G01X247973Y678356D02*
Y675919D01*
X249620Y674272D01*
Y671772D01*
X249625D01*
G01X253340Y724726D02*
Y727181D01*
X252940Y727581D01*
G01X257440Y739081D02*
Y736041D01*
G01X248440Y739081D02*
Y736163D01*
G01X252028Y805904D02*
Y791695D01*
G01X271421Y7319D02*
X272104Y6636D01*
X275503D01*
G01X264904Y390871D02*
X267817D01*
X267993Y390695D01*
G01X273809Y586128D02*
Y587435D01*
X273480Y587764D01*
Y589201D01*
G01X269609Y586128D02*
Y588653D01*
G01X270430Y665576D02*
X271850Y664156D01*
X273051D01*
G01X269709Y668795D02*
Y672575D01*
G01X261473Y678356D02*
Y675701D01*
X263045Y674129D01*
Y671772D01*
G01X265913D02*
X263045D01*
G01X273051Y691038D02*
X270140D01*
G01X265300Y702131D02*
X265966Y702797D01*
X270135D01*
G01X270940Y739081D02*
Y735642D01*
G01X266440Y739081D02*
Y736030D01*
G01X261940Y739081D02*
Y735878D01*
G01X271713Y791695D02*
Y788695D01*
G01Y807872D02*
Y791695D01*
G01X285703Y6670D02*
Y9813D01*
G01X289142Y372173D02*
Y372633D01*
X291686Y375177D01*
G01X288729Y382323D02*
X292729D01*
G01X284729D02*
Y382622D01*
X281864Y385487D01*
Y386178D01*
G01X288687Y385290D02*
X288729Y385248D01*
Y382323D01*
G01X283820Y396266D02*
X284451Y395635D01*
X286710D01*
G01X277775Y399203D02*
Y394712D01*
G01X280730Y393856D02*
Y393863D01*
X279881Y394712D01*
X277775D01*
G01D02*
Y394703D01*
G01X282309Y586128D02*
Y587704D01*
X283649Y589044D01*
X283650D01*
G01X278109Y589238D02*
Y586128D01*
G01X275509Y668795D02*
X278799D01*
X279090Y668504D01*
G01X276201Y664156D02*
X279505D01*
X279785Y663876D01*
G01X278350Y687309D02*
X276201Y689458D01*
Y691038D01*
G01X282516Y717269D02*
X278341D01*
G01X275440Y739081D02*
Y735626D01*
G01X279940Y727581D02*
Y724126D01*
G01X284440Y739081D02*
Y735427D01*
X283990Y734977D01*
G01X288940Y727581D02*
Y724987D01*
X289240Y724687D01*
G01X300040Y459733D02*
Y458989D01*
X301990Y457039D01*
Y431031D01*
X306617Y426404D01*
X309440D01*
G01X299090Y634421D02*
Y633333D01*
X301622Y630801D01*
X311599D01*
X314848Y634050D01*
Y636418D01*
G01X306540Y724266D02*
Y727181D01*
X306940Y727581D01*
G01X297940D02*
Y724377D01*
G01X291790Y735976D02*
Y735983D01*
X293440Y737633D01*
Y739081D01*
G01X302440D02*
Y736579D01*
X302660Y736359D01*
G01X291398Y807872D02*
Y792234D01*
G01X322765Y327721D02*
X321430Y326386D01*
X319225D01*
G01X322210Y336696D02*
Y336701D01*
X323460Y337951D01*
X325700D01*
G01X316392Y338320D02*
X319323D01*
G01X316392Y342418D02*
X321130D01*
G01X316392Y354376D02*
X319666D01*
G01X378830Y386352D02*
X377752D01*
X376250Y384850D01*
Y358938D01*
X358018Y340706D01*
X339859D01*
X337114Y343451D01*
X325380D01*
X322455Y346376D01*
X319807D01*
G01X316392D02*
X319807D01*
G01X321150Y357730D02*
Y357735D01*
X320500Y358385D01*
X316392D01*
Y358376D01*
G01X314860Y367656D02*
Y364606D01*
X314165Y363911D01*
Y362506D01*
G01X316938Y410219D02*
Y412551D01*
X316190Y413299D01*
G01X316963Y463789D02*
Y467655D01*
G01X316956Y475619D02*
Y478833D01*
G01X318288Y527406D02*
X324182D01*
Y527414D01*
G01X307574Y636613D02*
Y633762D01*
G01X314848Y639568D02*
Y641975D01*
X314940Y642067D01*
G01X317580Y719996D02*
Y719991D01*
X317320Y719731D01*
X314940D01*
G01X322940Y716581D02*
Y713800D01*
G01X314940Y716581D02*
Y715053D01*
X315477Y714516D01*
Y712926D01*
G01X311990Y717601D02*
X313010Y716581D01*
X314940D01*
G01X320440Y739081D02*
Y736031D01*
G01X315940Y739081D02*
Y735924D01*
G01X311440Y739081D02*
Y735831D01*
G01X311083Y807872D02*
Y791871D01*
G01X325700Y327721D02*
X322765D01*
G01X330208Y353801D02*
X333726D01*
G01X330158Y349221D02*
X333440D01*
G01X325749Y421643D02*
Y418701D01*
G01Y425585D02*
X327010D01*
X328290Y424305D01*
Y424304D01*
G01X339537Y424850D02*
X336218D01*
G01X325749Y429583D02*
X325740Y429592D01*
Y432017D01*
X325180Y432577D01*
G01X331302Y429920D02*
X333160D01*
X334420Y428660D01*
G01X336010Y531598D02*
X339993D01*
X340182Y531787D01*
G01X336182Y527414D02*
Y531426D01*
X336010Y531598D01*
G01X330182Y527414D02*
X336182D01*
G01X324182D02*
X330182D01*
G01X336688Y537828D02*
X341011D01*
G01X322940Y719731D02*
X325841D01*
G01X333940Y739081D02*
Y735895D01*
G01X329440Y739081D02*
Y735814D01*
G01X324940Y739081D02*
Y736067D01*
G01X338440Y739081D02*
Y737151D01*
X336990Y735701D01*
G01X350411Y30188D02*
Y21277D01*
G01X369040Y316735D02*
Y319129D01*
X364396Y323773D01*
X363900D01*
X363600Y324073D01*
X363404D01*
X362466Y325011D01*
X350350D01*
X349622Y325739D01*
X344720D01*
G01X347079Y409953D02*
Y408896D01*
G01Y409953D02*
Y416323D01*
X342687Y420715D01*
Y424850D01*
G01X354182Y424560D02*
Y421747D01*
X355250Y420679D01*
G01X342687Y424850D02*
X346862D01*
G01X351110Y531835D02*
X346195D01*
G01X354182Y527414D02*
Y528763D01*
X351110Y531835D01*
G01X348182Y527414D02*
Y529848D01*
X346195Y531835D01*
G01X342182Y527414D02*
Y529787D01*
X340182Y531787D01*
G01X346195Y531835D02*
X346147Y531787D01*
X340182D01*
G01X351110Y531835D02*
Y540294D01*
X375016Y564200D01*
X383488D01*
X385410Y566122D01*
G01X353298Y638032D02*
Y633903D01*
G01X347670Y642285D02*
X349840D01*
X351721Y644166D01*
X353667D01*
G01X351722Y659319D02*
X351911Y659130D01*
X355955D01*
G01X347606Y713349D02*
X344780D01*
G01X343730Y724581D02*
Y726508D01*
X342940Y727298D01*
Y727581D01*
G01X351940D02*
Y725787D01*
X350580Y724427D01*
G01X346940Y739081D02*
Y738362D01*
X349422Y735880D01*
X350180D01*
G01X346516Y807872D02*
Y790294D01*
G01X358285Y30188D02*
Y21325D01*
G01X445890Y283317D02*
X448040Y285467D01*
Y304939D01*
X433230Y319749D01*
X405189D01*
X401897Y316457D01*
X379563D01*
X379285Y316735D01*
X369040D01*
G01X362079Y382282D02*
Y387970D01*
X360969Y389080D01*
X360960D01*
G01X360182Y527414D02*
Y529231D01*
X358182Y531231D01*
G01X354182Y527414D02*
X360182D01*
G01X367477Y627663D02*
X365590D01*
X363530Y629723D01*
Y629727D01*
G01X367531Y641507D02*
X371407D01*
G01X367858Y657573D02*
X368406Y658121D01*
X370344D01*
G01X367399Y684652D02*
X368995Y686248D01*
X370283D01*
G01Y690248D02*
X367496D01*
G01X370283Y698248D02*
X364928D01*
X364844Y698332D01*
G01X359112Y695128D02*
X361717D01*
G01X359105Y699128D02*
Y695135D01*
X359112Y695128D01*
G01X359105Y699128D02*
X361786D01*
G01X359105Y703128D02*
Y699128D01*
G01X367480Y705169D02*
Y707884D01*
X371170Y711574D01*
G01X370283Y706248D02*
X368559D01*
X367480Y705169D01*
G01X370283Y694248D02*
X368809D01*
X367614Y693053D01*
G01X360246Y723537D02*
X360250D01*
Y721820D01*
X361350Y720720D01*
G01X359105Y711128D02*
X360113D01*
X361490Y712505D01*
G01X369336Y731459D02*
X366430D01*
G01X369336Y727459D02*
Y731459D01*
G01X360246Y727537D02*
Y730819D01*
G01X357096Y735537D02*
Y732976D01*
G01X360246Y743537D02*
X363359D01*
G01X360246Y739537D02*
X363162D01*
G01X366201Y807872D02*
Y790976D01*
G01X385724Y17519D02*
X382990D01*
G01X377183Y17789D02*
X379940D01*
G01X381218Y629998D02*
X385573D01*
G01X386464Y640267D02*
X383034D01*
G01X370359Y654157D02*
Y658106D01*
X370344Y658121D01*
G01X373494D02*
X378711D01*
X379093Y657739D01*
G01X373509Y654157D02*
X376650D01*
G01X390000Y689724D02*
Y689726D01*
X388570Y691156D01*
X385118D01*
G01X389961Y682218D02*
X389237Y682942D01*
X384758D01*
G01X373433Y678222D02*
X378559D01*
X379791Y679454D01*
G01X370283Y694248D02*
Y690248D01*
G01Y698248D02*
Y702248D01*
G01X384500Y715442D02*
Y714416D01*
X382960Y712876D01*
Y711431D01*
G01X376190Y711259D02*
X383629Y718698D01*
X402023D01*
X406720Y723395D01*
G01X372486Y739459D02*
X375575D01*
G01X376960Y791580D02*
Y788580D01*
G01X378012Y807872D02*
Y797998D01*
X376960Y796946D01*
Y791580D01*
G01X395939Y17519D02*
X399002D01*
G01X395656Y516297D02*
Y512808D01*
X395690Y512774D01*
G01X399837Y516297D02*
X395656D01*
G01X414949Y71906D02*
Y75291D01*
G01X409149Y71906D02*
Y74623D01*
X410713Y76187D01*
G01X413930Y639810D02*
X413397D01*
X412335Y640872D01*
X411313D01*
G01X417427Y704664D02*
Y704764D01*
X416758Y705433D01*
X416412D01*
X415208Y706637D01*
Y706757D01*
X414558Y707407D01*
Y707456D01*
X414550Y707464D01*
G01X405918Y706156D02*
X412105D01*
X413597Y704664D01*
X417427D01*
G01X402540Y710649D02*
X403496Y711605D01*
Y713835D01*
G01X424904Y590818D02*
Y586283D01*
G01X422210Y605343D02*
X422053Y605500D01*
X419221D01*
G01X425151Y604520D02*
Y608429D01*
G01X426315Y619873D02*
X422221D01*
G01X417422Y631847D02*
Y637592D01*
G01X419569Y652732D02*
X422007D01*
G01X426270Y646100D02*
Y646099D01*
X425567Y645396D01*
X423623D01*
G01X419569Y656883D02*
X422026D01*
G01X425146Y672426D02*
X420237D01*
X419569Y673094D01*
G01X430140Y665660D02*
X432180Y663620D01*
Y661479D01*
G01X424700D02*
Y663860D01*
X426100Y665260D01*
Y667884D01*
G01X419569Y677128D02*
Y676988D01*
X420963Y675594D01*
X421100D01*
X421468Y675226D01*
X422222D01*
G01X425173Y688588D02*
X422935Y686350D01*
Y685427D01*
G01X427900Y679709D02*
Y683149D01*
X426085Y684964D01*
Y685427D01*
G01X419569Y681122D02*
Y677128D01*
G01X420577Y700669D02*
Y704664D01*
G01Y696713D02*
X423055D01*
G01X426430Y735126D02*
X426520Y735216D01*
Y739001D01*
X426440Y739081D01*
G01X418440Y735930D02*
Y739081D01*
G01X430940D02*
Y735895D01*
G01X421940Y727581D02*
X421160D01*
X420160Y726581D01*
Y724309D01*
G01X417384Y807872D02*
Y791476D01*
G01X478370Y113070D02*
Y115521D01*
X446959Y146932D01*
X446522D01*
G01X445890Y283317D02*
X447540Y281667D01*
X452880D01*
X452900Y281647D01*
G01X434567Y587579D02*
X437516D01*
G01X440040Y605071D02*
Y608537D01*
G01X440135Y619873D02*
Y615808D01*
G01X442207Y632195D02*
Y633146D01*
X443815Y634754D01*
X443850D01*
G01X438863Y651595D02*
Y655595D01*
G01D02*
X435972D01*
G01X436000Y675706D02*
X435940Y675646D01*
Y675628D01*
X438865D01*
G01Y679628D02*
Y675628D01*
G01Y671628D02*
X435539D01*
G01X438865Y667628D02*
X436445D01*
G01X443940Y735681D02*
Y739081D01*
G01X435440D02*
Y735928D01*
G01X439940Y739081D02*
Y735507D01*
G01X448440Y727581D02*
X447240Y726381D01*
Y724780D01*
G01X437069Y807872D02*
Y791476D01*
G01X452115Y191819D02*
Y195057D01*
G01X450576Y245162D02*
X453620D01*
G01X460351Y249696D02*
Y246291D01*
X459990Y245930D01*
G01X453334Y257495D02*
X453360Y257521D01*
X453502D01*
X455214Y259233D01*
X456800D01*
G01X475795Y281667D02*
X452920D01*
X452900Y281647D01*
G01X463345Y581679D02*
X460236D01*
G01X456387Y587570D02*
Y592295D01*
X455890Y592792D01*
G01X453775Y604522D02*
Y600614D01*
G01X461165Y604060D02*
Y601700D01*
X458665Y599200D01*
X458600D01*
G01X453935Y619873D02*
Y624739D01*
G01X461940Y739081D02*
Y736187D01*
X462440Y735687D01*
G01X452940Y739081D02*
Y736802D01*
X453530Y736212D01*
G01X457440Y727581D02*
Y725663D01*
X458050Y725053D01*
G01X456754Y807872D02*
Y791476D01*
G01X471795Y272867D02*
Y267941D01*
G01X474397Y593964D02*
X471190D01*
G01X469992Y613207D02*
X473294D01*
G01X473153Y617880D02*
Y622451D01*
G01X465580Y641417D02*
X465529Y641366D01*
Y636499D01*
X468938Y633090D01*
X469444D01*
G01X471310Y733811D02*
Y732067D01*
X470430Y731187D01*
Y730748D01*
G01X466440Y727581D02*
Y724465D01*
G01X470940Y739081D02*
Y736878D01*
X471450Y736368D01*
G01X474940Y742231D02*
Y747192D01*
G01X476439Y807872D02*
Y791476D01*
G01X484068Y99980D02*
X483538Y100510D01*
Y103048D01*
G01X488438D02*
Y100123D01*
G01X492955Y103029D02*
Y99440D01*
G01X484280Y198566D02*
X487464D01*
G01X495276Y195553D02*
X497799D01*
X499154Y194198D01*
G01X496080Y191204D02*
Y192067D01*
X495276Y192871D01*
Y195553D01*
G01X492157Y242877D02*
X488816D01*
G01X499405D02*
X495307D01*
G01X493954Y250584D02*
Y247167D01*
X495300Y245821D01*
Y242877D01*
X495307D01*
G01X485719Y279421D02*
X505372D01*
X507489Y281538D01*
G01X497745Y449761D02*
X496904D01*
X495500Y448357D01*
Y447465D01*
G01X483863Y539525D02*
Y538320D01*
X485510Y536673D01*
G01X491100Y644351D02*
Y644344D01*
X490360Y643604D01*
X488615D01*
G01X485465D02*
X484854D01*
X482180Y646278D01*
G01X488513Y639623D02*
X491036D01*
X491380Y639279D01*
G01X493773Y634603D02*
X494887Y636382D01*
X495960Y637455D01*
Y641744D01*
X495900Y641804D01*
G01X491930Y654203D02*
X491418D01*
X488819Y651604D01*
X488615D01*
G01Y647604D02*
X488948D01*
X491860Y650516D01*
X492310D01*
G01X488615Y675604D02*
X491157D01*
G01X488615Y667604D02*
X491044D01*
G01X488615Y671604D02*
X491060D01*
G01X491189Y679656D02*
X491161Y679628D01*
X488615D01*
G01X496855Y687669D02*
X494323D01*
G01X487240Y739081D02*
Y736381D01*
X487940Y735681D01*
G01X492440Y730731D02*
Y730842D01*
X494850Y733252D01*
G01X482940Y739081D02*
Y736746D01*
X483180Y736506D01*
G01X504955Y103029D02*
Y99830D01*
G01X500955Y103029D02*
Y100139D01*
G01X508955Y103029D02*
Y99978D01*
G01X496955Y103029D02*
Y99958D01*
G01X504052Y205296D02*
X499225D01*
G01X505430Y436725D02*
X502494D01*
G01X502038Y522750D02*
X499973D01*
X498920Y523803D01*
G01X512130Y609042D02*
X509765D01*
X509238Y608515D01*
G01X503913Y613598D02*
X508024D01*
G01X507551Y638780D02*
X511852D01*
X511910Y638722D01*
G01X498666Y653012D02*
X496265Y655413D01*
X495888D01*
G01X498060Y660178D02*
X495622D01*
G01X500005Y687669D02*
X506143D01*
X506376Y687436D01*
G01X496597Y706582D02*
X500710D01*
G01X496597Y710582D02*
X499842D01*
G01X496597Y714582D02*
X499452D01*
G01X496597Y718582D02*
Y714582D01*
G01X504140Y739081D02*
Y737599D01*
X502890Y736349D01*
G01D02*
X501690D01*
X500140Y737899D01*
Y739081D01*
G01X496124Y791476D02*
Y807872D01*
G01X520955Y103029D02*
Y100444D01*
G01X516955Y103029D02*
Y100333D01*
G01X512955Y103029D02*
Y100428D01*
G01X524955Y99359D02*
Y103029D01*
G01X512200Y201775D02*
Y204200D01*
G01X521800Y214675D02*
Y218000D01*
X519300Y220500D01*
G01X524500Y204075D02*
Y205206D01*
X526657Y207363D01*
G01X524675Y238308D02*
Y234766D01*
G01X515675Y238308D02*
Y234555D01*
G01X522588Y265584D02*
X529527D01*
G01X526440Y425081D02*
Y422428D01*
G01X515780Y436725D02*
Y434039D01*
G01X524763Y615387D02*
X527828D01*
G01X518940Y726981D02*
Y723513D01*
X518500Y723073D01*
G01X523370Y724131D02*
Y726088D01*
X523940Y726658D01*
Y727581D01*
G01X514940D02*
Y724159D01*
X514901Y724120D01*
G01X515809Y791476D02*
Y807872D01*
G01X542248Y102986D02*
Y106333D01*
G01X536955Y103029D02*
Y100257D01*
G01X528955Y99781D02*
Y103029D01*
G01X532955D02*
Y100604D01*
G01X532500Y204075D02*
Y206500D01*
G01X545424Y226722D02*
X539871D01*
X536178Y223029D01*
X533758D01*
X531929Y221200D01*
Y219388D01*
G01X540132Y234993D02*
X536676D01*
G01X540132Y246993D02*
X536576D01*
G01X540132Y238993D02*
X536476D01*
G01X540132Y242993D02*
X536972D01*
G01X535940Y425081D02*
Y422473D01*
X536440Y421973D01*
G01X541650Y422280D02*
X540940Y422990D01*
Y425081D01*
G01X542438Y611000D02*
Y613723D01*
G01X540048Y629641D02*
X536378D01*
X536068Y629331D01*
Y629326D01*
G01X545634Y617102D02*
X541690D01*
X538400Y613812D01*
Y613804D01*
G01X538781Y620227D02*
X541980D01*
G01X536068Y632476D02*
Y635475D01*
X534558Y636985D01*
G01X539471Y632476D02*
X536068D01*
G01X549940Y716168D02*
X541440D01*
G01Y713018D02*
Y712540D01*
X543193Y710787D01*
G01X541940Y735681D02*
Y739081D01*
G01X531845Y724095D02*
X532940Y725190D01*
Y727581D01*
G01X535494Y791476D02*
Y807872D01*
G01X547248Y103161D02*
Y106582D01*
G01X555938Y100048D02*
Y97292D01*
G01X551454Y100048D02*
Y97154D01*
G01X553909Y204239D02*
Y207401D01*
G01X561834Y210682D02*
X558416D01*
G01X557909Y204239D02*
Y207537D01*
G01X549909Y204239D02*
Y207060D01*
G01X561834Y214682D02*
X558403D01*
X555750Y212029D01*
G01X544500Y204075D02*
Y207000D01*
G01X548347Y274262D02*
X551341D01*
G01X545940Y425081D02*
Y424023D01*
X544500Y422583D01*
G01X553840Y439007D02*
X553879Y438968D01*
X557017D01*
G01X551140Y448752D02*
Y445789D01*
G01X555140Y448752D02*
Y445940D01*
G01X554115Y460656D02*
X556971D01*
G01X554015Y456156D02*
X556771D01*
G01X547340Y479556D02*
Y484025D01*
G01X546938Y611000D02*
Y613828D01*
G01X559199Y601204D02*
X553619D01*
G01X550940Y735681D02*
Y739081D01*
G01X546440D02*
Y735681D01*
G01X555179Y807872D02*
Y791476D01*
G01X560938Y100723D02*
Y97195D01*
G01X572363Y103123D02*
X569559D01*
G01X561909Y204239D02*
Y207393D01*
G01X563615Y460956D02*
X566059D01*
G01X563515Y456156D02*
X565977D01*
G01X588153Y459599D02*
X588150Y459602D01*
Y465363D01*
X578257Y475256D01*
X562340D01*
G01X564213Y528325D02*
X567791D01*
G01X564213Y532225D02*
X567493D01*
G01X571413Y575625D02*
X574876D01*
G01X571513Y583525D02*
X574645D01*
G01X571613Y591325D02*
X574537D01*
G01X568288Y715547D02*
X567667Y716168D01*
X565074D01*
G01X560350Y735807D02*
X559938Y736219D01*
Y739081D01*
X559940D01*
G01X562395Y724557D02*
X564440Y726602D01*
Y727581D01*
G01X573440D02*
Y724053D01*
G01X575513Y103123D02*
X578938D01*
G01X587315Y121836D02*
X583661D01*
G01X587043Y117732D02*
X583829D01*
G01X587043Y132232D02*
X583829D01*
G01X587043Y128232D02*
X583547D01*
G01X589811Y171906D02*
X592917D01*
G01X589736Y179955D02*
X593277D01*
G01X579707Y223818D02*
Y220662D01*
G01X587707Y223818D02*
Y220728D01*
G01X583707Y223818D02*
Y220762D01*
G01X588437Y560970D02*
Y557521D01*
X588540Y557418D01*
G01X582023Y567253D02*
Y571242D01*
G01X586369Y590017D02*
Y585801D01*
G01X578399Y589937D02*
Y585696D01*
G01X582399Y589937D02*
Y583991D01*
X580557Y582149D01*
X578110D01*
G01X582620Y625963D02*
X579500D01*
G01X582620Y622813D02*
X583620D01*
X585500Y620933D01*
Y620926D01*
G01X579999Y616204D02*
Y617930D01*
X582620Y620551D01*
Y622813D01*
G01X587440Y656958D02*
X586550Y657848D01*
X584736D01*
G01X584552Y686026D02*
Y684082D01*
X586052Y682582D01*
X586060D01*
G01X589800Y683909D02*
Y680910D01*
X589050Y680160D01*
G01X579980Y683140D02*
X581402Y684562D01*
Y686026D01*
G01X587963Y724108D02*
Y727558D01*
X587940Y727581D01*
G01X583440Y739081D02*
Y735856D01*
G01X574864Y807872D02*
Y791476D01*
G01X590465Y121836D02*
X592918D01*
X594479Y120275D01*
X595286D01*
X595345Y120216D01*
G01X590842Y158949D02*
X591463D01*
X593537Y161023D01*
G01X590769Y163311D02*
X591249D01*
X593537Y161023D01*
G01X595707Y223818D02*
Y220995D01*
G01X591707Y223818D02*
Y221095D01*
G01X602149Y236295D02*
X605674D01*
G01X604926Y278476D02*
X602843Y276393D01*
X602282D01*
G01Y271893D02*
X604774D01*
G01X604338Y341610D02*
Y338285D01*
G01X604493Y361140D02*
X607137D01*
X608306Y359971D01*
G01X595427Y501238D02*
X605798D01*
G01X599826Y532108D02*
X596751D01*
G01X599826Y536108D02*
X596560D01*
G01X604437Y560970D02*
Y557956D01*
G01X596437Y560970D02*
Y557950D01*
X596050Y557563D01*
G01X599490Y574903D02*
X596530D01*
G01X599490Y578903D02*
X596495D01*
G01X599490Y582903D02*
X596484D01*
G01X599490Y586903D02*
X596209D01*
G01X599457Y591105D02*
X597654D01*
X596401Y589852D01*
G01X596860Y723422D02*
X596940Y723502D01*
Y727581D01*
G01X593004Y735662D02*
X592440Y736226D01*
Y739081D01*
G01X601440D02*
Y735681D01*
G01X605938Y735665D02*
Y739079D01*
X605940Y739081D01*
G01X594550Y791476D02*
Y807872D01*
G01X618623Y104704D02*
Y108918D01*
G01X613640Y339818D02*
Y336986D01*
G01X626558Y418774D02*
X624932Y420400D01*
X621399D01*
G01X617872Y526967D02*
X621760D01*
G01X609300Y534523D02*
Y531638D01*
G01X616829Y546764D02*
X613541D01*
G01X622798D02*
X619979D01*
G01X618946Y542003D02*
Y543777D01*
X619970Y544801D01*
Y546755D01*
X619979Y546764D01*
G01X617437Y561170D02*
Y557769D01*
X620166Y555040D01*
X621840D01*
G01X609060Y552101D02*
X610567D01*
X612937Y554471D01*
Y561170D01*
G01X619302Y636215D02*
X616471D01*
G01X606894Y650572D02*
Y647895D01*
X607620Y647169D01*
G01X614909Y675183D02*
Y671938D01*
G01X617242Y682697D02*
X620764D01*
X621344Y683277D01*
G01X606972Y691954D02*
Y695254D01*
X609682Y697964D01*
X610540D01*
G01X610693Y679333D02*
Y679332D01*
X611953Y678072D01*
X615116D01*
X616591Y679547D01*
X617242D01*
G01X607020Y704644D02*
Y704686D01*
X607410Y705076D01*
X610172D01*
G01X613882Y694818D02*
X615796D01*
X618020Y697042D01*
Y700000D01*
G01X614732Y735517D02*
Y735702D01*
X614940Y735910D01*
Y739081D01*
G01X619590Y735383D02*
Y735682D01*
X619440Y735832D01*
Y739081D01*
G01X608791Y735775D02*
X610440Y737424D01*
Y739081D01*
G01X614235Y791476D02*
Y807872D01*
G01X636224Y132241D02*
X638970D01*
G01X642863Y354885D02*
X642796Y354818D01*
X634440D01*
G01X638964Y457888D02*
X636872D01*
X635120Y456136D01*
G01X638964Y465888D02*
X635545D01*
G01X638964Y461888D02*
X634945D01*
G01X622199Y501238D02*
Y506535D01*
G01X632769Y543561D02*
Y539688D01*
X634190Y538267D01*
G01X632362Y568745D02*
Y565543D01*
G01X621937Y561170D02*
Y558276D01*
G01X634137Y636892D02*
Y639352D01*
G01X630137Y636892D02*
Y639312D01*
G01X623960Y735141D02*
Y739061D01*
X623940Y739081D01*
G01X628380Y735476D02*
Y739021D01*
X628440Y739081D01*
G01X637130Y738905D02*
X639928D01*
G01X633130D02*
X637130D01*
G01X629983Y791476D02*
Y807872D01*
G01X643957Y50675D02*
Y53688D01*
G01X651976Y310053D02*
X653288Y311365D01*
X655122D01*
G01X646013Y354885D02*
Y358110D01*
G01X642863Y358010D02*
Y354885D01*
G01X646113Y349785D02*
X648838D01*
G01X642726Y478679D02*
X646381D01*
G01X642761Y492010D02*
X646105D01*
G01X654755Y487265D02*
X651395D01*
G01X642661Y505210D02*
X646906D01*
G01X638436Y516730D02*
X641842D01*
G01X643012Y568745D02*
Y565243D01*
G01X651437Y572570D02*
Y569676D01*
G01X638470Y636890D02*
Y639290D01*
G01X650928D02*
Y636932D01*
X650970Y636890D01*
G01X646737Y636992D02*
Y639413D01*
G01X642737Y636992D02*
Y639413D01*
G01X651226Y660492D02*
X647487D01*
X647067Y660072D01*
X640931D01*
G01X651226Y666288D02*
Y660492D01*
G01Y720674D02*
X654514D01*
G01X653500Y732583D02*
Y732500D01*
X651226Y730226D01*
Y728674D01*
G01X655947Y50756D02*
Y53677D01*
G01X655122Y315070D02*
Y311365D01*
G01X660138Y365885D02*
Y368829D01*
X660861Y369552D01*
G01X653938Y367910D02*
Y364885D01*
G01X672306Y527718D02*
X668627D01*
G01X659541Y543561D02*
Y536218D01*
X659740Y536019D01*
G01X664998Y617431D02*
X667376D01*
X667610Y617197D01*
G01X654376Y660492D02*
X656971D01*
G01X668000Y676595D02*
X667615Y676980D01*
X664870D01*
G01X659678Y688057D02*
X663040D01*
G01X661479Y791476D02*
Y807872D01*
G01X679927Y50686D02*
Y53881D01*
G01X672752Y366160D02*
Y367811D01*
X671011Y369552D01*
G01X672248Y532470D02*
X668823D01*
G01X675398Y540752D02*
X678315D01*
G01X675398Y536752D02*
X678217D01*
G01X682880Y539585D02*
X687183D01*
G01X683520Y792080D02*
Y789080D01*
G01X685101Y807872D02*
Y798356D01*
X683520Y796775D01*
G01D02*
Y792080D01*
G01X693854Y140140D02*
X691148D01*
G01X693962Y145071D02*
X691314D01*
G01X693962Y149571D02*
X691280D01*
G01X687546Y158536D02*
Y154228D01*
G01X698050Y216868D02*
X700947D01*
G01X698430Y212132D02*
X701687D01*
G01X698050Y221368D02*
X700994D01*
G01X692955Y469943D02*
X692954D01*
X690986Y467975D01*
G01X689017Y481755D02*
X687049Y483723D01*
G01X692955Y477817D02*
X690986Y479786D01*
G01X692955Y481755D02*
X692954D01*
X690986Y483723D01*
G01X689017Y477817D02*
Y477818D01*
X687049Y479786D01*
G01X689017Y473881D02*
Y473880D01*
X687049Y471912D01*
G01X691161Y515905D02*
Y518684D01*
G01X686661Y515905D02*
Y519199D01*
G01X693966Y523712D02*
X697260D01*
X698438Y524890D01*
G01X692526Y547065D02*
X696644D01*
X699660Y550081D01*
X700757D01*
X701023Y549815D01*
G01X707176Y46995D02*
Y50574D01*
G01X700829Y469943D02*
X702797Y467975D01*
G01X700829Y473881D02*
Y473880D01*
X702797Y471912D01*
G01X700829Y477817D02*
Y477818D01*
X702797Y479786D01*
G01X707736Y513230D02*
Y510140D01*
G01X712820Y513434D02*
Y519647D01*
G01X712281Y529130D02*
Y525785D01*
G01X701023Y549815D02*
Y553658D01*
G01X710585Y543908D02*
Y539103D01*
G01X703151Y535399D02*
Y536528D01*
X701171Y538508D01*
X701170D01*
G01X704173Y549815D02*
X708258D01*
G01X704786Y807872D02*
Y791274D01*
G01X712660Y807872D02*
Y791127D01*
X709040Y787507D01*
G01X708723Y807872D02*
Y791092D01*
G01X731566Y445468D02*
Y442136D01*
G01X731227Y500100D02*
X727602D01*
G01X722383Y515757D02*
X719332D01*
G01X724471Y807872D02*
Y789766D01*
X722590Y787885D01*
G01X737223Y454832D02*
X741401D01*
G01X745075Y496800D02*
X748300D01*
G01X734460Y791654D02*
Y795405D01*
X736282Y797227D01*
Y807872D01*
G01X754998Y451032D02*
X757823D01*
G01X754998Y446532D02*
X758223D01*
G01X754998Y455532D02*
X758494D01*
G01X755075Y475000D02*
X756500D01*
X757500Y474000D01*
G01X752075Y492500D02*
Y494025D01*
X749300Y496800D01*
X748300D01*
X-294532Y1044846D03*
X-281332D03*
X-287932D03*
X-267012Y1044916D03*
X-39858Y731383D03*
X-35858D03*
X-31858D03*
X4390Y533777D03*
X13170Y372673D03*
X18340Y366452D03*
X13120Y375871D03*
X16010Y369168D03*
X21530Y368991D03*
X14140Y391826D03*
X18210Y386530D03*
X13950Y388616D03*
X13390Y397543D03*
X14240Y394866D03*
X19450Y550297D03*
X20650Y546243D03*
X20350Y555807D03*
X18960Y572061D03*
X17876Y578422D03*
X16200Y566921D03*
X21881Y595792D03*
X17020Y592934D03*
X13510Y591939D03*
X15850Y610980D03*
X14500Y601957D03*
X11980Y617956D03*
X15349Y614142D03*
X14550Y628297D03*
X13807Y634826D03*
X9300Y631472D03*
X9240Y638699D03*
X17071Y658951D03*
X11680Y656335D03*
X9260Y658321D03*
X14000Y658369D03*
X14170Y653991D03*
X9360Y653943D03*
X33841Y9183D03*
X23987Y12977D03*
X28104Y30414D03*
X24411Y16186D03*
X36848Y25198D03*
X28408Y26414D03*
X34149Y44149D03*
X30282Y34564D03*
X30274Y37714D03*
X36588Y32278D03*
X36567Y73145D03*
X39126Y84631D03*
X34008Y91017D03*
X36567Y107988D03*
X32260Y96899D03*
X38280Y362184D03*
X35750Y364593D03*
X33420Y367309D03*
X23860Y366275D03*
X28250Y438740D03*
X37990Y453022D03*
X28250Y472076D03*
X37990Y520218D03*
X38807Y543539D03*
X34140Y540345D03*
X34240Y536966D03*
X38349Y555730D03*
X33231Y556346D03*
X30672Y551245D03*
X23610Y568111D03*
X34440Y597285D03*
X28112Y591718D03*
X36930Y611082D03*
X28270Y602194D03*
X33140Y602232D03*
X28185Y612088D03*
X35862Y617052D03*
X30744Y617898D03*
X29964Y658951D03*
X24168Y655750D03*
X37920Y651828D03*
X45410Y21563D03*
X54860Y16952D03*
X49890Y30392D03*
X51580Y17595D03*
X42205Y21518D03*
X54800Y25547D03*
X43480Y34592D03*
X45578Y50478D03*
X50981Y58681D03*
X46981Y58690D03*
X44010Y55170D03*
X54981Y59420D03*
X49559Y50577D03*
X41685Y73110D03*
X54101Y74252D03*
X51340Y69181D03*
X46570Y73891D03*
X47510Y109421D03*
X54703Y122796D03*
X46811Y122928D03*
X54062Y257049D03*
X49244Y360352D03*
X40690Y359555D03*
X53340Y393132D03*
X49750Y387305D03*
X51720Y384808D03*
X50840Y395761D03*
X47820Y398827D03*
X49730Y412473D03*
X45530D03*
X52150Y414896D03*
X47900Y414660D03*
X44360Y414915D03*
X49640Y430237D03*
X45410Y430444D03*
X51350Y433695D03*
X47420Y433725D03*
X44360Y433729D03*
X51670Y462885D03*
X47590Y463876D03*
X49830Y465496D03*
X47200Y467262D03*
X49590Y469432D03*
X49625Y478472D03*
Y480972D03*
X49185Y472713D03*
X50330Y497940D03*
X53330D03*
X49645Y491804D03*
Y489304D03*
X47380Y494638D03*
X53622Y509276D03*
X53330Y506417D03*
Y503817D03*
X50330D03*
X53769Y513033D03*
X54988Y518683D03*
X54117Y529098D03*
X49857Y520516D03*
X50630Y529281D03*
X46140Y541712D03*
X41957Y543321D03*
X50140Y550572D03*
X39540Y538464D03*
X50870Y564008D03*
X43467Y555938D03*
X53988Y568748D03*
X49680Y579709D03*
X49620Y574212D03*
X47557Y588971D03*
X44507Y594082D03*
X40908Y589691D03*
X43850Y602797D03*
X39360Y604593D03*
X39370Y600956D03*
X42950Y612487D03*
X50270Y627793D03*
X48540Y624953D03*
X52230Y614907D03*
X51051Y619407D03*
X48060Y621229D03*
X47480Y616848D03*
X50170Y636895D03*
X51038Y643928D03*
X46890Y633564D03*
X53751Y652029D03*
X44640Y651029D03*
X40980Y656396D03*
X49720Y668412D03*
X59524Y25922D03*
X56610Y20553D03*
X66981Y59390D03*
X62981Y59440D03*
X57040Y73421D03*
X60318Y65593D03*
X64190Y72841D03*
X61760Y107321D03*
X55230Y112521D03*
X63900Y112081D03*
X64309Y141882D03*
X68756Y167695D03*
X56190Y170026D03*
X59640Y161376D03*
X57257Y180712D03*
X67853Y180744D03*
X68690Y175589D03*
X55963Y199565D03*
X68930Y197193D03*
X66570Y189983D03*
X57749Y204326D03*
X56383Y218543D03*
X68830Y215817D03*
X63720Y228683D03*
X56936Y223944D03*
X56287Y242872D03*
X63718Y239030D03*
X61945Y267579D03*
X66818Y297483D03*
X57994Y287655D03*
X57624Y366105D03*
X58000Y412641D03*
X64568Y451029D03*
X67568D03*
X70568D03*
X66747Y466363D03*
X64050Y465689D03*
X61183Y465314D03*
X61357Y483392D03*
Y480892D03*
Y477892D03*
X61188Y487117D03*
X56330Y497940D03*
X58830D03*
X61676Y502656D03*
Y500156D03*
X61188Y489617D03*
Y492117D03*
X55982Y494543D03*
X64480Y501596D03*
X65438Y510666D03*
X61033Y510705D03*
X61003Y515110D03*
X65478D03*
X56148Y530809D03*
X62253Y522589D03*
X67369Y522993D03*
X70696Y527237D03*
X67260Y546688D03*
X65900Y566403D03*
X66181Y562149D03*
X63930Y560181D03*
X66262Y553344D03*
X65989Y578115D03*
X66036Y574901D03*
X63670Y576040D03*
X57710Y572918D03*
X57070Y580074D03*
X69766Y582525D03*
X57440Y585607D03*
X68630Y599945D03*
X63300Y621755D03*
X61205Y623870D03*
X63570Y613914D03*
X63610Y618917D03*
X61205Y628870D03*
X63490Y630693D03*
X62160Y644091D03*
X59390Y642906D03*
X56240Y630081D03*
X59530Y631704D03*
X63650Y646957D03*
X61600Y653611D03*
X66880Y761625D03*
X59260Y779815D03*
X58840Y783097D03*
X62290Y779629D03*
X67660Y779452D03*
X62730Y782694D03*
X66860Y782716D03*
X60370Y776861D03*
X64790Y776777D03*
X56500Y789667D03*
X79360Y46044D03*
X82065Y73224D03*
X80845Y106859D03*
X76880Y126528D03*
X72890Y154349D03*
X76030Y156152D03*
X81030Y172605D03*
X78850Y157866D03*
X85010Y171679D03*
X71510Y164548D03*
X74470Y175666D03*
X82553Y185431D03*
X82030Y191733D03*
X75236Y188946D03*
X75359Y201109D03*
X85876Y218939D03*
X78190Y214642D03*
X86172Y213852D03*
X75560Y218513D03*
X73870Y205758D03*
X72150Y225148D03*
X78614Y229920D03*
X79217Y232861D03*
X83390Y235665D03*
X79142Y237920D03*
X86479Y249259D03*
X77239Y260814D03*
X81210Y261337D03*
X81165Y257717D03*
X79544Y267579D03*
X78373Y276029D03*
X78220Y281745D03*
X78207Y279092D03*
X72190Y297395D03*
X82368Y297135D03*
X72368Y287906D03*
X82560Y288099D03*
X82600Y285426D03*
X77368Y299206D03*
X73917Y385722D03*
X74058Y389621D03*
X83084D03*
X74031Y393857D03*
X73868Y397913D03*
X83245D03*
X85951Y410263D03*
X80490Y420690D03*
Y423690D03*
X86050Y428718D03*
X80490Y426690D03*
X79900Y439193D03*
X86050Y425112D03*
Y437470D03*
Y434470D03*
X79900Y445193D03*
Y442193D03*
X85617Y451275D03*
X82617D03*
X86050Y443432D03*
Y446432D03*
X74291Y486665D03*
X83455Y489485D03*
Y491985D03*
X85955Y489485D03*
Y491985D03*
X83455Y494485D03*
X85955D03*
X83536Y498308D03*
X81635Y517104D03*
Y513104D03*
X81174Y503587D03*
X85346Y512295D03*
X73057Y515286D03*
X72635Y508991D03*
X81491Y533191D03*
X81635Y521104D03*
X82031Y523928D03*
X72216Y540493D03*
X80318Y544311D03*
X81585Y536382D03*
X80318Y541026D03*
X84990Y563286D03*
X82140Y560758D03*
X81980Y556851D03*
X81516Y577905D03*
X83030Y582656D03*
X85140Y585213D03*
X73130Y601599D03*
X73180Y611184D03*
X75380Y608914D03*
Y603914D03*
X80630Y689682D03*
X82847Y716068D03*
X82736Y791695D03*
Y788695D03*
X70925D03*
Y791695D03*
X97830Y66508D03*
X98531Y121340D03*
X102257Y167955D03*
X90878Y177967D03*
X90905Y199733D03*
X101449Y194368D03*
X86560Y205852D03*
X96168Y231618D03*
X98700Y234650D03*
X96990Y223043D03*
X101020Y223348D03*
X88399Y244041D03*
X93200Y300734D03*
X99968Y367705D03*
X95968Y367814D03*
X95951Y376661D03*
X98410Y421908D03*
X98470Y418834D03*
X90031Y421693D03*
X90238Y418623D03*
X101650Y428745D03*
Y425552D03*
Y433296D03*
Y436075D03*
X101590Y446203D03*
X101650Y443038D03*
X88617Y451275D03*
X86726Y501997D03*
X88563Y491984D03*
Y489484D03*
Y494484D03*
X86695Y498180D03*
X91458Y511853D03*
X87721Y505817D03*
X92422Y531081D03*
X95660Y531362D03*
X98803Y531597D03*
X97268Y537055D03*
X97366Y542897D03*
X88200Y568111D03*
X98370Y619252D03*
X94070Y618986D03*
Y613841D03*
X97790Y613797D03*
X96200Y616325D03*
X95350Y644088D03*
X95310Y647481D03*
X98480Y646217D03*
X98410Y648878D03*
Y680541D03*
X100223Y733207D03*
X89810Y765905D03*
X97390Y766435D03*
X98590Y782494D03*
X97180Y786472D03*
X94547Y788695D03*
Y791695D03*
X112386Y71874D03*
X115628Y104405D03*
X111220Y160923D03*
X106090Y167615D03*
X112530Y186363D03*
X106760Y175370D03*
X114920Y179082D03*
X108910Y193194D03*
X106517Y210796D03*
X104550Y262359D03*
X104270Y265662D03*
X110230Y360735D03*
X103151Y373340D03*
X110230Y363235D03*
X117030Y389978D03*
X110490Y397362D03*
X116960Y394023D03*
X103750Y402740D03*
X103810Y405876D03*
X103870Y399604D03*
X108235Y401017D03*
X111120Y401084D03*
X115727Y405844D03*
X113412Y404826D03*
X113504Y407673D03*
X107531Y394023D03*
X114207Y417910D03*
Y414910D03*
X105670Y411262D03*
X117980Y451981D03*
X118020Y455079D03*
X114072Y480964D03*
X115516Y485696D03*
X110400Y502223D03*
X110436Y499681D03*
X110472Y496888D03*
X113337Y502080D03*
X113372Y496888D03*
X113301Y499574D03*
X117026Y488316D03*
X108026Y492500D03*
X114372Y518898D03*
X109972Y509321D03*
X112575Y532934D03*
X109972Y519508D03*
X113912Y541144D03*
X114005Y544358D03*
X112627Y536697D03*
X109640Y611890D03*
X109410Y621425D03*
X109500Y616724D03*
X109260Y644687D03*
Y648989D03*
X117790Y667235D03*
X115748Y716275D03*
X106358Y785790D03*
X102421Y782191D03*
X110295Y785734D03*
Y782191D03*
X116370Y785941D03*
X104300Y773100D03*
X106650Y779581D03*
X102421Y785938D03*
X114232Y791695D03*
Y788695D03*
X129860Y14571D03*
X130195Y19162D03*
X131474Y43439D03*
X131068Y76588D03*
X126220Y80364D03*
Y83291D03*
X125480Y91163D03*
X132400Y88153D03*
X129580Y86837D03*
X129780Y92580D03*
X124150Y94643D03*
X128330Y98360D03*
X130350Y130400D03*
Y134167D03*
X126460Y250160D03*
X129650Y250414D03*
X126570Y256194D03*
X129650Y255414D03*
X129660Y279890D03*
X130310Y269174D03*
X130324Y272096D03*
Y277096D03*
X123160Y287060D03*
X129610Y287115D03*
X123960Y283696D03*
X128960D03*
X125050Y384546D03*
X122120Y386736D03*
X126300Y390369D03*
X122729Y398001D03*
X127729D03*
X125229D03*
X128226Y413925D03*
X125726D03*
X123226D03*
X129028Y425593D03*
X121080Y460060D03*
X124040Y459746D03*
X127060Y460040D03*
X126377Y466738D03*
X126260Y470267D03*
X121360Y472028D03*
X118720Y471989D03*
X126072Y480864D03*
X130794Y493910D03*
X133731D03*
X127705Y489431D03*
X125105D03*
X119326Y489706D03*
X121968Y488481D03*
X122018Y516353D03*
X118124Y510811D03*
X133138Y510114D03*
X121644Y509398D03*
X130596Y510042D03*
X124652Y509398D03*
X130703Y512549D03*
X130844Y515128D03*
X128087Y513874D03*
X124279Y523691D03*
X132960Y550005D03*
X125340Y558090D03*
X120300Y572512D03*
X133590Y588438D03*
X130790Y595613D03*
X128240Y666583D03*
X120909Y674490D03*
X132190Y662616D03*
X121070Y670509D03*
X132050Y671817D03*
X129607Y686735D03*
X133607Y686699D03*
X130260Y679836D03*
X132438Y704733D03*
X133490Y695470D03*
X126220Y720949D03*
X120357Y738889D03*
X132334Y732982D03*
X120322Y742187D03*
X123518Y742030D03*
X119900Y754021D03*
X125600Y759000D03*
X125960Y785699D03*
X120090Y780618D03*
X130850Y782456D03*
X118169Y783857D03*
X130660Y785601D03*
X127290Y781982D03*
X122720Y785051D03*
X137500Y25494D03*
X141490Y19267D03*
X137872Y29551D03*
X147427Y30367D03*
X146380Y20345D03*
X147461Y38078D03*
X147497Y42983D03*
X139931Y40842D03*
X139932Y35310D03*
X145210Y60154D03*
X149157Y60010D03*
X135050Y53493D03*
X137540Y58255D03*
X143857Y51943D03*
X149025Y51720D03*
X146558Y74863D03*
X135290Y87664D03*
X140350Y81347D03*
X135640Y134167D03*
X135590Y130449D03*
X147570Y249033D03*
X147160Y242219D03*
X144400Y244061D03*
Y247561D03*
X148330Y258806D03*
X141682Y269829D03*
X143150Y281123D03*
X145200Y276468D03*
X138930Y278965D03*
X148350Y281769D03*
X134540Y267786D03*
X137925Y290987D03*
X137990Y296735D03*
X139950Y293835D03*
X136130Y305640D03*
X137091Y301799D03*
X149020Y303498D03*
X145720Y311336D03*
X135730Y314543D03*
X134768Y319043D03*
X135224Y323543D03*
X146100D03*
X145580Y316836D03*
X136506Y332193D03*
X144058Y376025D03*
X137889Y403348D03*
X141800Y404481D03*
X141847Y401820D03*
X135088Y405060D03*
X135181Y402121D03*
X145295Y404388D03*
X145284Y401507D03*
X135507Y421367D03*
X142239Y422346D03*
X139395Y425090D03*
X138437Y435930D03*
Y438430D03*
X147820Y441929D03*
X147576Y445279D03*
Y447779D03*
Y450279D03*
X138437Y440930D03*
X135300Y468444D03*
X146240Y472111D03*
X139310Y478102D03*
X136470Y481994D03*
X139365Y516636D03*
X139402Y513707D03*
X149477Y532733D03*
X144120Y547577D03*
X146920Y547677D03*
X145020Y576001D03*
X143252Y573105D03*
X145550Y588088D03*
X149050Y588044D03*
X141260Y588175D03*
X141190Y597685D03*
X145880Y584125D03*
X144710Y598135D03*
X136420Y599352D03*
X147753Y627557D03*
X145750Y630254D03*
X148140Y660112D03*
X148487Y676041D03*
X148200Y669205D03*
X140110Y675907D03*
X147750Y687539D03*
X143823Y682907D03*
X134450Y682978D03*
X139158Y686725D03*
X135280Y679212D03*
X138726Y696707D03*
X138198Y712628D03*
X134777Y738726D03*
Y734726D03*
X134753Y726161D03*
X137070Y728012D03*
X144631Y735955D03*
X134720Y742382D03*
X147290Y744113D03*
X145040Y740741D03*
X139600Y781281D03*
X135470Y781697D03*
X135610Y784521D03*
X139680Y784596D03*
X149450Y780429D03*
X146150Y783820D03*
X145570Y780580D03*
X141791Y788695D03*
Y791695D03*
X150787Y9246D03*
X158181Y11978D03*
X153863Y15176D03*
X164139Y13027D03*
X154592Y21173D03*
X157877Y30674D03*
X152810Y29921D03*
X158165Y21300D03*
X150592Y20974D03*
X152412Y38112D03*
X152366Y42983D03*
X156255Y45743D03*
X159861Y36134D03*
X160731Y41038D03*
X162350Y42984D03*
X152789Y53124D03*
X157659Y47891D03*
X157010Y58963D03*
X164550Y61239D03*
X156440Y74863D03*
X161221Y89447D03*
X151618Y83343D03*
X160040Y108844D03*
X164280Y101810D03*
X162130Y129344D03*
X164490Y127110D03*
X159190Y127781D03*
X163518Y243987D03*
X162317Y249877D03*
X152990Y248096D03*
X157690Y249918D03*
X161918Y254287D03*
X160449Y259605D03*
X154546Y256986D03*
X162484Y276599D03*
X152634Y276809D03*
X158583Y285548D03*
X161918Y293869D03*
X161767Y287242D03*
X149721Y292987D03*
X152733Y288517D03*
X158076Y290635D03*
X162181Y303075D03*
X161687Y310355D03*
X154581Y308767D03*
X162063Y327940D03*
X162017Y324389D03*
X159564Y328013D03*
X161513Y317143D03*
X151230Y330164D03*
X150918Y318134D03*
X159285Y336220D03*
X150510Y336306D03*
X156448Y336629D03*
X162071Y336947D03*
X164418Y348187D03*
X152058Y376016D03*
X160058Y375818D03*
X150524Y382808D03*
X165290Y385948D03*
X151820Y385554D03*
X150902Y379714D03*
X160886Y380294D03*
X160710Y384044D03*
X161640Y403286D03*
X162940Y406188D03*
X161577Y436834D03*
X161563Y432521D03*
X154370Y449930D03*
X151145Y469456D03*
X150547Y459363D03*
X163377Y484538D03*
X152554Y494027D03*
X158406Y500016D03*
X162335Y512456D03*
X154126Y524411D03*
X154475Y530422D03*
X162335Y543954D03*
X159185Y537654D03*
X155109Y561153D03*
X164259Y557273D03*
X154140Y577815D03*
X158430Y568437D03*
X161280Y581585D03*
X162786Y568599D03*
X151900Y590454D03*
X156480Y583315D03*
X153527Y597138D03*
X160699Y587904D03*
X150380Y602885D03*
X153712Y610917D03*
X153330Y599935D03*
X153422Y603043D03*
X153955Y620760D03*
X157963Y643289D03*
Y633735D03*
X162668Y631897D03*
X162530Y643235D03*
Y636435D03*
X151915Y675068D03*
X155957Y674813D03*
X160112Y674990D03*
X165012Y675887D03*
X164812Y662579D03*
X151567Y687579D03*
X155650Y681515D03*
X161994Y678445D03*
X159590Y683050D03*
X157287Y678138D03*
X165167Y681311D03*
X152222Y678394D03*
X160101Y687962D03*
X163018Y684381D03*
X164092Y688014D03*
X150840Y682436D03*
X149860Y726626D03*
X154970Y736966D03*
X161981Y730784D03*
X158881D03*
X162640Y743927D03*
X158970D03*
X154400Y744337D03*
X155230Y740259D03*
X163138Y778565D03*
X160480Y777583D03*
X155170Y780656D03*
X164630Y781222D03*
X153320Y783499D03*
X160320Y786346D03*
X149810Y783858D03*
X179235Y7369D03*
X171310Y12450D03*
X171666Y7449D03*
X175280Y12401D03*
X174166Y7449D03*
X166639Y13027D03*
X168961Y27073D03*
X165959Y27133D03*
X173110Y26877D03*
X180907Y27544D03*
X176090Y26906D03*
X180159Y40661D03*
X165336Y46126D03*
X177224Y49101D03*
X174724D03*
X177224Y51601D03*
X174724D03*
X172224Y49101D03*
Y54101D03*
X177224D03*
X174724D03*
X172224Y51601D03*
X169149Y50968D03*
X168040Y61462D03*
X177757Y88271D03*
X168308Y88412D03*
X177733Y91967D03*
X167383Y93147D03*
X180990Y108770D03*
X177210Y97657D03*
X165690Y98835D03*
X171950Y105105D03*
X168850Y99251D03*
X169510Y106579D03*
X173900Y97662D03*
X177680Y101764D03*
X174710Y105699D03*
X167127Y120603D03*
X174213Y120569D03*
X177763Y121057D03*
X168170Y123367D03*
X173170D03*
X180510Y233307D03*
X178040Y228978D03*
X174138Y243873D03*
X171320Y243601D03*
X167467Y243242D03*
X167483Y239914D03*
X177891Y249324D03*
X171668Y256287D03*
X175756Y257668D03*
X173263Y262589D03*
X176301Y262624D03*
X167322Y255855D03*
X167698Y260617D03*
X178929Y262244D03*
X175110Y260412D03*
X175118Y274287D03*
X170617Y267326D03*
X175318Y278687D03*
X170510Y275522D03*
X178025Y279018D03*
X174078Y271435D03*
X170829Y271452D03*
X178941Y270160D03*
X177470Y294933D03*
X180254Y295023D03*
X175162Y293934D03*
X175659Y286984D03*
X178810Y287263D03*
X174148Y289289D03*
X176037Y309845D03*
X180254Y310663D03*
X175921Y301920D03*
X178921D03*
X178812Y324259D03*
X180342Y316469D03*
X175330Y318552D03*
X166189Y335285D03*
X167383Y341306D03*
X177359Y332553D03*
X174876Y336549D03*
X168110Y350642D03*
X177604Y355155D03*
X177720Y352522D03*
X177029Y347811D03*
X177672Y358103D03*
X176058Y376568D03*
X168058Y376035D03*
X167951Y380551D03*
X175290Y389582D03*
X174500Y383383D03*
X178660Y388418D03*
X171934Y386364D03*
X175155Y380727D03*
X180430Y392969D03*
X175663Y386424D03*
X176371Y404721D03*
X180440Y398056D03*
X172760Y406540D03*
X170506Y424127D03*
X175993Y414924D03*
X167527Y420268D03*
X179562Y424001D03*
X173381Y424005D03*
X178232Y430642D03*
X178217Y435317D03*
X173151Y427552D03*
X170683Y436834D03*
X170361Y428595D03*
X172944Y448387D03*
X170444D03*
X177525Y451946D03*
X180125D03*
X178961Y448138D03*
X176220Y448247D03*
X171616Y467804D03*
X179857Y477790D03*
X168370D03*
X169728Y487664D03*
X168189Y514331D03*
X178085Y512456D03*
X173252Y515693D03*
X165707Y506156D03*
X172087Y510536D03*
X169615Y519216D03*
X166297Y532416D03*
X169491Y529702D03*
X166837Y523486D03*
X174395Y527975D03*
X168243Y542706D03*
X174930Y547106D03*
X169157Y548676D03*
X169293Y562358D03*
X173163Y551903D03*
X169444Y558757D03*
X167105Y552882D03*
X178083Y553402D03*
X172889Y562710D03*
X171053Y569411D03*
X175330Y578535D03*
X166930Y578435D03*
X166786Y569056D03*
X175386Y569589D03*
X179740Y568951D03*
X172430Y584035D03*
X177830Y583535D03*
X166570Y583874D03*
X166605Y587860D03*
X178416Y587849D03*
X179532Y600437D03*
X173432D03*
X165832Y600337D03*
Y606037D03*
Y613137D03*
X172532Y619537D03*
X178632Y619437D03*
X165832D03*
X179120Y639615D03*
X169930Y635329D03*
X172510Y639771D03*
X167530Y631935D03*
X174479Y631986D03*
X177038Y647135D03*
X166388Y647435D03*
X171180Y652009D03*
X171270Y655650D03*
X179180Y675205D03*
X174761Y663816D03*
X167810Y668131D03*
X168645Y688064D03*
X165628Y691289D03*
X167315Y684943D03*
X178982Y688631D03*
X171180Y683815D03*
X178278Y705976D03*
Y701976D03*
Y697976D03*
X169268Y705304D03*
X169396Y701006D03*
X169268Y697399D03*
X169619Y693335D03*
X178278Y709976D03*
X180820Y717914D03*
X171154Y715673D03*
X169531Y710542D03*
X175463Y720245D03*
X171689Y728920D03*
X165599Y730476D03*
X174954Y728404D03*
X177920Y739302D03*
X167568Y743335D03*
X177224Y777765D03*
X169350Y785470D03*
X172600Y780150D03*
X169860Y782086D03*
X167350Y778074D03*
X173287Y791695D03*
Y788695D03*
X189235Y7369D03*
X191735D03*
X181735D03*
X194825Y10196D03*
X194861Y12952D03*
X183407Y27544D03*
X188634Y27860D03*
X191596Y27620D03*
X184843Y88467D03*
X191930Y88507D03*
X184928Y91847D03*
X189928D03*
X196653Y91837D03*
X196000Y95568D03*
X195473Y108767D03*
X184170Y95213D03*
X186060Y100103D03*
X196493Y105637D03*
X183013Y98813D03*
X190100Y99701D03*
X188203Y104567D03*
X196010Y125188D03*
X186730Y121202D03*
X194463Y122631D03*
X188821Y232784D03*
X184050Y230139D03*
X183550Y235060D03*
X193677Y243855D03*
X189192Y243061D03*
X184318Y247612D03*
X188899Y240208D03*
X195126Y249955D03*
X184296Y241098D03*
X188899Y236808D03*
X194056Y256697D03*
X193735Y265857D03*
X188442Y252643D03*
X184829Y259139D03*
X181176Y257643D03*
X188658Y256870D03*
X184117Y264852D03*
X181602Y262656D03*
X186873Y263697D03*
X185798Y256760D03*
X186873Y260697D03*
X194693Y259197D03*
Y262197D03*
X190918Y277687D03*
X185991Y279041D03*
X186118Y270787D03*
X188418Y278887D03*
X183440Y269816D03*
X194205Y271034D03*
X191860Y270148D03*
X183198Y278034D03*
X183698Y285693D03*
X193557Y294428D03*
X187812Y286352D03*
X184812Y292979D03*
X186254Y295023D03*
X191054Y294424D03*
X183254Y295023D03*
X192298Y286183D03*
X194771Y302176D03*
X193812Y308619D03*
X195254Y310663D03*
X184754Y302843D03*
X181921Y301920D03*
X191949Y301987D03*
X188810Y301998D03*
X187907Y308784D03*
X186254Y310663D03*
X183254D03*
X193313Y325492D03*
X186296Y326366D03*
X186350Y317116D03*
X196476Y317042D03*
X183228Y317023D03*
X193957Y317064D03*
X191159Y317171D03*
X190557Y325701D03*
X187404Y343998D03*
X192293Y340792D03*
X185195Y332852D03*
X184367Y337792D03*
X192230Y337322D03*
X192040Y333606D03*
X186925Y355812D03*
X192519Y352761D03*
X186908Y352760D03*
X184058Y376479D03*
X195420Y372406D03*
X194231Y390267D03*
X184927Y383876D03*
X192681Y377554D03*
X193590Y383383D03*
X185074Y380726D03*
X194330Y396425D03*
X192676Y402961D03*
X196273Y403152D03*
X182771Y424013D03*
X185271D03*
X182771Y421513D03*
X185271D03*
X190700Y418325D03*
X182132Y418327D03*
X182877Y430662D03*
X182879Y435312D03*
X192527Y429049D03*
X189077Y438281D03*
X192069Y444852D03*
X184523Y441915D03*
X181923Y445044D03*
Y442544D03*
X185747Y487664D03*
X193500Y489796D03*
X181231Y512455D03*
X184843Y533995D03*
X188640Y530667D03*
X191457Y531553D03*
X193466Y546886D03*
X186841Y545372D03*
X181232Y553402D03*
X188654Y573395D03*
X193080Y581235D03*
X191500Y571956D03*
X182480Y566819D03*
X196740Y589735D03*
X181330Y587535D03*
X185032Y606737D03*
X184932Y600537D03*
X185032Y612937D03*
X184932Y619437D03*
X192130Y632235D03*
X184748Y639687D03*
X182480Y634585D03*
X191480Y639135D03*
X182353Y631612D03*
X196410Y650155D03*
X187410Y649715D03*
Y659705D03*
X191910Y650055D03*
X188200Y672526D03*
X196463Y685036D03*
X182163Y684555D03*
X185993Y682670D03*
X191542Y691925D03*
X194508Y704476D03*
X187798Y704513D03*
X181744Y694829D03*
X181950Y698191D03*
X190375Y695624D03*
X185440Y712499D03*
X196144Y712602D03*
X187744Y708356D03*
X191930Y712624D03*
X188566Y722353D03*
X183566D03*
X193566Y722333D03*
X196079Y723943D03*
X194440Y735623D03*
X189940Y735681D03*
X185440D03*
X182674Y730521D03*
X191150Y724108D03*
X186164Y724134D03*
X192949Y771020D03*
X182500Y780786D03*
X189770Y778082D03*
X204785Y13762D03*
X204978Y10605D03*
X201849Y15292D03*
X198577Y15374D03*
X199016Y88434D03*
X206103Y88207D03*
X204003Y91247D03*
X202560Y107797D03*
X210203Y108457D03*
X206273Y98364D03*
X200480Y97687D03*
X212423Y104957D03*
X208908Y96975D03*
X205903Y101477D03*
X199993Y103637D03*
X210623Y121267D03*
X207070Y179744D03*
X207154Y175212D03*
X207041Y184502D03*
X207070Y188978D03*
X212020Y234359D03*
X205535Y234497D03*
Y228682D03*
X211935Y230585D03*
X198296Y232699D03*
X211935Y244085D03*
X198685Y240785D03*
X211935Y237385D03*
Y240785D03*
X205566Y243497D03*
X205271Y240209D03*
X198685Y237385D03*
Y244085D03*
X211028Y255696D03*
X210333Y265197D03*
X208129Y257519D03*
X206144Y252477D03*
X208289Y263639D03*
X210305Y259330D03*
Y262289D03*
X201994Y261248D03*
X200977Y256305D03*
X202402Y263713D03*
X200469Y259139D03*
X201518Y265990D03*
X208226Y269697D03*
X201667Y274542D03*
X199509Y278094D03*
X209449Y281098D03*
X210303Y268227D03*
X206299Y281098D03*
X210303Y271227D03*
X203149Y281098D03*
X201518Y268887D03*
X209449Y287398D03*
Y290548D03*
X203149Y287398D03*
X206299D03*
X196867Y294342D03*
X206299Y290548D03*
X206319Y296863D03*
X203149Y290548D03*
X206299Y293698D03*
Y312598D03*
X198880Y310245D03*
X196812Y308619D03*
X206299Y306298D03*
Y303148D03*
X209449Y312598D03*
X203166Y312577D03*
X202525Y299358D03*
X209300Y322800D03*
X207310Y330149D03*
X206299Y315748D03*
X203058Y315593D03*
X200211Y321446D03*
X200572Y323920D03*
X208000Y325200D03*
X208700Y328000D03*
X200590Y327615D03*
X208485Y332356D03*
X200905Y333776D03*
X201489Y336207D03*
Y339107D03*
X197243Y344518D03*
X206817Y358874D03*
X207274Y353124D03*
X198987Y353137D03*
X206657Y356116D03*
X202823Y376922D03*
X197938Y376839D03*
X206973Y361900D03*
X200439Y390168D03*
X203880Y385272D03*
X205790Y387003D03*
X200488Y396425D03*
X201267Y403294D03*
X210880Y402359D03*
X206380Y402201D03*
X200039Y448750D03*
Y451350D03*
X197809Y469953D03*
X204584Y462478D03*
X197161Y465628D03*
X200434Y478345D03*
X200459Y487253D03*
X208710Y500856D03*
X211379Y501904D03*
X211609Y516553D03*
X205257Y528822D03*
X211287Y528547D03*
X212342Y536729D03*
X199539Y537112D03*
X204309Y539953D03*
X205286Y551130D03*
X211240Y572893D03*
X210040Y576893D03*
X201510Y576885D03*
X197730Y572893D03*
X197709Y567464D03*
X209590Y580893D03*
X210790Y566926D03*
X209940Y584893D03*
X197230Y595335D03*
X198890Y584105D03*
X207178Y591595D03*
X211760Y610915D03*
X207476Y608936D03*
X207010Y602472D03*
X196907Y605012D03*
X197030Y598535D03*
X204024Y604135D03*
Y609135D03*
X208904Y611515D03*
X200380Y629085D03*
X199786Y618893D03*
X211862Y617709D03*
X202510Y624005D03*
X197230Y615435D03*
X197130Y626135D03*
X208904Y616515D03*
X197480Y639815D03*
X203065Y638700D03*
X205221Y630886D03*
X200910Y659735D03*
Y650155D03*
X205410Y650035D03*
X209238Y674373D03*
X202450Y663633D03*
X199510Y663158D03*
X205410Y661200D03*
X211560Y670575D03*
X202518Y673273D03*
X197889Y671226D03*
X210824Y692266D03*
X199590Y682868D03*
X197582Y703474D03*
X200692Y704081D03*
X199350Y692724D03*
X211236Y695586D03*
X197243Y697899D03*
X210023Y712842D03*
X201663Y712694D03*
X198940Y712499D03*
X198566Y722353D03*
X209017Y722344D03*
X203611Y722303D03*
X205440Y712510D03*
X211897Y723870D03*
X201411Y708231D03*
X212440Y735829D03*
X198940Y735681D03*
X207940D03*
X203440D03*
X205883Y724373D03*
X200817Y724180D03*
X199760Y763929D03*
X202050Y784919D03*
X206210Y771577D03*
X212350Y773283D03*
X200846Y788695D03*
Y791695D03*
X225990Y21219D03*
X221990D03*
X222290Y45504D03*
X226290D03*
X221310Y51103D03*
X225310D03*
X221600Y66317D03*
X225600D03*
X213190Y88414D03*
X220276Y88440D03*
X214573Y93771D03*
X215773Y90147D03*
X222983Y91587D03*
X220200Y93561D03*
X226620Y89385D03*
X219095Y108675D03*
X217040Y103121D03*
X214320Y101978D03*
X220983Y106174D03*
X213908Y96975D03*
X219510Y101338D03*
X226713Y122007D03*
X228138Y125802D03*
X226010Y233542D03*
X217135Y230585D03*
Y244085D03*
X226010Y240342D03*
X217135Y240785D03*
Y237385D03*
X227517Y244187D03*
X219772Y252659D03*
X215761Y252833D03*
X224794Y256754D03*
X218153Y260697D03*
Y263697D03*
X223929Y263639D03*
X216512Y258490D03*
X225973Y262197D03*
X216109Y265139D03*
Y262139D03*
X218508Y256664D03*
X225973Y265197D03*
Y259197D03*
X225199Y281098D03*
X216109Y274139D03*
X212599Y281098D03*
X218899D03*
X224357Y273228D03*
X216109Y271139D03*
X215749Y281098D03*
X213138Y274187D03*
X212599Y290548D03*
X225199Y287398D03*
X212599Y293698D03*
X222049Y290548D03*
X225160Y293676D03*
X225199Y290548D03*
Y284248D03*
X222049Y287398D03*
X212599D03*
X215749Y290548D03*
Y293698D03*
Y287398D03*
X225199Y309448D03*
Y299998D03*
Y303148D03*
X222049Y309448D03*
X212599Y299998D03*
Y303148D03*
X222049Y312598D03*
X218899Y309448D03*
X222049Y303148D03*
X225199Y306298D03*
Y312598D03*
X222049Y306298D03*
X218899D03*
X222049Y299998D03*
X212610Y306305D03*
X218899Y299998D03*
Y303148D03*
X218947Y312617D03*
X215100Y322700D03*
X217129Y327207D03*
X215085Y325649D03*
X212600Y319100D03*
X217129Y324207D03*
X224949Y328707D03*
X225199Y315748D03*
X224585Y322992D03*
X224711Y325922D03*
X217129Y336207D03*
X217067Y339542D03*
X217129Y333207D03*
X223010Y344242D03*
X223166Y338842D03*
X222911Y333155D03*
X224996Y334617D03*
X223095Y336241D03*
X221280Y340579D03*
X228057Y352837D03*
X222777Y353066D03*
X214888Y352909D03*
X222974Y356134D03*
X214657Y356205D03*
X214007Y362701D03*
X222225Y364031D03*
X227745Y368007D03*
X223561Y385108D03*
X214008Y385165D03*
X221438Y390655D03*
X224108Y388029D03*
X214786Y388603D03*
X218090Y390891D03*
X216633Y384989D03*
X215120Y399654D03*
X214406Y395539D03*
X223085Y401702D03*
X213710Y402237D03*
X224730Y418003D03*
X221406Y436560D03*
X227816Y442675D03*
X218483Y442550D03*
X221858Y442300D03*
X225024Y442467D03*
X226276Y460704D03*
X213994Y466054D03*
X228242Y463681D03*
X223953Y463550D03*
X212809Y479053D03*
X215409Y479253D03*
X222419Y479933D03*
X218040Y473853D03*
X223786Y476638D03*
X226255Y472579D03*
X216209Y488853D03*
X213209D03*
X224209Y494928D03*
X219309Y489353D03*
X222209D03*
X224209Y491853D03*
X217609Y516353D03*
X219328Y528823D03*
X223376Y523322D03*
X215946Y544202D03*
X221591Y563371D03*
X223561Y561475D03*
X218950Y565589D03*
X223453Y578087D03*
X216590Y570850D03*
X220428Y580271D03*
X227100Y580916D03*
X218859Y593093D03*
X225100Y597453D03*
X219960Y596373D03*
X219296Y604811D03*
X219960Y601373D03*
X215699Y625977D03*
X215604Y621977D03*
X215985Y633977D03*
X216107Y637977D03*
X215948Y629977D03*
X221129Y642363D03*
X228290Y629893D03*
X218308Y635939D03*
X225179Y642614D03*
X215768Y671993D03*
X218240Y674433D03*
X225237Y671772D03*
X212635Y665604D03*
X224289Y680081D03*
X224360Y684366D03*
X213365Y692151D03*
X224060Y690317D03*
X224336Y687758D03*
X223707Y695436D03*
X220580Y692876D03*
X223741Y700554D03*
X221340Y697995D03*
X226610Y713482D03*
X217530Y715305D03*
X221320Y720698D03*
X213310Y719064D03*
X222710Y713706D03*
X216820Y723301D03*
X227650Y720791D03*
X224410Y719970D03*
X216940Y736063D03*
X221440Y735934D03*
X225940Y724061D03*
Y733671D03*
Y736437D03*
X218270Y785657D03*
X220960Y778561D03*
X226670Y773299D03*
X220532Y788695D03*
Y791695D03*
X212658D03*
Y788695D03*
X241990Y21219D03*
X229990D03*
X242290Y45504D03*
X230290D03*
X229310Y51103D03*
X233290Y51045D03*
X237310Y50983D03*
X241310D03*
X237600Y66317D03*
X241600D03*
X229600D03*
X233600D03*
X236360Y93931D03*
X236812Y88698D03*
X229725Y88719D03*
X235113Y91307D03*
X231013Y91547D03*
X243373Y88767D03*
X239563Y92077D03*
X243730Y103057D03*
X240355Y108757D03*
X239500Y100925D03*
X231910Y105731D03*
X235190Y96905D03*
X230643Y108497D03*
X234243Y100156D03*
X233083Y94817D03*
X237773Y103607D03*
X242913Y106157D03*
X233268Y121742D03*
X233138Y125802D03*
X230749Y160807D03*
X230650Y164566D03*
X230890Y169424D03*
X231000Y173381D03*
X230100Y187389D03*
X230140Y197240D03*
X232948Y234047D03*
X236710Y244042D03*
X242460Y237591D03*
X237654Y249719D03*
X231710Y243642D03*
Y240242D03*
X231749Y265139D03*
X239569Y257639D03*
X241613Y262197D03*
X239569Y266639D03*
X241613Y259197D03*
X237594Y252754D03*
X241613Y265197D03*
X233793Y266697D03*
Y257697D03*
X233904Y252772D03*
X239569Y263639D03*
X233793Y263697D03*
X231749Y262139D03*
X233793Y260697D03*
X239569Y260639D03*
X231749Y259139D03*
X240910Y274742D03*
X233793Y269697D03*
X234649Y281098D03*
X237865Y281131D03*
X239569Y269639D03*
X232118Y271587D03*
X241613Y271197D03*
Y268197D03*
X228821Y274197D03*
X231648Y274243D03*
X237799Y290548D03*
Y284248D03*
X231499Y287398D03*
X231450Y290583D03*
X237760Y293692D03*
X237799Y287398D03*
X240949Y290548D03*
Y287398D03*
X231499Y284248D03*
Y296848D03*
Y293698D03*
X240949Y296848D03*
X237800Y299998D03*
X231499Y309448D03*
Y299998D03*
X237799Y312598D03*
X231499D03*
X240949Y309448D03*
X237799Y303148D03*
X234649D03*
X237799Y306298D03*
X240925Y306257D03*
X240949Y299998D03*
Y303148D03*
X241258Y319123D03*
X231567Y321742D03*
X232782Y327096D03*
X230725Y325649D03*
X238545Y327149D03*
X240374Y328960D03*
X240511Y325517D03*
X240692Y344204D03*
X233055Y339936D03*
X230725Y331649D03*
X238548Y333149D03*
X230725Y334547D03*
X240598Y334642D03*
X240218Y338010D03*
X231144Y338225D03*
X238560Y336136D03*
X232769Y333207D03*
X232804Y336181D03*
X239290Y340428D03*
X233697Y353961D03*
X238084Y355992D03*
X228419Y356855D03*
X233635Y357082D03*
X230010Y373300D03*
X237578Y369584D03*
X233136Y367070D03*
X243078Y368384D03*
X231257Y362218D03*
X243940Y390885D03*
X236687Y385234D03*
X232172Y388814D03*
X228729Y385227D03*
X241451Y392147D03*
X236412Y387722D03*
X231223Y391424D03*
X239546Y390528D03*
X239228Y393291D03*
X236430Y393470D03*
X232647Y396011D03*
X228906Y424560D03*
X228713Y416525D03*
Y419525D03*
X240599Y440053D03*
X231870Y439511D03*
X228906Y433560D03*
Y427560D03*
Y436560D03*
X231885Y442252D03*
X235319Y464362D03*
X231461Y462591D03*
X243471Y460292D03*
X238430Y460338D03*
X233309Y472553D03*
X237609Y472453D03*
X241909Y472553D03*
X234209Y480953D03*
X228604Y479682D03*
X242915Y576539D03*
X243209Y574018D03*
X239269Y597128D03*
X229809Y583627D03*
X229269Y597682D03*
X242830Y597415D03*
X234370Y593242D03*
X242796Y589749D03*
X236780Y628738D03*
X229199Y642180D03*
X243693Y632254D03*
X238420Y642148D03*
X234500Y637685D03*
X243743Y636514D03*
X229584Y652668D03*
X237451Y652761D03*
X241670Y652558D03*
X233584Y652519D03*
X243596Y671772D03*
X229895Y671672D03*
X239168D03*
X237275Y679609D03*
X240493Y692678D03*
X239084Y696252D03*
X233954Y697395D03*
X236120Y704173D03*
X238348Y712469D03*
X242680Y712337D03*
X234960Y714064D03*
X239210Y720040D03*
X234910Y720816D03*
X243900Y724662D03*
X239440Y736140D03*
X230440Y736412D03*
X234940Y724325D03*
Y733355D03*
X243940Y736412D03*
X239500Y733523D03*
X230440Y724242D03*
X234940Y736392D03*
X236180Y786517D03*
X242230Y774803D03*
X234011Y772902D03*
X240217Y788695D03*
Y791695D03*
X232343D03*
Y788695D03*
X249990Y21219D03*
X245990D03*
X257270Y29334D03*
X258300Y22289D03*
X250290Y45504D03*
X246290D03*
X258103Y53688D03*
X257500Y56117D03*
X245310Y50867D03*
X249300Y50862D03*
X253490Y53736D03*
X253810Y63244D03*
X245600Y66317D03*
X249600D03*
X246073Y92197D03*
X256573Y94097D03*
X247870Y105821D03*
X252683Y105867D03*
X253558Y95038D03*
X256133Y99347D03*
X248558Y95038D03*
X259030Y123727D03*
X259443Y120773D03*
X249453Y114307D03*
X255287Y226709D03*
X254221Y230582D03*
X256492Y222466D03*
X254181Y234521D03*
X257950Y236924D03*
X254418Y240407D03*
X255209Y260639D03*
X255359Y266557D03*
X247389Y259139D03*
X256553Y256881D03*
X249433Y263697D03*
Y260697D03*
X256916Y262609D03*
X247389Y262139D03*
X257253Y259197D03*
X259518Y252358D03*
X249433Y257697D03*
X246467Y255442D03*
X257046Y279607D03*
X255205Y272755D03*
X244109Y277996D03*
X244099Y281098D03*
X254234Y281622D03*
X250399Y281098D03*
X247389Y268139D03*
X257253Y271197D03*
Y268197D03*
X250399Y296848D03*
X253611Y293765D03*
X250399Y290548D03*
X244099Y284248D03*
X250399D03*
X244099Y293698D03*
X244110Y290505D03*
X257447Y287117D03*
X244099Y287398D03*
X250399D03*
X253549Y290548D03*
X247249Y296848D03*
X244099D03*
X258380Y295984D03*
X254334Y298728D03*
X247249Y303148D03*
X244118Y309387D03*
X254007Y306819D03*
X244118Y303187D03*
X257057Y309636D03*
X244099Y299998D03*
X247249Y306298D03*
X257418Y303533D03*
X258590Y311560D03*
X247281Y315727D03*
X247290Y327694D03*
X254631Y324716D03*
X254998Y329779D03*
X256276Y322652D03*
X247789Y322910D03*
X254905Y327213D03*
X250401Y315713D03*
X253710Y315669D03*
X248509Y339207D03*
X254819Y332435D03*
X250466Y344381D03*
X245691Y341215D03*
X247218Y333049D03*
X255009Y338318D03*
X246685Y337357D03*
X255124Y335244D03*
X247025Y330512D03*
X251334Y352857D03*
X259444Y354291D03*
X246265Y355855D03*
X251491Y357134D03*
X256588Y359005D03*
X244595Y363535D03*
X250661Y384780D03*
X256532Y384895D03*
X247065Y385398D03*
X244546Y385315D03*
X253762Y385255D03*
X247797Y406029D03*
X250297D03*
X252797D03*
X245297D03*
X244196Y419610D03*
Y417010D03*
X258798Y417594D03*
X254798Y417728D03*
X244196Y427610D03*
Y425010D03*
Y433010D03*
Y435610D03*
X254813Y427018D03*
X252670Y443592D03*
X246465Y464893D03*
X251780Y460883D03*
X257568Y461513D03*
X255509Y472253D03*
X246109Y472465D03*
X251309Y472553D03*
X245609Y517182D03*
X252036Y582131D03*
X245860Y575049D03*
X249909Y568653D03*
X259678Y581553D03*
X249541Y587156D03*
X253709Y586128D03*
X249541Y583156D03*
X253187Y596382D03*
X246639Y608378D03*
Y605778D03*
X249640Y602519D03*
X246639Y624378D03*
Y621778D03*
Y616378D03*
Y613778D03*
X249013Y628514D03*
X251803Y636704D03*
X254773Y644424D03*
X254303Y636744D03*
X256463Y639364D03*
X252173Y644344D03*
X249083Y636664D03*
X256513Y642494D03*
X246553Y636684D03*
X249462Y648383D03*
X257271Y671772D03*
X252486D03*
X253398Y692357D03*
X244780Y682521D03*
X250795Y703150D03*
X251451Y697465D03*
X259170Y705138D03*
X254940Y712381D03*
X258570Y722981D03*
X255310Y715915D03*
X248530Y721829D03*
X250630Y719457D03*
X253340Y724726D03*
X248440Y736163D03*
X257440Y736041D03*
X252940Y736318D03*
X248770Y724631D03*
X252940Y733567D03*
X256650Y778342D03*
X247900Y778823D03*
X252470Y785797D03*
X252028Y791695D03*
X271421Y7319D03*
X262955Y12663D03*
X273660Y23037D03*
X268579Y19365D03*
X265934Y16522D03*
X273645Y27712D03*
X266111Y29229D03*
X265789Y20990D03*
X268809Y16400D03*
X274990Y16396D03*
X268372Y40782D03*
X265872D03*
X272010Y40553D03*
X274510D03*
X273873Y63167D03*
X269793D03*
X261750Y75886D03*
X274580Y74281D03*
X269920Y74318D03*
X272440Y76177D03*
X268080Y76416D03*
X267703Y89397D03*
X272245Y89585D03*
X263703Y93847D03*
X271133Y92787D03*
X265830Y102566D03*
X264210Y96914D03*
X273973Y97645D03*
X262473Y106937D03*
X263683Y99902D03*
X268702Y107928D03*
X269010Y121648D03*
X264980Y121886D03*
X269620Y243240D03*
X269192Y248209D03*
X272242Y244842D03*
X272620Y238653D03*
X260108Y240376D03*
X267118Y245587D03*
X271458Y241347D03*
X270260Y237037D03*
X266187Y249852D03*
X267020Y257079D03*
X263029Y259139D03*
X265073Y266697D03*
X263029Y265139D03*
X271811Y256687D03*
X271898Y263173D03*
X273521Y265849D03*
X260068Y262187D03*
X263268Y262370D03*
X263774Y256464D03*
X272464Y259964D03*
X269263Y252800D03*
X271944Y278363D03*
X264386Y280407D03*
X265944Y278363D03*
X274886Y272587D03*
X273386Y280407D03*
X270444Y270543D03*
X271886Y272587D03*
X265886Y271718D03*
X268886Y272587D03*
X268944Y278363D03*
X263029Y271139D03*
Y268139D03*
X273444Y270543D03*
X274944Y278363D03*
X270386Y280407D03*
X267386D03*
X262886Y288227D03*
X264386Y296047D03*
X267386D03*
X261463Y296111D03*
X265825Y293987D03*
X268867Y293942D03*
X270444Y286183D03*
X265768Y287546D03*
X273444Y286183D03*
X273618Y295387D03*
X271811Y303313D03*
X271944Y309643D03*
X262944D03*
X261386Y311687D03*
X260045Y309615D03*
X268944Y309643D03*
X265944Y309640D03*
X261915Y302033D03*
X269380Y302736D03*
X264501Y303109D03*
X266939Y303281D03*
X274303Y303413D03*
X259820Y303800D03*
X267268Y311642D03*
X264287Y311687D03*
X270518Y311637D03*
X274832Y309687D03*
X262035Y322679D03*
X267883Y325837D03*
X265318Y326487D03*
X270525Y325754D03*
X262201Y328491D03*
X272967Y325842D03*
X275517D03*
X267030Y330147D03*
X262700Y325494D03*
X268502Y344181D03*
X263576Y340898D03*
X274701Y333804D03*
X270326Y335795D03*
X270485Y339030D03*
X264015Y336151D03*
X263173Y331794D03*
X267943Y339617D03*
X270293Y330540D03*
X272964Y330669D03*
X262379Y338103D03*
X262247Y334502D03*
X270071Y333021D03*
X272263Y334222D03*
X272352Y340900D03*
X269456Y355353D03*
X269117Y352876D03*
X269886Y358753D03*
X260536Y374216D03*
X270293Y363972D03*
X273477Y385100D03*
X261663Y385193D03*
X267993Y390695D03*
X270796Y386643D03*
X266882Y388165D03*
X261539Y387755D03*
X264421Y384812D03*
X275497Y390758D03*
X263419Y393450D03*
X265162Y401391D03*
X272220Y401343D03*
X262798Y417886D03*
X271720Y422587D03*
X265532Y422648D03*
X269630Y424884D03*
X274180Y424966D03*
X266822Y443297D03*
X275256Y445753D03*
X271035Y443051D03*
X273735Y443034D03*
X273509Y471649D03*
X263807Y461234D03*
X260609Y472453D03*
X264909Y472553D03*
X269109Y472353D03*
X275452Y483219D03*
X267741Y491608D03*
X263924Y491754D03*
X269609Y576413D03*
X274309Y574653D03*
X261175Y569054D03*
X263792Y574203D03*
X268009Y570953D03*
X273480Y589201D03*
X269609Y588653D03*
X268717Y606015D03*
X261967Y608638D03*
Y605638D03*
X260064Y602993D03*
X261967Y614638D03*
X263467Y626638D03*
X269428Y622966D03*
X261967Y617638D03*
X263467Y623638D03*
X273938Y633084D03*
X273674Y640095D03*
X273548Y636471D03*
X266610Y654171D03*
X270040Y651241D03*
X269640Y655290D03*
X270430Y665576D03*
X269709Y672575D03*
X265913Y671772D03*
X261890Y664761D03*
X265550Y668415D03*
X274360Y673831D03*
X270140Y691038D03*
X272460Y687889D03*
X267240Y682519D03*
X269420Y677062D03*
X265300Y702131D03*
X272650Y693742D03*
X269410Y706003D03*
X267124Y707892D03*
X273510Y699749D03*
X266170Y694826D03*
X260680Y712988D03*
X271210Y718000D03*
X264600Y723086D03*
X270940Y722080D03*
X275440Y735626D03*
X261940Y735878D03*
X266440Y736030D03*
X270940Y735642D03*
X263430Y770417D03*
X264340Y778780D03*
X272175Y783074D03*
X271713Y788695D03*
Y791695D03*
X259902D03*
X280699Y13908D03*
X278199D03*
X282180Y10253D03*
X285703Y9813D03*
X278660Y10073D03*
X278305Y23057D03*
X280699Y16408D03*
X278199D03*
X278307Y27707D03*
X284505Y30676D03*
X287766Y21289D03*
X287476Y37125D03*
X277472Y34959D03*
Y37459D03*
X280072Y34330D03*
X275766Y52772D03*
X275800Y50212D03*
X290823Y63167D03*
X282023D03*
X277853D03*
X287270Y75018D03*
X283870Y74724D03*
X279100Y74447D03*
X289738Y76173D03*
X285543Y76867D03*
X281400Y75938D03*
X276969Y76247D03*
X277000Y88323D03*
X286263Y88677D03*
X276603Y92119D03*
X287423Y91857D03*
X287595Y106109D03*
X279010Y104889D03*
X286710Y95717D03*
X281200Y98369D03*
X289720Y96094D03*
X278760Y101061D03*
X287599Y108831D03*
X278880Y108482D03*
X278354Y244281D03*
X290154Y244007D03*
X285934Y243931D03*
X282178Y244005D03*
X279161Y237817D03*
X289254Y255688D03*
X286492Y258364D03*
X283660Y251542D03*
X281954Y255588D03*
X288954Y260788D03*
X276328Y264687D03*
X276904Y252550D03*
X282166Y262922D03*
X281945Y260231D03*
X278811Y259135D03*
X279336Y264795D03*
X277886Y272587D03*
X280886D03*
X286010Y276042D03*
X282867Y281142D03*
X276444Y270543D03*
X282309Y270435D03*
X279444Y270543D03*
X277944Y278363D03*
X279386Y280407D03*
X276386D03*
X281767Y277742D03*
X276507Y295816D03*
X290363Y286082D03*
X286132Y285953D03*
X281818Y290787D03*
X278918Y286887D03*
X276444Y286183D03*
X279386Y311687D03*
X285890Y311357D03*
X277020Y302298D03*
X282337Y308217D03*
X281859Y310862D03*
X277816Y309678D03*
X279754Y303269D03*
X276386Y311687D03*
X281461Y321744D03*
X280776Y326412D03*
X286071Y329184D03*
X278067Y325842D03*
X282167Y324242D03*
X288466Y325343D03*
X285704Y321809D03*
X275660Y338857D03*
X281212Y338079D03*
X277288Y334282D03*
X282234Y333792D03*
X285794Y339063D03*
X281205Y340997D03*
X279718Y333694D03*
X275602Y343811D03*
X289191Y341348D03*
X290190Y352480D03*
X278943Y346914D03*
X277718Y352687D03*
X282818D03*
X286711Y352668D03*
X283140Y346082D03*
X286020Y356454D03*
X277040Y376172D03*
X279863Y367513D03*
X286550Y374402D03*
X281450Y373151D03*
X276687Y385100D03*
X288687Y385290D03*
X281864Y386178D03*
X284687Y386769D03*
X285390Y390550D03*
X288220Y389630D03*
X283820Y396266D03*
X281142Y402379D03*
X287067Y402358D03*
X280730Y393856D03*
X276400Y422341D03*
X280010Y422279D03*
X281190Y424966D03*
X278080Y424760D03*
X286210Y444926D03*
X289630Y444828D03*
X283212Y442286D03*
X286100Y442298D03*
X288742Y442090D03*
X287970Y446705D03*
X282000Y444966D03*
X279112Y444954D03*
X276626Y442913D03*
X279990Y442071D03*
X276809Y471853D03*
X276347Y459741D03*
X280210Y460762D03*
X287567Y470649D03*
Y467649D03*
X280380Y467284D03*
X278990Y464793D03*
X284332Y472834D03*
X282298Y483803D03*
X277470Y481197D03*
X280970D03*
X288009Y495653D03*
X280874Y556139D03*
X279658Y574443D03*
X285530Y573002D03*
X291066Y590488D03*
Y593088D03*
X283650Y589044D03*
X278109Y589238D03*
X287997Y649064D03*
X280880Y650295D03*
X278699Y656491D03*
X289171Y661908D03*
X279090Y668504D03*
X279785Y663876D03*
X289365Y665845D03*
Y673719D03*
X279843Y675688D03*
X288880Y689467D03*
X278350Y687309D03*
X275710Y681593D03*
X289248Y680521D03*
X275560Y697804D03*
X279060Y693306D03*
X284760Y707022D03*
X286798Y704143D03*
X278370Y705093D03*
X277475Y695723D03*
X278341Y717269D03*
X289060Y722193D03*
X281830Y722184D03*
X285130Y714433D03*
X275880Y722141D03*
X285880Y722268D03*
X289150Y718548D03*
X279940Y724126D03*
X289240Y724687D03*
X283990Y734977D03*
X280210Y734805D03*
X288390Y734796D03*
X284020Y724956D03*
X284532Y747493D03*
X275627Y777692D03*
X281930Y773190D03*
X286722Y785929D03*
X279587Y791695D03*
X295307Y41260D03*
X295390Y44017D03*
X295610Y50299D03*
X295560Y52907D03*
X294903Y63167D03*
X306693D03*
X303053D03*
X298883D03*
X292313Y76345D03*
X305880Y76361D03*
X299220Y76196D03*
X302953Y76167D03*
X295867Y76567D03*
X296093Y88477D03*
X302853Y89057D03*
X301870Y92072D03*
X296870D03*
X294800Y100593D03*
X295490Y97209D03*
X302370Y95215D03*
X291927Y102991D03*
X293505Y94965D03*
X296927Y102991D03*
X303220Y98397D03*
X299590Y121289D03*
X299850Y124708D03*
X293873Y130357D03*
X302930Y132994D03*
X300118Y250987D03*
X296176Y249585D03*
X299776Y248010D03*
X295910Y266706D03*
X295110Y262961D03*
X301511Y262204D03*
X300477Y265010D03*
X296210Y253187D03*
X300310Y253842D03*
Y257242D03*
X292710Y266542D03*
X295307Y275439D03*
X294510Y280709D03*
X301473Y282650D03*
X297810Y280709D03*
X301723Y279150D03*
X297782Y291966D03*
X295010Y286767D03*
X301182Y291966D03*
X294382D03*
X305132Y286867D03*
X298332D03*
X301732D03*
X297668Y300709D03*
X294888Y304456D03*
X294781Y309788D03*
X301795Y310398D03*
X296639Y308057D03*
X305250Y310342D03*
X300201Y300874D03*
X303197Y304297D03*
X295200Y321473D03*
X294596Y328129D03*
X297073Y329159D03*
X294218Y343587D03*
X294888Y335326D03*
X298452Y340487D03*
X305880Y339046D03*
X306820Y342146D03*
X299410Y331201D03*
X303759Y331478D03*
X294618Y348287D03*
X293467Y352442D03*
X305446Y359450D03*
X295527Y359812D03*
X298202Y374572D03*
X303171Y374224D03*
X291686Y375177D03*
X295388Y375644D03*
X303722Y385367D03*
X293290Y389737D03*
X291382Y385457D03*
X299533Y394056D03*
X291860Y442927D03*
X292170Y445986D03*
X301240Y470885D03*
X291327Y466811D03*
X300040Y459733D03*
X306220Y477125D03*
X303631Y475607D03*
Y472607D03*
X301209Y488853D03*
X303709Y489353D03*
X297370Y498563D03*
X300209Y495853D03*
X305708Y503043D03*
X296913Y514460D03*
X301457Y513837D03*
X295047Y554565D03*
X304410Y572782D03*
X291357Y586128D03*
X299121Y597542D03*
X306229Y600263D03*
X301796Y603917D03*
X298303Y613184D03*
X305602Y620685D03*
Y618185D03*
X299629Y623877D03*
X299090Y634421D03*
X302870Y633981D03*
X297162Y642065D03*
X293843Y642536D03*
X303110Y639381D03*
X305200Y652883D03*
X301070Y655920D03*
X292850Y656359D03*
X304870Y655747D03*
X306294Y659156D03*
X297394Y657033D03*
X302772Y659604D03*
X301360Y652183D03*
X306294Y667156D03*
Y663156D03*
Y675156D03*
Y671156D03*
X300880Y664296D03*
X294120Y668391D03*
X295890Y662662D03*
X297770Y674720D03*
X305979Y691156D03*
X306145Y683156D03*
X305979Y687156D03*
X306294Y679156D03*
X292970Y682450D03*
X295950Y689520D03*
X293068Y677108D03*
X296858Y702544D03*
X297300Y697221D03*
X301696Y701851D03*
Y699351D03*
X293286Y703504D03*
X305990Y697189D03*
X303681Y714421D03*
X305213Y720393D03*
X293300Y718944D03*
X296885Y718059D03*
X297223Y715523D03*
X291318Y713875D03*
X291790Y735976D03*
X306540Y724266D03*
X297940Y724377D03*
X302660Y736359D03*
X298160Y736489D03*
X302810Y733807D03*
X298590Y733669D03*
X293480Y725080D03*
X295700Y733133D03*
X293440Y748380D03*
X291340Y771217D03*
X295100Y786269D03*
X299249Y771403D03*
X304740Y777277D03*
X291398Y792234D03*
X299272Y791695D03*
X317334Y10955D03*
X322640Y9774D03*
X317334Y28955D03*
X314640Y63167D03*
X310483D03*
X318543D03*
X322713D03*
X318910Y74595D03*
X314310Y74540D03*
X307740Y74263D03*
X309730Y76232D03*
X321283Y76327D03*
X316623Y76047D03*
X312402Y76587D03*
X314830Y92851D03*
X312183Y88837D03*
X321463Y88517D03*
X315083Y90207D03*
X311553Y92347D03*
X310850Y99620D03*
X320740Y98599D03*
X312223Y96407D03*
X317970Y95961D03*
X313583Y122387D03*
X311420Y250230D03*
X311290Y247249D03*
X315410Y258656D03*
X312680Y258353D03*
X307204Y304212D03*
X310623Y313589D03*
X313123D03*
X320623D03*
X318123D03*
X315623D03*
X321643Y321928D03*
X309143D03*
X311643D03*
X314143D03*
X316643D03*
X319143D03*
X322765Y327721D03*
X311740Y325839D03*
X322210Y336696D03*
X319323Y338320D03*
X309510Y344127D03*
X313980Y335813D03*
X314550Y331564D03*
X318480Y335039D03*
X321130Y342418D03*
X309190Y336959D03*
X319666Y354376D03*
X319807Y346376D03*
X321150Y357730D03*
X319288Y350376D03*
X307410Y348380D03*
X309131Y374573D03*
X314860Y367656D03*
X313222Y374229D03*
X322255Y371935D03*
X321297Y367739D03*
X319363Y372149D03*
X315383Y387863D03*
X307116Y385979D03*
X315533Y384749D03*
X310484Y383312D03*
X321144Y399643D03*
X318644D03*
X316190Y413299D03*
X317140Y421775D03*
X321910Y410139D03*
X311610Y432528D03*
X313530Y436460D03*
X315940Y438104D03*
X319478Y429389D03*
X308220Y432552D03*
X322599Y432505D03*
X309440Y426404D03*
X318950Y432473D03*
X316963Y467655D03*
X321357Y456709D03*
X307800Y467859D03*
X310380Y473942D03*
X316956Y478833D03*
X321246Y472669D03*
X315980Y472128D03*
X307670Y473605D03*
X320080Y512736D03*
X318968Y536052D03*
X318678Y540966D03*
X321828Y541682D03*
X313888Y566003D03*
X313141Y550821D03*
X313075Y553755D03*
X313108Y556556D03*
X313275Y559590D03*
X316788Y572903D03*
X316688Y569603D03*
X313347Y570695D03*
X319135Y591407D03*
X313419Y594040D03*
X313227Y590232D03*
X310919Y594040D03*
X310627Y590232D03*
X315957Y594127D03*
X312641Y611556D03*
X307996Y611536D03*
X312656Y606881D03*
X307994Y606886D03*
X320094Y604114D03*
X320512Y613603D03*
X308102Y620685D03*
Y618185D03*
X320367Y618071D03*
X314910Y627222D03*
X317722Y614646D03*
X308741Y623871D03*
X311311Y618197D03*
X317492Y618193D03*
X307574Y633762D03*
X314940Y642067D03*
X310453Y642451D03*
X320360Y642275D03*
X311382Y635432D03*
X314790Y652049D03*
X317130Y653628D03*
X316184Y662630D03*
X314614Y690767D03*
X316184Y687630D03*
X322440Y700130D03*
X320110Y703093D03*
X316165Y693404D03*
X313230Y702465D03*
X317580Y719996D03*
X307113Y713003D03*
X321820Y712680D03*
X311990Y717601D03*
X319620Y716403D03*
X309531Y714298D03*
X312972Y712693D03*
X318090Y712846D03*
X307940Y736445D03*
X311440Y735831D03*
X315940Y735924D03*
X320440Y736031D03*
X307280Y733705D03*
X321930Y724895D03*
X314930Y724533D03*
X307146Y769416D03*
X315020Y780559D03*
X320657Y779595D03*
X320440Y771967D03*
X311083Y791871D03*
X318957Y791695D03*
X323334Y12377D03*
X323871Y25812D03*
Y16812D03*
Y19812D03*
Y28812D03*
X336316Y31815D03*
X327117Y31840D03*
X326353Y63167D03*
X323640Y74393D03*
X326140Y76196D03*
X336024Y88176D03*
X329643Y89887D03*
X335668Y92822D03*
X330668D03*
X325360Y92517D03*
X324070Y88861D03*
X336340Y99265D03*
X327950Y101057D03*
X323000Y94337D03*
X325970Y98817D03*
X327430Y108208D03*
X327190Y103818D03*
X337630Y106304D03*
X334720Y102184D03*
X332453Y122297D03*
X323032Y122237D03*
X331583Y128717D03*
X336495Y290569D03*
X331376Y299883D03*
X328526Y308696D03*
X334478Y299604D03*
X323123Y313589D03*
X336720Y310846D03*
X337293Y316660D03*
X333540Y315590D03*
X332700Y333089D03*
X333726Y353801D03*
X333440Y349221D03*
X327058Y358376D03*
X323040Y354485D03*
X334816Y367787D03*
X337316Y367758D03*
X337330Y372679D03*
X334816Y372609D03*
X336850Y380332D03*
X326282Y399743D03*
X323644Y399643D03*
X325749Y418701D03*
X331090Y424304D03*
X331900Y419317D03*
X336740Y417069D03*
X328290Y424304D03*
X324940Y413899D03*
X336218Y424850D03*
X325180Y432577D03*
X334420Y428660D03*
X336088Y454511D03*
X326190Y448621D03*
X329120Y449203D03*
X327780Y445819D03*
X331360Y447306D03*
X322986Y467109D03*
X325040Y480129D03*
X330115Y490303D03*
X335162Y502791D03*
X326740Y495763D03*
X329672Y502057D03*
X326170Y518386D03*
X335860Y516486D03*
X336010Y531598D03*
X329348Y533403D03*
X324927Y546013D03*
X328592Y541146D03*
X328352Y545412D03*
X325588Y541447D03*
X332408Y544097D03*
X323154Y556367D03*
Y558867D03*
Y553867D03*
X337550Y558618D03*
Y556118D03*
Y553618D03*
X323088Y561503D03*
X323188Y564503D03*
X330388Y565803D03*
X336057Y575657D03*
X332388Y567703D03*
X328088Y567503D03*
X323931Y589733D03*
X329260Y603381D03*
X328930Y611691D03*
X323346Y621930D03*
X329110Y623514D03*
X330440Y639504D03*
X328032Y642674D03*
X337070Y639759D03*
X326350Y638968D03*
X332710Y642694D03*
X328760Y657144D03*
X327540Y653432D03*
X335610Y658177D03*
X332747Y655636D03*
X332190Y659883D03*
X329912Y662383D03*
X335915Y675011D03*
X335390Y667895D03*
X326890Y676159D03*
X327257Y672408D03*
X333180Y665611D03*
X335130Y670744D03*
X334313Y663113D03*
X327500Y667244D03*
X324970Y665128D03*
X337030Y677894D03*
X337798Y686721D03*
X324120Y703114D03*
X336110Y693934D03*
X331520Y701642D03*
X332720Y698170D03*
X325841Y719731D03*
X330410Y712895D03*
X325560Y713391D03*
X336990Y735701D03*
X324940Y736067D03*
X329440Y735814D03*
X333940Y735895D03*
X329590Y724283D03*
X334640Y725035D03*
X338270Y733387D03*
X338460Y724585D03*
X326280Y775980D03*
X337800Y774677D03*
X339162Y9304D03*
Y11904D03*
X350411Y21277D03*
X339239Y24232D03*
X339471Y19373D03*
Y16773D03*
X339239Y26832D03*
X346600Y38561D03*
X346150Y36030D03*
X353060Y61504D03*
X349490Y57698D03*
X352578Y74292D03*
X339750Y73383D03*
X350198Y88277D03*
X343111Y88429D03*
X340543Y88647D03*
X345463Y90837D03*
X353713Y93057D03*
X344770Y101718D03*
X351793Y105404D03*
X344873Y94847D03*
X343070Y99372D03*
X340450Y101914D03*
X344073Y124397D03*
X351533Y124697D03*
X343743Y120967D03*
X351373Y134367D03*
X351503Y130972D03*
Y127972D03*
X345297Y284849D03*
X342955Y291523D03*
X341693Y286010D03*
X354170Y308924D03*
X351500Y301795D03*
X340792Y307107D03*
X353903Y314077D03*
X353841Y306194D03*
X339370Y329176D03*
X341910Y325739D03*
X344720D03*
X339600Y332076D03*
X343880Y356989D03*
X349110Y375767D03*
X352420Y375672D03*
X346020Y374075D03*
X343430Y385937D03*
X343770Y382166D03*
X351650Y420270D03*
X346862Y424850D03*
X345270Y452745D03*
X346750Y466532D03*
X352890Y479656D03*
X348000Y479150D03*
X352260Y483029D03*
X338762Y479636D03*
X339506Y482841D03*
X348220Y486484D03*
X352160Y502138D03*
X351250Y499752D03*
X348870Y501571D03*
X343420Y497966D03*
X353400Y507260D03*
X353460Y504536D03*
X348190Y511550D03*
X353120Y510003D03*
X350690Y516376D03*
X340902Y503742D03*
X352940Y518025D03*
X341512Y512429D03*
X350902Y512520D03*
X346350Y517286D03*
X340182Y531787D03*
X351110Y531835D03*
X340330Y541931D03*
X341011Y537828D03*
X342190Y565848D03*
X342759Y599193D03*
X339616Y603438D03*
Y605938D03*
X339384Y611544D03*
X351964Y599332D03*
X339600Y621293D03*
Y618693D03*
X339384Y614144D03*
X353298Y633903D03*
X340340Y638054D03*
X340669Y644827D03*
X348480Y638558D03*
X345580Y638109D03*
X347670Y642285D03*
X351728Y653860D03*
X351722Y659319D03*
X340630Y655093D03*
X351730Y649206D03*
X339930Y661219D03*
X353902Y667128D03*
X351730Y663450D03*
X340530Y675658D03*
X351720Y670018D03*
X338970Y670776D03*
X340870Y665042D03*
X340525Y686600D03*
X353260Y688757D03*
X351810Y706800D03*
X339750Y695271D03*
X339010Y700406D03*
X338926Y697752D03*
X344780Y713349D03*
X352400Y722132D03*
X339300Y716800D03*
X342230Y720936D03*
X341190Y712379D03*
X352010Y713968D03*
X342230Y709384D03*
X343730Y724581D03*
X350180Y735880D03*
X350580Y724427D03*
X345610Y733982D03*
X354060Y734790D03*
X350720Y745722D03*
X344710Y785782D03*
X350450Y784982D03*
X346516Y790294D03*
X363025Y12926D03*
X358285Y21325D03*
X366159Y21822D03*
X361930Y60031D03*
X367300Y60442D03*
X356550Y74767D03*
X365670Y64458D03*
X366733Y88477D03*
X359646Y88174D03*
X362133Y90877D03*
X367776Y91746D03*
X358343Y90948D03*
X360827Y108541D03*
X362300Y98674D03*
X369670Y99845D03*
X361470Y101757D03*
X354943Y104191D03*
X354448Y108092D03*
X367560Y120823D03*
X367350Y123927D03*
X365283Y128125D03*
X354580Y298101D03*
X364220Y296795D03*
X357400Y307608D03*
X365970Y299194D03*
X356835Y313894D03*
X369280Y300916D03*
X367220Y303202D03*
X362660Y316986D03*
X357110Y329210D03*
X359410Y317080D03*
X369040Y316735D03*
X369934Y322946D03*
X359120Y331164D03*
X357040Y332970D03*
X365026Y332478D03*
X362540Y361443D03*
X354690Y377000D03*
X364645Y377065D03*
X360960Y389080D03*
X364880Y384455D03*
X364580Y391273D03*
X366140Y407639D03*
X360350Y395873D03*
X369280Y415600D03*
X355250Y420679D03*
X365850Y414874D03*
X368660Y449478D03*
X369500Y445873D03*
X354565Y451562D03*
X354750Y445325D03*
X369507Y464391D03*
X355150Y486758D03*
X368787Y472998D03*
X368943Y506356D03*
X366426Y527722D03*
Y530222D03*
Y532722D03*
X368238Y522673D03*
X358182Y531231D03*
X357820Y534561D03*
X365329Y546121D03*
X368694Y546159D03*
X368825Y539776D03*
X369918Y592253D03*
X369848Y588903D03*
X360647Y602636D03*
X354973Y605588D03*
Y602588D03*
Y611588D03*
X361473Y620588D03*
X354973Y614588D03*
Y620588D03*
Y623588D03*
X361562Y645175D03*
X363530Y629727D03*
X367858Y657573D03*
X365070Y658065D03*
X365990Y645272D03*
X367870Y650239D03*
X364980Y655266D03*
X363340Y650512D03*
X361650Y658537D03*
X361580Y652755D03*
X362173Y665128D03*
X368200Y672132D03*
X368100Y668133D03*
X361810Y675011D03*
X365620Y663069D03*
X361660Y671306D03*
X365380Y668972D03*
X365160Y672922D03*
X361760Y668716D03*
X367399Y684652D03*
X367866Y677326D03*
X361646Y689228D03*
X367066Y681094D03*
X364320Y680434D03*
X367496Y690248D03*
X361510Y680886D03*
X362040Y684875D03*
X364649Y684022D03*
X364765Y687963D03*
X365090Y676923D03*
X364844Y698332D03*
X361786Y699128D03*
X361717Y695128D03*
X367480Y705169D03*
X367614Y693053D03*
X361580Y703860D03*
X363590Y702324D03*
X364115Y692990D03*
X367520Y701710D03*
X366510Y723622D03*
X361350Y720720D03*
X361490Y712505D03*
X367350Y713661D03*
X357830Y718682D03*
X363162Y739537D03*
X366430Y731459D03*
X357096Y732976D03*
X360246Y730819D03*
X354520Y728701D03*
X363460Y735388D03*
X364750Y727821D03*
X363359Y743537D03*
X364090Y748565D03*
X354420Y749198D03*
X357610Y748302D03*
X366860Y739956D03*
X354870Y771388D03*
X360160Y775523D03*
X363300Y781303D03*
X367904Y778327D03*
X366201Y787976D03*
X354390Y790294D03*
X366201Y790976D03*
X379940Y17789D03*
X382990Y17519D03*
X371180Y17789D03*
X370960Y20577D03*
X381907Y21507D03*
X383280Y59940D03*
X376006Y60991D03*
X383247Y64141D03*
X373560Y63973D03*
X380906Y88134D03*
X373820Y88400D03*
X372776Y91746D03*
X384450Y108830D03*
X372620Y98355D03*
X384090Y98743D03*
X379160Y102923D03*
X374030Y95000D03*
X382087Y103647D03*
X380483Y99047D03*
X378733Y105987D03*
X384863Y95437D03*
X376100Y108780D03*
X376723Y94178D03*
X377363Y121108D03*
X378183Y124904D03*
X374040Y304980D03*
X373640Y301078D03*
X370460Y305908D03*
X371090Y303487D03*
X384248Y319157D03*
X372080Y330574D03*
X379560Y374955D03*
X379720Y372257D03*
X378830Y386352D03*
X382620Y391882D03*
X379300Y380862D03*
X379286Y378015D03*
X379750Y383965D03*
X382190Y388077D03*
X376600Y408045D03*
X382680Y408202D03*
X374560Y412421D03*
X371260Y412879D03*
X376150Y430405D03*
X383750Y437058D03*
X372320Y439514D03*
X371950Y430527D03*
X378910Y430874D03*
X371080Y448276D03*
X372710Y445705D03*
X375190Y463996D03*
X381239Y467171D03*
X371080Y481589D03*
X374203Y482079D03*
X377284Y473374D03*
X374207Y479329D03*
X373850Y496585D03*
X381760Y496004D03*
X374203Y491029D03*
X376540Y498385D03*
X379177Y509798D03*
X383924Y514797D03*
X383617Y517862D03*
X385040Y521754D03*
X384588Y526069D03*
X382632Y530322D03*
Y527822D03*
Y532822D03*
X373538Y520213D03*
X376528Y520138D03*
X379733Y549392D03*
X370309Y550322D03*
X377150Y543151D03*
X376490Y540574D03*
X382596Y537379D03*
X382333Y540414D03*
X384485Y552365D03*
X382595Y554166D03*
X385410Y566122D03*
X383344Y590662D03*
Y593262D03*
X373448Y589053D03*
X373518Y592403D03*
X385573Y629998D03*
X371407Y641507D03*
X383034Y640267D03*
X373218Y634217D03*
X382580Y637413D03*
X380101Y660239D03*
X379093Y657739D03*
X376650Y654157D03*
X379492Y650239D03*
X376089Y646156D03*
X373680Y662417D03*
X376087Y670156D03*
X377211Y673197D03*
X379461Y675246D03*
X379462Y666156D03*
X379791Y679454D03*
X376946Y689985D03*
X377681Y694244D03*
X377679Y701168D03*
X377669Y706237D03*
X377100Y697218D03*
X371170Y711574D03*
X382960Y711431D03*
X372110Y720308D03*
X376190Y711259D03*
X375575Y739459D03*
X375548Y731459D03*
X375834Y727459D03*
X377840Y724388D03*
X376770Y734898D03*
X370430Y749138D03*
X373500Y748457D03*
X376960Y788580D03*
Y791580D03*
X399002Y17519D03*
X392600Y20548D03*
X389240D03*
X397655Y21336D03*
X392250Y59899D03*
X389690Y60665D03*
X401310Y61439D03*
X397790Y61360D03*
X393371Y72919D03*
X397790Y69610D03*
X390355Y75775D03*
X401220Y65155D03*
X399804Y88778D03*
X397442Y90667D03*
X389400Y89232D03*
X392493Y92647D03*
X399653Y108357D03*
X391536Y108990D03*
X398820Y95823D03*
X391190Y104173D03*
X388860Y98010D03*
X400163Y99177D03*
X391310Y99570D03*
X399613Y104657D03*
X391233Y96093D03*
X399150Y131773D03*
X391880Y131692D03*
X398088Y128455D03*
X393088D03*
X399858Y249711D03*
X399298Y257231D03*
X391998Y258251D03*
X399598Y260251D03*
X398258Y252341D03*
X394378Y260501D03*
X392668Y272511D03*
X399608Y275211D03*
X393458Y282931D03*
X392508Y275581D03*
X400928Y293151D03*
X396098Y283931D03*
X398038Y292571D03*
X399880Y319568D03*
X390080Y331575D03*
X389740Y404725D03*
X395740Y407528D03*
X393370Y411618D03*
X399060Y454322D03*
X399050Y450968D03*
X398800Y462248D03*
Y458058D03*
X392076Y470970D03*
X387080Y486400D03*
X385940Y482478D03*
X388890Y480439D03*
X386410Y477576D03*
X389670Y477262D03*
X389107Y492097D03*
X388982Y496939D03*
X395690Y512774D03*
X396350Y532016D03*
X396558Y522251D03*
X396470Y527847D03*
X396048Y540127D03*
X395922Y536127D03*
X396590Y549310D03*
X399590Y553502D03*
X390000Y567345D03*
X396520Y567444D03*
X393596Y567630D03*
X391630Y597900D03*
X401091Y587054D03*
X398386Y587126D03*
X401422Y597270D03*
X400589Y611672D03*
X400587Y607022D03*
X401422Y599770D03*
X398822Y600399D03*
X391447Y611973D03*
X394389Y604053D03*
X398195Y620821D03*
X400695Y618321D03*
X398195D03*
X400695Y620821D03*
X392063Y624109D03*
X401353Y624007D03*
X399223Y644930D03*
X395701Y637430D03*
X399440Y637340D03*
X394380Y643389D03*
X396940Y658078D03*
X396366Y653229D03*
X399363Y653588D03*
X389856Y645705D03*
X396478Y661529D03*
X399911Y661325D03*
X386173Y665065D03*
X391938Y672320D03*
X392097Y676231D03*
X399873Y666411D03*
X400267Y684029D03*
X390000Y689724D03*
X389961Y682218D03*
X396550Y680266D03*
X399829Y690191D03*
X400968Y686699D03*
X400408Y681193D03*
X390660Y686923D03*
X391910Y696742D03*
X392080Y692796D03*
X391740Y705957D03*
X398620Y701411D03*
X390950Y701922D03*
X389350Y711288D03*
X396150Y708926D03*
X400730Y721954D03*
X394840Y711437D03*
X414949Y75291D03*
X403739Y72783D03*
X404310Y65213D03*
X410713Y76187D03*
X401670Y93807D03*
X404528Y88702D03*
X409060Y92095D03*
X404813Y93887D03*
X407303Y95117D03*
X408072Y109146D03*
X405688Y253581D03*
X404738Y260421D03*
X402948Y253251D03*
X405970Y256489D03*
X405038Y267521D03*
X401728Y277251D03*
X401618Y267351D03*
X403148Y270191D03*
X405248Y272731D03*
X405878Y294071D03*
X403628Y292201D03*
X408790Y317049D03*
X411240Y316482D03*
X403130Y418091D03*
X406200Y417755D03*
X405980Y414630D03*
X405930Y411386D03*
X406140Y424766D03*
X406150Y433203D03*
X406530Y440667D03*
X406000Y444755D03*
X402900Y444842D03*
X414870Y455166D03*
Y450976D03*
X406352Y471405D03*
X409054Y483084D03*
X412260Y482881D03*
X410607Y485620D03*
X413607D03*
X413733Y490781D03*
X410733D03*
X407733D03*
Y493781D03*
Y496781D03*
Y499781D03*
X410733Y493781D03*
X413733D03*
X410733Y496781D03*
X413733D03*
X410733Y499781D03*
X413733D03*
X409985Y508431D03*
X413138Y504813D03*
X413222Y508054D03*
X411439Y516956D03*
X407865Y516627D03*
X405348Y506316D03*
X402458Y505903D03*
X401556Y508937D03*
X409251Y521763D03*
X412088Y521721D03*
X407776Y527426D03*
X405954Y532502D03*
X404336Y545280D03*
X408486Y537333D03*
X416515Y547602D03*
X402499Y554143D03*
X404578Y551838D03*
X408736Y551529D03*
X413342Y556219D03*
X410522Y593947D03*
X413022D03*
X406884Y594176D03*
X406881Y591322D03*
X405234Y611692D03*
X405249Y607017D03*
X412783Y605500D03*
X412960Y618207D03*
X405426Y626809D03*
X410315Y614782D03*
X416454Y621319D03*
X413105Y613739D03*
X403904Y618333D03*
X410085Y618329D03*
X413930Y639810D03*
X409520Y637387D03*
X414760Y636225D03*
X403970Y642364D03*
X406100Y631851D03*
X410989Y652957D03*
X413535Y646804D03*
X411982Y660285D03*
X413718Y655267D03*
X410918Y649363D03*
X413966Y675624D03*
X415218Y664203D03*
X411675Y672654D03*
X411065Y667516D03*
X414183Y686151D03*
X411862Y688027D03*
X413643Y680004D03*
X412250Y683196D03*
X411149Y678387D03*
X415834Y693272D03*
X412878Y693183D03*
X414550Y707464D03*
X414318Y700979D03*
X414810Y696968D03*
X409581Y711643D03*
X402540Y710649D03*
X412080Y719034D03*
X414080Y721334D03*
X415730Y710897D03*
X406720Y723395D03*
X413940Y735665D03*
X409010Y726147D03*
X415780Y747078D03*
X421893Y123537D03*
X421473Y160556D03*
Y157556D03*
X421640Y228403D03*
Y223403D03*
X422698Y244301D03*
X422288Y250661D03*
X419038Y242611D03*
X428405Y245194D03*
X424961Y241203D03*
X418905Y245694D03*
X426992Y250016D03*
X427768Y253569D03*
X422178Y266891D03*
X428208Y262109D03*
X422528Y253531D03*
X426335Y267062D03*
X418575Y263691D03*
X420858Y261331D03*
X427817Y258829D03*
X418597Y273538D03*
X418698Y279631D03*
X426948Y281051D03*
X421728Y279141D03*
X428748Y275222D03*
X418998Y289871D03*
X422918Y289501D03*
X418588Y286681D03*
X421128Y292601D03*
X423178Y284601D03*
X427909Y286759D03*
X427468Y292287D03*
X418718Y301181D03*
X421710Y424527D03*
X430340Y416573D03*
X432450Y418766D03*
X422120Y418288D03*
X432960Y414886D03*
X422080Y414644D03*
Y410454D03*
X421770Y433187D03*
X422860Y441790D03*
X422760Y445581D03*
X425870Y449509D03*
X422460Y449467D03*
X429670Y449552D03*
X419420Y453168D03*
X428747Y463314D03*
X419420Y457358D03*
X428747Y468770D03*
X419071Y509283D03*
X431280Y514223D03*
X431356Y516836D03*
X422050Y517028D03*
X425999Y516211D03*
X424873Y513921D03*
X423278Y525160D03*
X428874Y525193D03*
X417520Y525128D03*
X428874Y530627D03*
X417520Y531177D03*
X428745Y536999D03*
X423332Y536763D03*
X417617Y536773D03*
X426068Y546048D03*
X417979Y545352D03*
X428039Y548119D03*
X421461Y547703D03*
X420883Y556729D03*
X428039Y556539D03*
X423861Y556535D03*
X431145Y556608D03*
X424904Y586283D03*
X429340Y596874D03*
X422210Y605343D03*
X419221Y612253D03*
X425151Y608429D03*
X431520Y607039D03*
X422221Y619873D03*
X420245Y636004D03*
X417422Y637592D03*
X422470Y647852D03*
X432180Y647458D03*
X425334Y656419D03*
X422007Y652732D03*
X423623Y645396D03*
X422026Y656883D03*
X429820Y656709D03*
X425146Y672426D03*
X430140Y665660D03*
X417974Y663446D03*
X421080Y665945D03*
X422222Y675226D03*
X426100Y667884D03*
X422510Y677836D03*
X430873Y684536D03*
X425173Y688588D03*
X427900Y679709D03*
X430861Y679156D03*
X422981Y690351D03*
X430862Y691156D03*
X430813Y687156D03*
X427210Y691934D03*
X423317Y705344D03*
X423055Y696713D03*
X430618Y699156D03*
X430667Y703156D03*
X430731Y707156D03*
X430813Y695156D03*
X427230Y707377D03*
X426391Y701173D03*
X423242Y707949D03*
X425590Y695895D03*
X421350Y694003D03*
X422940Y723802D03*
X430738Y711156D03*
X427130Y717871D03*
X421730Y717398D03*
X429240Y721014D03*
X424410Y718429D03*
X417330Y717420D03*
X431440Y723955D03*
X420160Y724309D03*
X430940Y735895D03*
X426430Y735126D03*
X418440Y735930D03*
X420290Y733741D03*
X423900Y736055D03*
X424200Y733399D03*
X426440Y724240D03*
X421690Y779548D03*
X417880Y786361D03*
X428250Y772054D03*
X426900Y779752D03*
X421321Y791476D03*
X417384D03*
X446268Y69074D03*
X442380Y75513D03*
X439670Y70044D03*
X446088Y90159D03*
Y85159D03*
Y87659D03*
X446920Y78358D03*
X447715Y97926D03*
X434158Y122272D03*
X443448Y124552D03*
X441518Y122242D03*
X434158Y125092D03*
X444828Y122132D03*
X446522Y146932D03*
X433253Y160737D03*
X433363Y157607D03*
X444550Y184057D03*
X442520Y223623D03*
X442580Y236459D03*
X441580Y250730D03*
X443212Y240957D03*
X447900Y265292D03*
X441498Y266731D03*
X441792Y259473D03*
X442148Y279361D03*
X442165Y271284D03*
X441076Y294906D03*
X445540Y288853D03*
X445890Y283317D03*
X441361Y300812D03*
X438340Y403375D03*
X439150Y400930D03*
X443240Y401984D03*
X446830Y400551D03*
X445900Y403460D03*
X436370Y410543D03*
X444020Y410374D03*
X439830D03*
X446660Y413325D03*
X446950Y417162D03*
X440900Y446260D03*
X436710D03*
X444850Y446337D03*
X438390Y456129D03*
X438520Y452324D03*
X433720Y449467D03*
X437887Y471073D03*
X444920Y485259D03*
X447770Y485290D03*
X437716Y476295D03*
X445366Y490657D03*
X445199Y494590D03*
X439749Y506523D03*
X439762Y515540D03*
Y523757D03*
X447781Y523888D03*
X434605Y521488D03*
X442763Y549595D03*
X445838Y538085D03*
X435998Y539726D03*
X434203Y542897D03*
X438722Y538842D03*
X441063Y540563D03*
X448329Y534995D03*
X441326Y556050D03*
X437832Y556374D03*
X434187Y556444D03*
X442240Y553337D03*
X437516Y587579D03*
X441230Y587341D03*
X447830Y588739D03*
X446378Y582681D03*
X435319Y600123D03*
X440040Y608537D03*
X437120Y612933D03*
X440135Y615808D03*
X448460Y625960D03*
X445604Y629045D03*
X433872Y645119D03*
X446980Y638774D03*
X437100Y643793D03*
X446500Y645075D03*
X443850Y634754D03*
X439250Y630973D03*
X434681Y642639D03*
X435420Y647117D03*
X437509Y648996D03*
X446799Y657526D03*
X435972Y655595D03*
X444700Y651900D03*
X445270Y660832D03*
X444403Y665963D03*
X447210Y665143D03*
X436000Y675706D03*
X435539Y671628D03*
X436445Y667628D03*
X447161Y673564D03*
X444458Y669350D03*
X440688Y684438D03*
Y689438D03*
X440690Y702386D03*
X440688Y694438D03*
X446900Y714648D03*
X442650Y719485D03*
X446260Y722014D03*
X444530Y723917D03*
X440660Y712065D03*
X439200Y722093D03*
X447240Y724780D03*
X439940Y735507D03*
X443940Y735681D03*
X435440Y735928D03*
X436440Y724710D03*
X442120Y724781D03*
X447680Y733564D03*
X444370Y770152D03*
X434540Y778500D03*
X441006Y785297D03*
Y791476D03*
X437069D03*
X458120Y44721D03*
X464170Y56436D03*
X450618Y69004D03*
X457583Y66384D03*
X454263Y77675D03*
X458598Y77967D03*
X462294Y87759D03*
Y85259D03*
Y90259D03*
X461516Y78275D03*
X450917Y97566D03*
X461594Y99342D03*
X449538Y105144D03*
X453168D03*
X453940Y98586D03*
X460412Y105704D03*
X457912D03*
X462912D03*
X453298Y122254D03*
X450798D03*
X452158Y124582D03*
X458818Y122065D03*
Y125422D03*
X461880Y150596D03*
X455292Y162797D03*
X455470Y166963D03*
X452669Y157140D03*
X455913Y178698D03*
X454763Y183503D03*
X453340Y185670D03*
X457482Y183523D03*
X462790Y183489D03*
X452115Y195057D03*
X459000Y200500D03*
X450650Y203785D03*
X450576Y234431D03*
X454150Y249053D03*
X453620Y245162D03*
X459990Y245930D03*
X457165Y262368D03*
X456800Y259233D03*
X459108Y253181D03*
X449860Y267121D03*
X456530Y256034D03*
X449290Y276227D03*
X449860Y272121D03*
X452900Y281647D03*
X453780Y292411D03*
X453810Y289325D03*
X451790Y300129D03*
X461130Y408318D03*
X448970Y403846D03*
X451950Y402434D03*
X461080Y411451D03*
X463690Y451813D03*
X461590Y446700D03*
X461540Y449833D03*
X457702Y475480D03*
X460702D03*
X454702D03*
X463702D03*
X450899Y483452D03*
X463540Y495717D03*
X457537Y495546D03*
X454770Y495587D03*
X450813Y492993D03*
X463565Y515723D03*
X452895Y510061D03*
X449402Y515514D03*
X451504Y529734D03*
X450540Y521331D03*
X463991Y531504D03*
X451325Y525981D03*
X456722Y529536D03*
X454022Y541052D03*
X463031Y543563D03*
X453917Y550069D03*
X450367Y540720D03*
X453700Y545047D03*
X453854Y555069D03*
X460236Y581679D03*
X455890Y592792D03*
X450778Y583106D03*
X458600Y599200D03*
X453775Y600614D03*
X462270Y612911D03*
X453935Y624739D03*
X459690Y626423D03*
X464050Y633877D03*
X458903Y644884D03*
X456342Y649436D03*
X461997Y654507D03*
X463178Y647483D03*
X458650Y666543D03*
X460587Y669424D03*
X457138Y663251D03*
X463020Y661023D03*
X464330Y663251D03*
X458820Y674137D03*
X463120Y681992D03*
X460530Y681874D03*
X459650Y685993D03*
X457730Y682010D03*
X456960Y685581D03*
X461960Y684394D03*
X459950Y722720D03*
X453960Y723142D03*
X449060Y721761D03*
X457060Y722427D03*
X460822Y712620D03*
X451820Y712210D03*
X454070Y714226D03*
X453530Y736212D03*
X458050Y725053D03*
X462440Y735687D03*
X455410Y734113D03*
X450410Y733682D03*
X451320Y725044D03*
X461565Y785806D03*
X463750Y780452D03*
X454120Y785923D03*
X460691Y791476D03*
X456754D03*
X475310Y59746D03*
X464767Y78145D03*
X475030Y63879D03*
X479450Y63721D03*
X466647Y91224D03*
X466682Y102410D03*
X474381Y125310D03*
X478088Y125219D03*
X471500Y138000D03*
X473200Y140300D03*
X468400Y135800D03*
X470324Y133424D03*
X474813Y162220D03*
X467473Y159766D03*
X473951Y157235D03*
X473950Y172124D03*
X475760Y168747D03*
X472670Y166398D03*
X473580Y177859D03*
X474630Y174843D03*
X480220Y185766D03*
X475770Y186451D03*
X468452Y197934D03*
X471300Y201900D03*
X476400Y203100D03*
X478000Y212500D03*
X466200Y207300D03*
X471795Y267941D03*
X464810Y311253D03*
X470090Y332824D03*
X475190Y339013D03*
X474140Y408318D03*
X469590D03*
X465330D03*
X468210Y401505D03*
X465913Y402659D03*
X465883Y399834D03*
X474080Y411451D03*
X469530D03*
X465270D03*
X480050Y419556D03*
X471540Y437214D03*
X473140Y439971D03*
X469500Y447730D03*
X467920Y451667D03*
X472210Y450267D03*
X465730Y449833D03*
X465790Y446700D03*
X479575Y467597D03*
X479754Y462988D03*
X466702Y475480D03*
X480118Y479107D03*
Y474107D03*
X466307Y495676D03*
X467677Y510055D03*
X467496Y513179D03*
X466587Y515764D03*
X467586Y506807D03*
X474130Y553659D03*
X474290Y563565D03*
X471804Y561085D03*
Y556085D03*
X471190Y593964D03*
X468740Y585897D03*
X469890Y596580D03*
X473294Y613207D03*
X473153Y622451D03*
X476320Y629280D03*
X465580Y641417D03*
X469229Y638135D03*
X475820Y635422D03*
X478905Y659426D03*
X470190Y648693D03*
X474946Y659376D03*
X468810Y652180D03*
X479512Y649436D03*
X468540Y655799D03*
X479353Y668666D03*
X466049Y675327D03*
X466980Y667059D03*
X469977Y676496D03*
X468260Y664366D03*
X469467Y679915D03*
X479409Y682305D03*
X479354Y677054D03*
X477710Y722299D03*
X466620Y714137D03*
X473940Y714184D03*
X471450Y736368D03*
X466440Y735987D03*
X471310Y733811D03*
X466440Y724465D03*
X470550Y724034D03*
X473560Y724951D03*
X465850Y733428D03*
X476980Y736594D03*
X476160Y734205D03*
X474940Y747192D03*
X471780Y786300D03*
X476439Y791476D03*
X486810Y60785D03*
X483240Y60546D03*
X487030Y68075D03*
X488438Y109623D03*
Y100123D03*
X484068Y99980D03*
X492955Y99440D03*
X494355Y108674D03*
X491875Y125222D03*
X487140Y123397D03*
X484350Y112811D03*
X487020Y119754D03*
X494910Y133316D03*
X487857Y152147D03*
X490760Y154771D03*
X488570Y147486D03*
X492424Y142234D03*
X494467Y148867D03*
X487740Y161235D03*
X488220Y157515D03*
X490130Y163086D03*
X493670Y171871D03*
X489040Y169483D03*
X482500Y184169D03*
X487080Y180918D03*
X482980Y181071D03*
X488850Y175419D03*
X494210Y175035D03*
X495300Y201600D03*
X487839Y194142D03*
X487464Y198566D03*
X488017Y203716D03*
X486370Y189279D03*
X491046Y207506D03*
X486738Y210434D03*
X487168Y214568D03*
X491320Y231809D03*
X492700Y223800D03*
X488816Y242877D03*
X484169Y272867D03*
X484780Y314090D03*
X494850Y315733D03*
X480830Y333921D03*
X495140Y385762D03*
X486300Y422150D03*
X481300D03*
X486670Y426196D03*
X495500Y447465D03*
X482880Y467935D03*
Y462935D03*
X483685Y473522D03*
X483641Y479628D03*
X492260Y482826D03*
X494980Y482979D03*
X490334Y497342D03*
X486640Y543687D03*
X485510Y536673D03*
X483209Y545250D03*
Y550250D03*
X490661Y547148D03*
X489962Y540849D03*
X489938Y563425D03*
X486720Y563730D03*
X481380Y553210D03*
X483838Y566194D03*
Y556148D03*
Y561148D03*
X490658Y579025D03*
X487398Y576665D03*
X490693Y570770D03*
X490538Y567825D03*
X481410Y573563D03*
X483838Y571194D03*
X485890Y590563D03*
X489380Y590839D03*
X485380Y596505D03*
X485738Y587125D03*
X490738D03*
X481340Y593296D03*
X494238Y600441D03*
X490600Y608136D03*
X489800Y600200D03*
X487832Y624429D03*
X490040Y622140D03*
X491100Y644351D03*
X491380Y639279D03*
X495900Y641804D03*
X480310Y642224D03*
X491930Y654203D03*
X495622Y660178D03*
X492310Y650516D03*
X482180Y646278D03*
X481253Y654837D03*
X493020Y646701D03*
X484700Y660355D03*
X491157Y675604D03*
X482398Y673087D03*
X482544Y668042D03*
X491044Y667604D03*
X491060Y671604D03*
X490120Y662703D03*
X492770Y665090D03*
X491189Y679656D03*
X494323Y687669D03*
X492294Y682347D03*
X483056Y679628D03*
X481227Y685366D03*
X491167Y687507D03*
X481227Y691366D03*
X494340Y691623D03*
X491067Y699656D03*
X491380Y694656D03*
X490900Y706145D03*
X481227Y696366D03*
X495560Y694781D03*
X488180Y719244D03*
X490890Y714898D03*
X488090Y710545D03*
X496000Y736152D03*
X483180Y736506D03*
X487940Y735681D03*
X491890Y735740D03*
X494850Y733252D03*
X480620Y734244D03*
X480770Y778125D03*
X485870Y776087D03*
X491720Y776713D03*
X495110Y771733D03*
X480376Y791476D03*
X502900Y57670D03*
X496955Y99958D03*
X508955Y99978D03*
X500955Y100139D03*
X504955Y99830D03*
X500310Y109211D03*
X508904Y124063D03*
X497430Y124024D03*
X504750Y111749D03*
X509691Y112938D03*
X499456Y128666D03*
X509710Y127269D03*
X500215Y136449D03*
X502132Y146686D03*
X502183Y156709D03*
X500963Y162261D03*
X496360Y167221D03*
X501040Y177297D03*
X498940Y179744D03*
X510000Y173500D03*
X502999Y180541D03*
X499154Y194198D03*
X509100Y191900D03*
X505580Y192555D03*
X498875Y217172D03*
X499225Y205296D03*
X506234Y207368D03*
X499075Y235575D03*
X496123Y233500D03*
X504941Y227859D03*
X498867Y227773D03*
X499405Y242877D03*
X507000Y239000D03*
X504160Y255584D03*
X511070Y310719D03*
X509140Y338005D03*
X504897Y390481D03*
X497111Y388567D03*
X502111D03*
X505819Y417473D03*
X510577Y417741D03*
X498238Y417825D03*
X502687Y417453D03*
X499551Y429636D03*
X502494Y436725D03*
X509486Y433829D03*
X497818Y440265D03*
X509464Y450265D03*
X506456Y446928D03*
X505442Y458719D03*
X502938Y463823D03*
X505843Y465018D03*
X498119Y470011D03*
X511070Y493380D03*
X511520Y496255D03*
X505740Y495880D03*
X511230Y499059D03*
X506230D03*
X511560Y513792D03*
X504613Y522050D03*
X498920Y523803D03*
X503958Y529405D03*
X504613Y525200D03*
X501331Y528932D03*
X500138Y543225D03*
X503448Y540235D03*
X505718Y542865D03*
X503338Y549825D03*
Y544825D03*
X500038Y555925D03*
Y550725D03*
X500138Y563025D03*
Y558625D03*
X500338Y566425D03*
X510338Y571325D03*
X500438Y574925D03*
X500419Y578644D03*
X500538Y572025D03*
X500338Y569425D03*
X499868Y585725D03*
X500538Y588525D03*
X505738Y590525D03*
Y600425D03*
X496140Y608883D03*
X504268Y608625D03*
X500098Y608885D03*
X509238Y608515D03*
X508024Y613598D03*
X500538Y600925D03*
X504980Y616425D03*
X508400Y617803D03*
X502080Y622999D03*
X498350Y627580D03*
X505780Y642543D03*
X501120Y633249D03*
X510700Y634300D03*
X496690Y633589D03*
X501940Y644073D03*
X498666Y653012D03*
X504836Y657097D03*
X503680Y659666D03*
X505690Y654419D03*
X508061Y645381D03*
X504295Y649612D03*
X498040Y675306D03*
X498870Y668324D03*
X504114Y670830D03*
X496453Y670876D03*
X501914Y675624D03*
X504241Y665809D03*
X497320Y665216D03*
X506376Y687436D03*
X506470Y683512D03*
X496577Y684553D03*
X505580Y679105D03*
X496277Y678185D03*
X501540Y681970D03*
X506409Y691373D03*
X500710Y706582D03*
X497350Y699767D03*
X506092Y697575D03*
X510608Y717448D03*
X499842Y710582D03*
X499452Y714582D03*
X502890Y736349D03*
X506105Y724132D03*
X498080Y733252D03*
X509855Y724107D03*
X500260Y729094D03*
X501604Y733003D03*
X501890Y746663D03*
X507935Y785704D03*
X511770Y779940D03*
X499270Y776431D03*
X504440Y772548D03*
X500061Y791476D03*
X496124D03*
X513120Y72069D03*
X512955Y100428D03*
X524955Y99359D03*
X516955Y100333D03*
X520955Y100444D03*
X512878Y108635D03*
X519625Y108543D03*
X526835Y108314D03*
X525570Y124623D03*
X516146Y113121D03*
X522111Y113310D03*
X518248Y137692D03*
X518640Y125539D03*
X518477Y141401D03*
X527349Y152246D03*
X526875Y161838D03*
X518725Y170525D03*
X512600Y178900D03*
X515600Y172800D03*
X521320Y178184D03*
X516100Y178100D03*
X526621Y177079D03*
X512200Y204200D03*
X526443Y194116D03*
X514500Y194300D03*
X525293Y191705D03*
X515231Y191334D03*
X520015Y194584D03*
X523593Y198171D03*
X512200Y196000D03*
X511997Y207730D03*
X520068Y207142D03*
X516551Y214987D03*
X512160Y217073D03*
X526657Y207363D03*
X524405Y212531D03*
X514766Y208222D03*
X519183Y224173D03*
X519300Y220500D03*
X516625Y230075D03*
X515675Y234555D03*
X524675Y234766D03*
X517189Y226229D03*
X517670Y247527D03*
X515675Y254098D03*
X525480Y268959D03*
X518590Y310129D03*
X526250Y310940D03*
X519650Y320384D03*
X522420Y315475D03*
X517260Y315978D03*
X523930Y321642D03*
X514400Y340829D03*
X520510Y337299D03*
X527438Y340353D03*
X517617Y422944D03*
X514820Y417617D03*
X526440Y422428D03*
X527300Y417368D03*
X526440Y432077D03*
X515780Y434039D03*
X517929Y439676D03*
X523667Y438452D03*
X522379Y431974D03*
X513140Y452621D03*
X519440Y452321D03*
X526340D03*
X512867Y443679D03*
X516353Y443517D03*
X523838Y442723D03*
X513140Y459721D03*
Y466021D03*
X525640Y473021D03*
X519640D03*
X513140D03*
X516353Y480708D03*
X525603Y480187D03*
X525638Y484023D03*
X519490Y496645D03*
X525698Y496724D03*
X519938Y493125D03*
X524938D03*
X522250Y513692D03*
X514430Y511801D03*
X519430D03*
X527138Y529525D03*
X523938Y528725D03*
X515110Y528785D03*
X519438Y543025D03*
X513480Y541499D03*
X518938Y540425D03*
X521938Y540325D03*
X516380Y540364D03*
X525338Y540125D03*
X513838Y556925D03*
X516738Y562425D03*
X513738D03*
X512354Y590825D03*
X515413Y590950D03*
X524638Y590225D03*
X520228Y590335D03*
X519638Y600425D03*
X523538Y600325D03*
X527438D03*
X525570Y602466D03*
X514058Y605055D03*
X523800Y611145D03*
X520370Y625158D03*
X526300Y623621D03*
X518920Y615387D03*
X519830Y634663D03*
X511910Y638722D03*
X514320Y641085D03*
X515371Y658880D03*
X515438Y649996D03*
X525692Y654862D03*
X517328Y655529D03*
X521516Y650576D03*
X517806Y670102D03*
X517222Y673917D03*
X518800Y665776D03*
X526610Y672286D03*
X515541Y661845D03*
X526430Y664730D03*
X515425Y685783D03*
X518382Y678247D03*
X515429Y692278D03*
X526600Y679117D03*
X517888Y687901D03*
X518947Y685122D03*
X527111Y686052D03*
X515429Y697278D03*
X518500Y723073D03*
X512548Y722093D03*
X514620Y713193D03*
X517443Y717011D03*
X517775Y711203D03*
X522865Y711178D03*
X514498Y716473D03*
X519440Y735681D03*
X512140Y736554D03*
X514901Y724120D03*
X523370Y724131D03*
X516940Y735683D03*
X521800Y732667D03*
X514420Y733131D03*
X524576Y733227D03*
X512610Y747115D03*
X525110Y774395D03*
X519440Y772861D03*
X519746Y791476D03*
X515809D03*
X542180Y93534D03*
X539510Y108742D03*
X542248Y106333D03*
X536955Y100257D03*
X532955Y108669D03*
X528955Y99781D03*
X532955Y100604D03*
X535960Y112850D03*
X527613Y113373D03*
X542700Y112881D03*
X527898Y147146D03*
X538655Y151415D03*
X538294Y159415D03*
X533483Y177449D03*
X533797Y180764D03*
X529272Y178311D03*
X542002Y180100D03*
X539500Y196500D03*
X536232Y192086D03*
X529592Y192999D03*
X533474Y196500D03*
X541657Y207645D03*
X532320Y209470D03*
X538525Y213425D03*
X532500Y206500D03*
X536676Y234993D03*
X534208Y227832D03*
X528105Y230594D03*
X536576Y246993D03*
X539438Y250323D03*
X536972Y242993D03*
X536476Y238993D03*
X535772Y250076D03*
X529527Y265584D03*
X539267Y267102D03*
X532794Y282068D03*
X530119Y280101D03*
X528680Y317349D03*
X541380Y340358D03*
X543110Y333848D03*
X536180Y341432D03*
X536170Y336603D03*
X531795Y340409D03*
X531430Y337074D03*
X527603Y337208D03*
X529910Y419478D03*
X540700Y418852D03*
X541650Y422280D03*
X536440Y421973D03*
X530940Y422207D03*
X541440Y431787D03*
X536440Y431923D03*
X531440Y432178D03*
X529968Y440216D03*
X529028Y430469D03*
X535352Y440414D03*
X542738Y455823D03*
X530038Y444323D03*
X533040Y453221D03*
X540141Y442994D03*
X534738Y445523D03*
X541838Y450723D03*
X533740Y458021D03*
Y465021D03*
X542738Y463123D03*
X533740Y473021D03*
X540938Y473623D03*
X535729Y476632D03*
X539419Y491107D03*
X532934Y491384D03*
X538038Y488323D03*
X533038D03*
X543280Y491040D03*
X530438Y529525D03*
X541538Y529625D03*
X534401Y529562D03*
X530638Y539525D03*
X534638Y539825D03*
X541238Y539625D03*
X528138Y539925D03*
X533038Y590325D03*
X540701Y590162D03*
X527638Y590325D03*
X535776Y590487D03*
X530338Y590325D03*
X536438Y600425D03*
X542438Y613723D03*
X529408Y603485D03*
X540540Y601008D03*
X538828Y602945D03*
X542848Y602975D03*
X535048Y602885D03*
X538400Y613804D03*
X541980Y620227D03*
X527828Y615387D03*
X532420Y615484D03*
X540048Y629641D03*
X539471Y632476D03*
X530779Y637354D03*
X532479Y633588D03*
X535230Y648711D03*
X541440Y647594D03*
X531970Y650491D03*
X542424Y654821D03*
X536557Y655498D03*
X539120Y670129D03*
X529525Y669349D03*
X529899Y661020D03*
X539734Y675020D03*
X539830Y667332D03*
X531599Y689838D03*
X533270Y679351D03*
X531597Y697509D03*
X535485Y715182D03*
X535272Y711217D03*
X535062Y708679D03*
X530012Y708618D03*
X543193Y710787D03*
X539577Y721891D03*
X537503Y710088D03*
X528388Y722903D03*
X540062Y708779D03*
X537702Y735662D03*
X541940Y735681D03*
X528440D03*
X531845Y724095D03*
X532940Y734810D03*
X531029Y733142D03*
X539650Y780942D03*
X529300Y771341D03*
X533600Y778780D03*
X539431Y791476D03*
X535494D03*
X547248Y106582D03*
X555938Y97292D03*
X551454Y97154D03*
X547480Y96632D03*
X557995Y110244D03*
X546306Y110193D03*
X550490Y112989D03*
X548367Y135415D03*
X548007Y139415D03*
X552173Y138528D03*
X550599Y132596D03*
X547543Y143415D03*
X550550Y151682D03*
X558059Y154254D03*
X558348Y142511D03*
X551464Y143862D03*
X550604Y168072D03*
X558845Y158697D03*
X550370Y157461D03*
X557668Y176534D03*
X555510Y173872D03*
X551395Y174172D03*
X555836Y179259D03*
X546000Y180000D03*
X558768Y191223D03*
X544500Y197500D03*
X546000Y192000D03*
X553909Y207401D03*
X547927Y212190D03*
X558416Y210682D03*
X544700Y216100D03*
X549909Y207060D03*
X557909Y207537D03*
X555750Y212029D03*
X544500Y207000D03*
X547148Y220220D03*
X545424Y226722D03*
X546690Y233066D03*
X544990Y231086D03*
X549488Y233003D03*
X549358Y230153D03*
X552120Y232388D03*
X552050Y229124D03*
X550040Y243929D03*
X545703Y245725D03*
X545981Y236287D03*
X550090Y247079D03*
X545116Y266847D03*
X547929Y258102D03*
X557207Y274828D03*
X551341Y274262D03*
X545223Y276895D03*
X557207Y280328D03*
X555072Y289563D03*
X557222Y285109D03*
X553690Y340829D03*
X547340Y339103D03*
X555707Y389146D03*
X552090Y388953D03*
X548470Y378127D03*
X549760Y407251D03*
X553230D03*
X553750Y410420D03*
X544500Y422583D03*
X557017Y438968D03*
X549574Y432582D03*
X543381Y448428D03*
X556771Y456156D03*
X556959Y443009D03*
X551140Y445789D03*
X555140Y445940D03*
X546384Y445107D03*
X547488Y452373D03*
X556971Y460656D03*
X554550Y469674D03*
X545513Y469740D03*
X543338Y459323D03*
X547638Y462356D03*
X546038Y457523D03*
X547340Y484025D03*
X546250Y490302D03*
X548000Y509493D03*
X547880Y515743D03*
X544370Y510267D03*
Y515267D03*
X544138Y530125D03*
X554860Y531701D03*
X549920Y527242D03*
X545413Y547950D03*
X551161Y547148D03*
X545138Y539725D03*
X551538Y540325D03*
X551338Y544225D03*
X551438Y561225D03*
X551338Y551100D03*
X551438Y563825D03*
X551538Y568525D03*
X551238Y571725D03*
X550938Y587325D03*
X547000Y590163D03*
X551238Y584025D03*
X543850Y590313D03*
X548138Y600425D03*
X544638Y600525D03*
X553619Y601204D03*
X550149Y604639D03*
X546938Y613828D03*
X543400Y625963D03*
X552350Y614028D03*
X552849Y631652D03*
X558281Y637840D03*
X551030Y637200D03*
X543400Y635615D03*
X545377Y647594D03*
X549314D03*
X551230Y652844D03*
X555356Y665156D03*
Y669156D03*
X555308Y673156D03*
X551283Y670800D03*
X555357Y689156D03*
X555284Y685156D03*
X555235Y681156D03*
X555308Y677156D03*
X547346Y697581D03*
X544984Y699419D03*
X551283Y699243D03*
X555150Y697156D03*
X555271Y693156D03*
X547542Y711523D03*
X544934Y720820D03*
X550535Y721903D03*
X555551Y722342D03*
X557488Y713709D03*
X553725Y717251D03*
X550004Y709559D03*
X555062Y708679D03*
X545062D03*
X555148Y735583D03*
X550940Y735681D03*
X546440D03*
X553193Y724847D03*
X546566Y724119D03*
X544082Y724460D03*
X549049Y724412D03*
X557426Y724436D03*
X557978Y734053D03*
X545300Y783152D03*
X550940Y771858D03*
X554870Y779438D03*
X555179Y791476D03*
X566090Y109136D03*
X560938Y97195D03*
X569559Y103123D03*
X565938Y96820D03*
X563230Y150222D03*
X564076Y145372D03*
X563410Y165289D03*
X563274Y162169D03*
X562195Y159015D03*
X563129Y178369D03*
X559646Y174476D03*
X569682Y195199D03*
X572782D03*
X561909Y207393D03*
X569874Y231795D03*
X572690Y226569D03*
X572020Y222393D03*
X567980Y222353D03*
X568410Y226647D03*
X561258Y230153D03*
X566248Y230283D03*
X563506Y232027D03*
X571576Y246693D03*
X564676D03*
X571476Y260093D03*
X564676D03*
Y253693D03*
X564274Y279395D03*
X566774Y275195D03*
X566876Y289890D03*
X561525Y298192D03*
X560865Y285434D03*
X565953Y301635D03*
X567320Y415088D03*
X565310Y412700D03*
X565977Y456156D03*
X566059Y460956D03*
X572440Y464323D03*
Y469323D03*
X562340Y484252D03*
X561610Y503885D03*
X560960Y510151D03*
X571830Y509411D03*
X573840Y512108D03*
X564370Y504117D03*
Y509117D03*
X567791Y528325D03*
X568068Y525306D03*
X567493Y532225D03*
X561065Y543998D03*
X560838Y540325D03*
X562308Y536895D03*
X566298Y548465D03*
X563188Y541925D03*
X566338Y554235D03*
X561174Y564471D03*
X574738Y579525D03*
X565858Y576195D03*
X561198Y581793D03*
X566378Y567725D03*
X561608Y571775D03*
X574537Y591325D03*
X574738Y587425D03*
X574645Y583525D03*
X565398Y584765D03*
X568163Y595115D03*
X561568Y589355D03*
X574071Y606204D03*
X568930Y607754D03*
X566053Y627509D03*
X571650Y625998D03*
X574730Y625521D03*
X565647Y637705D03*
X565556Y632431D03*
X571790Y646799D03*
X559440Y650767D03*
X566950Y659439D03*
X563850Y659575D03*
X563840Y653515D03*
X565168Y664614D03*
Y674614D03*
Y669614D03*
Y684614D03*
X563586Y682137D03*
X563577Y692284D03*
X563441Y676872D03*
X565168Y679614D03*
X563393Y686908D03*
X565168Y689614D03*
X568215Y702343D03*
X565168Y694614D03*
Y699614D03*
X568288Y715547D03*
X560544Y718091D03*
X569604Y721248D03*
X574190Y717805D03*
X564319Y721587D03*
X562540Y713454D03*
X560062Y708679D03*
X570614Y713237D03*
X565062Y708679D03*
X568908Y735883D03*
X573440Y735681D03*
X564438Y735853D03*
X560350Y735807D03*
X573440Y724053D03*
X568940Y724090D03*
X562395Y724557D03*
X571232Y732545D03*
X566798Y734023D03*
X569680Y771106D03*
X560150Y781347D03*
X562700Y772391D03*
X572720Y777184D03*
X559116Y791476D03*
X578938Y103123D03*
X588943Y98963D03*
X589308Y103990D03*
X583829Y117732D03*
X583661Y121836D03*
X580501Y138336D03*
X583829Y132232D03*
X583547Y128232D03*
X587968Y138765D03*
X581565Y154969D03*
X583970Y144589D03*
X580180Y148894D03*
X579540Y143304D03*
X579897Y161355D03*
X584438Y160933D03*
X582792Y167632D03*
X581915Y179955D03*
X582920Y194220D03*
X588692Y192809D03*
X585580Y210516D03*
X579707Y220662D03*
X583707Y220762D03*
X587707Y220728D03*
X579707Y229395D03*
X585579Y230095D03*
X576105Y231626D03*
X578076Y246693D03*
Y253393D03*
Y260093D03*
X575874Y282395D03*
X581474Y274795D03*
X575874Y289895D03*
Y285995D03*
X575880Y293016D03*
X575908Y295606D03*
X583853Y313783D03*
X585584Y308881D03*
X579168Y313641D03*
X588607Y305034D03*
X576650Y311446D03*
X581650D03*
X583737Y321204D03*
X585984Y323246D03*
X579788Y354743D03*
X589070Y423525D03*
X578830Y448192D03*
X575550Y463784D03*
X575650Y469996D03*
X588153Y459599D03*
X579600Y508878D03*
X578840Y512108D03*
X585013Y547959D03*
X575438Y545425D03*
X589036Y548825D03*
X583890Y537093D03*
X576208Y542405D03*
X575838Y548935D03*
X575238Y552025D03*
X588540Y557418D03*
X584413Y563198D03*
X583538Y552225D03*
X575038Y554725D03*
X575138Y559825D03*
X577778Y556355D03*
X575038Y567725D03*
X575538Y571725D03*
X574876Y575625D03*
X578110Y582149D03*
X582023Y571242D03*
X586369Y585801D03*
X578399Y585696D03*
X588780Y611056D03*
X586810Y603344D03*
X579500Y625963D03*
X577000Y620029D03*
X585500Y620926D03*
X588780Y616056D03*
X587440Y656958D03*
X576700Y655594D03*
X588950Y650070D03*
X583930Y652439D03*
X579020Y658250D03*
X577217Y652002D03*
X576987Y660180D03*
X580740Y653286D03*
X584903Y663828D03*
X580637Y663629D03*
X576846Y675985D03*
X579076Y669603D03*
X576520Y667750D03*
X586060Y682582D03*
X587040Y688218D03*
X589050Y680160D03*
X579980Y683140D03*
X576644Y679562D03*
X578030Y690236D03*
X577010Y682718D03*
X576519Y687665D03*
X589500Y690546D03*
X586995Y694080D03*
X579151Y707857D03*
X588151D03*
X584101Y707893D03*
X576442Y705492D03*
X585400Y697289D03*
X584312Y710716D03*
X579220Y720776D03*
X585693Y722428D03*
X583440Y735856D03*
X587940Y735681D03*
X587963Y724108D03*
X577940Y724127D03*
X583440Y724927D03*
X577570Y734118D03*
X580510Y724421D03*
X587170Y773768D03*
X579240Y775147D03*
X578802Y791476D03*
X574864D03*
X603158Y91535D03*
X601374Y94048D03*
X604543Y94886D03*
X598123Y102023D03*
X595318Y98854D03*
X593850Y103755D03*
X592392Y100623D03*
X594920Y123370D03*
X595345Y120216D03*
X605070Y123991D03*
X600118Y112568D03*
X592938Y117657D03*
X595438Y138130D03*
X592938Y140689D03*
Y133232D03*
X594938Y127893D03*
X593537Y161023D03*
X592917Y171906D03*
X592491Y175906D03*
X593277Y179955D03*
X595707Y220995D03*
X591707Y221095D03*
Y230162D03*
X597074Y239995D03*
X600874Y239795D03*
X604774Y249795D03*
X596774D03*
X600874D03*
X604674Y239995D03*
X592874Y250995D03*
X605674Y236295D03*
X595374Y236795D03*
X592858Y247079D03*
X593459Y240780D03*
X594067Y265168D03*
X594174Y256695D03*
X593874Y262395D03*
X596574Y268695D03*
X600674Y268795D03*
X604574D03*
X604926Y278476D03*
X604774Y271893D03*
X590874Y275195D03*
X594374Y271395D03*
X596574Y276393D03*
X592201Y308988D03*
X593607Y305034D03*
X591977Y319360D03*
X590984Y323246D03*
X598551Y329541D03*
X601450Y326509D03*
X604338Y338285D03*
X600770Y358702D03*
X605746Y387837D03*
X597440Y391690D03*
X605573Y393920D03*
X594860Y395088D03*
X600680Y412780D03*
X590720Y456076D03*
X591100Y450128D03*
X605800Y463167D03*
X603819Y485332D03*
X605798Y501238D03*
X598670Y508170D03*
X596751Y532108D03*
X603010Y527908D03*
X596560Y536108D03*
X606300Y551844D03*
X604820Y555040D03*
X604437Y557956D03*
X596050Y557563D03*
X596530Y574903D03*
X596495Y578903D03*
X592437Y566543D03*
X601043Y567781D03*
X596484Y582903D03*
X596209Y586903D03*
X590898Y597158D03*
X605396Y590552D03*
X605286Y584152D03*
X605290Y594166D03*
X596401Y589852D03*
X593867Y595695D03*
X605521Y601097D03*
X590842Y608112D03*
X591023Y600384D03*
X605362Y609413D03*
X602314Y607641D03*
Y602641D03*
X593867Y600695D03*
X590646Y618751D03*
X605010Y641435D03*
X600980Y641533D03*
X594733Y653385D03*
X591279Y656223D03*
X596998Y658008D03*
X591840Y659568D03*
X596470Y655231D03*
X601588Y664798D03*
X602332Y671156D03*
X600736Y668425D03*
X593142Y663828D03*
X600719Y675156D03*
X597300Y663128D03*
X600690Y691896D03*
X600727Y681876D03*
X602020Y679156D03*
X600727Y686876D03*
X604220Y703774D03*
X600650Y707835D03*
X592960Y703291D03*
X592440Y723768D03*
X596860Y723422D03*
X601856Y711479D03*
X606146Y713145D03*
X601813Y715579D03*
X598880Y719232D03*
X595950Y708997D03*
X594170Y719290D03*
X601440Y735681D03*
X605938Y735665D03*
X596940Y735681D03*
X593004Y735662D03*
X603938Y753623D03*
X606270Y774615D03*
X597530Y780191D03*
X592480Y771514D03*
X598487Y791476D03*
X594550D03*
X618623Y108918D03*
X610543Y107678D03*
X617925Y114064D03*
X613432Y153528D03*
X608274Y249795D03*
X608774Y239995D03*
X610415Y237441D03*
X617778Y238873D03*
X608274Y268795D03*
X612974Y269095D03*
X609150Y328514D03*
X616490Y327534D03*
X613640Y336986D03*
X607671Y344818D03*
X619190Y336986D03*
X608306Y359971D03*
X611848Y359784D03*
X607855Y352341D03*
X618581Y354818D03*
X617592Y362539D03*
X620238Y364369D03*
X609078Y388557D03*
X608869Y396959D03*
X608821Y403445D03*
X619014Y408353D03*
X609078Y393557D03*
X612641Y397478D03*
Y402478D03*
X611050Y423087D03*
X621399Y420400D03*
X611130Y417928D03*
X616258Y422211D03*
X610580Y448662D03*
X609370Y452974D03*
X610010Y456581D03*
X617980Y460408D03*
X621760Y526967D03*
X609300Y531638D03*
X613541Y546764D03*
X613470Y537495D03*
X616320Y537066D03*
X609168Y554851D03*
X610070Y557588D03*
X621937Y558276D03*
X621840Y555040D03*
X609060Y552101D03*
X607077Y566915D03*
X610821Y566494D03*
X621937Y567143D03*
X609026Y579132D03*
X617270Y580443D03*
X611520Y596594D03*
X612270Y586543D03*
X612493Y607666D03*
X611254Y617943D03*
X612370Y614143D03*
X615690Y625536D03*
X614579Y645072D03*
X616730Y633290D03*
X608310Y641603D03*
X611572Y629894D03*
X620510Y639427D03*
X616471Y636215D03*
X613796Y648705D03*
X612950Y656140D03*
X607620Y647169D03*
X615700Y657757D03*
X610651Y675156D03*
X614909Y671938D03*
X613200Y661577D03*
X620160Y670594D03*
X615940Y666862D03*
X617235Y689036D03*
X610693Y679333D03*
X610570Y691156D03*
X610550Y686640D03*
X610810Y683933D03*
X612670Y681438D03*
X612811Y688422D03*
X621410Y696941D03*
X607020Y704644D03*
X608975Y708094D03*
X612914Y707630D03*
X610540Y697964D03*
X618020Y700000D03*
X610570Y695156D03*
X607380Y699671D03*
X617930Y703520D03*
X620480Y693827D03*
X611244Y709830D03*
X621254Y713788D03*
X617093Y709167D03*
X609070Y721917D03*
X616070Y720838D03*
X613730Y717663D03*
X620670Y722216D03*
X620830Y717516D03*
X609840Y713617D03*
X619590Y735383D03*
X614732Y735517D03*
X608791Y735775D03*
X619080Y772610D03*
X619030Y778682D03*
X612260Y783106D03*
X609347Y778624D03*
X618172Y791476D03*
X614235D03*
X610298D03*
X626380Y85117D03*
X624020Y83243D03*
X623750Y87130D03*
X626380Y88518D03*
X623725Y90422D03*
X626180Y91919D03*
X623820Y93654D03*
X626320Y96084D03*
X623610Y97125D03*
X626180Y99276D03*
X628838Y120216D03*
X628738Y133012D03*
X624800Y184953D03*
Y179953D03*
X624358Y176090D03*
X632483Y192781D03*
X624950Y189801D03*
X632485Y202077D03*
X634962Y200121D03*
Y195121D03*
X622470Y261628D03*
X635000Y265400D03*
X634212Y281670D03*
X624101Y296525D03*
X624383Y292591D03*
X631672Y301066D03*
X632376Y305257D03*
X631702Y307880D03*
X632122Y312898D03*
X633773Y310439D03*
X635652Y313118D03*
X636962Y310928D03*
X623820Y321062D03*
X633470Y326710D03*
X628140Y317610D03*
X631860Y321455D03*
X627000Y327926D03*
X622890Y325227D03*
X633652Y315198D03*
X628141Y344818D03*
X630190Y336986D03*
X625190D03*
X624889Y357778D03*
X637738Y392034D03*
X636990Y386464D03*
X627022Y383713D03*
X634511Y389156D03*
X633633Y403717D03*
X637614Y397259D03*
X630691Y405007D03*
X636938Y402885D03*
X633663Y411009D03*
X630691Y410007D03*
X636586Y410910D03*
X633455Y427209D03*
X634578Y424964D03*
X635840Y449890D03*
X626250Y450248D03*
X631280Y446007D03*
X635120Y456136D03*
X630570Y451450D03*
X634945Y461888D03*
X635545Y465888D03*
X622100Y465822D03*
X625900Y461769D03*
X628250Y471142D03*
X632680Y466669D03*
X636010Y469995D03*
X630420Y491511D03*
X636170Y493028D03*
X622600Y488753D03*
X622199Y506535D03*
X632157Y511230D03*
X625130Y534199D03*
X634530Y521565D03*
X634190Y538267D03*
X622798Y546764D03*
X632362Y565543D03*
X636890Y571351D03*
X624870Y573143D03*
X627084Y578257D03*
X634921Y580163D03*
X627047Y581066D03*
X636868Y593141D03*
X630768Y593241D03*
X624468D03*
Y612141D03*
X624368Y605941D03*
Y599741D03*
X629868Y612241D03*
X635968D03*
X623940Y628720D03*
X636890Y627095D03*
X629781Y628559D03*
X627986Y625895D03*
X630984Y624829D03*
X622510Y635544D03*
X634137Y631342D03*
X627146Y638932D03*
X623290Y641222D03*
X634137Y639352D03*
X630137Y639312D03*
X631930Y655254D03*
X634251Y683493D03*
X623940Y723503D03*
X633970Y723033D03*
X622290Y708516D03*
X628160Y722343D03*
X623960Y735141D03*
X628380Y735476D03*
X631690Y733744D03*
X635460Y735130D03*
X636170Y729335D03*
X630040Y745114D03*
X632300Y749755D03*
X636910Y745815D03*
X624010Y746351D03*
X629912Y769200D03*
X625010Y778281D03*
X636390Y775395D03*
X632030Y779137D03*
X632000Y775400D03*
X629983Y791476D03*
X633920D03*
X643957Y53688D03*
X639957Y53849D03*
X638970Y132241D03*
X639200Y170100D03*
X639350Y250123D03*
X640448Y294422D03*
X643170Y294282D03*
X641227Y297070D03*
X644113Y297071D03*
X653352Y291388D03*
X642932Y284768D03*
X640112Y285042D03*
X649995Y296433D03*
X640171Y311965D03*
X644105D03*
X652362Y306598D03*
X651352Y323938D03*
X653162Y318398D03*
X650162D03*
X640647Y339854D03*
X648450Y338711D03*
X646013Y358110D03*
X648838Y349785D03*
X642863Y358010D03*
X639838Y349818D03*
X646171Y364676D03*
X648425Y373474D03*
X652139Y377125D03*
X647440Y386383D03*
X641236Y381616D03*
X645236Y377858D03*
X647340Y393283D03*
X647440Y408383D03*
X647340Y400083D03*
X651138Y417385D03*
X648493Y417221D03*
X641480Y430289D03*
X650079D03*
X648208Y427819D03*
X643208D03*
X653070Y427500D03*
X650822Y425295D03*
X641690Y443656D03*
X647280Y446851D03*
X653360Y446280D03*
X651080Y455238D03*
X652110Y465238D03*
X651840Y460012D03*
X648920Y457851D03*
X646600Y463571D03*
X648956Y469323D03*
X646381Y478679D03*
X650521Y482930D03*
X647921Y475778D03*
X651395Y487265D03*
X646105Y492010D03*
X650790Y497730D03*
X650150Y494337D03*
X646906Y505210D03*
X638350Y507893D03*
X641842Y516730D03*
X646460Y512967D03*
X652690Y531693D03*
X640470Y523266D03*
X645040Y524444D03*
X645150Y535704D03*
X638166Y560972D03*
X638286Y557415D03*
X643012Y565243D03*
X651437Y569676D03*
X639673Y576888D03*
X651437Y578943D03*
X646732Y580781D03*
X641870Y580743D03*
X646870Y569443D03*
Y576243D03*
X643568Y593241D03*
Y612341D03*
Y606641D03*
Y599541D03*
X644636Y627257D03*
X642795Y624818D03*
X648701Y624774D03*
X638470Y639290D03*
X650928D03*
X646940Y643448D03*
X641263Y631393D03*
X649173Y629876D03*
X646737Y639413D03*
X642737D03*
X647870Y649784D03*
X646580Y654775D03*
X651226Y666288D03*
X639940Y687841D03*
X640330Y684439D03*
X642999Y685781D03*
X648077Y713569D03*
X644950Y719110D03*
X653500Y732583D03*
X639928Y738905D03*
X638890Y734879D03*
X652660Y749000D03*
X639920Y753526D03*
X646680Y755009D03*
X646500Y746300D03*
X650400Y770522D03*
X638470Y762212D03*
X649640Y757527D03*
X646370Y759252D03*
X647410Y767053D03*
X651690Y778099D03*
X640010Y778215D03*
X652212Y786700D03*
X655947Y53677D03*
X659947Y53722D03*
X658769Y143630D03*
X658767Y151013D03*
X655642Y144915D03*
Y149915D03*
X658959Y165625D03*
X658972Y158337D03*
X655695Y159567D03*
Y164567D03*
X667300Y188112D03*
X660700Y203282D03*
X669250Y203317D03*
X665320Y203247D03*
X664560Y195018D03*
Y191443D03*
X660770Y214951D03*
X665390Y214916D03*
X661160Y235485D03*
X658582Y222614D03*
X658601Y229770D03*
X655030Y228744D03*
Y223744D03*
X661190Y246085D03*
X657838Y243407D03*
Y238407D03*
X660899Y311515D03*
X656270Y299379D03*
X654962Y307698D03*
X654060Y302459D03*
X659350Y298810D03*
X654352Y323938D03*
X655122Y315070D03*
X656730Y338633D03*
X666270Y359134D03*
X660138Y365885D03*
X659543Y377086D03*
X662390Y377039D03*
X653938Y364885D03*
X668925Y364887D03*
X663632Y366698D03*
X654340Y386283D03*
X661140D03*
X669215Y377488D03*
X654840Y408483D03*
X661940Y408383D03*
X666312Y417742D03*
X658295Y417662D03*
X653649Y417582D03*
X668779Y417135D03*
X663674Y417999D03*
X655812Y424106D03*
X656021Y427864D03*
X665766Y427868D03*
X663339Y425601D03*
X658339D03*
X664450Y435739D03*
X658680Y446610D03*
X664528Y463432D03*
X667428D03*
X666928Y468132D03*
X660458Y470932D03*
X659828Y465162D03*
X667774Y477992D03*
X661158Y486152D03*
X667070Y483608D03*
X662780Y477039D03*
X660518Y492862D03*
X662630Y500823D03*
X654240Y511568D03*
X653800Y505331D03*
X659933Y513927D03*
X664024Y513414D03*
X668573Y514155D03*
X668823Y532470D03*
X668627Y527718D03*
X659740Y536019D03*
X667050Y535324D03*
X665170Y595943D03*
X661396Y588900D03*
X655445Y591918D03*
X664603Y601976D03*
X658980Y610043D03*
X655978Y609635D03*
X656070Y612743D03*
X655688Y601761D03*
X664870Y614543D03*
X654645Y627064D03*
X667610Y617197D03*
X663560Y625019D03*
X659600Y623785D03*
X655873Y615540D03*
X655170Y639432D03*
X654221Y631425D03*
X656971Y660492D03*
X657550Y655072D03*
X668000Y676595D03*
X659978Y666274D03*
X656254Y683277D03*
X663040Y688057D03*
X665050Y680648D03*
X657340Y690286D03*
X655610Y706309D03*
X656505Y701191D03*
X654514Y720674D03*
X657320Y723584D03*
X654050Y718086D03*
X656650Y713057D03*
X659200Y721454D03*
X659300Y734119D03*
X654000Y736400D03*
X656660Y736218D03*
X655574Y728674D03*
X657570Y730414D03*
X658860Y727383D03*
X656000Y732400D03*
X657500Y761500D03*
X664460Y785890D03*
X657010Y786039D03*
X661479Y791476D03*
X665416D03*
X679927Y53881D03*
X675927Y53779D03*
X669987Y53672D03*
X670980Y77061D03*
X671810Y106472D03*
X670280Y188112D03*
X676590Y188198D03*
X680100Y188182D03*
X680220Y200725D03*
X678650Y203480D03*
X681770Y203514D03*
X682140Y191214D03*
Y194615D03*
X680310Y217357D03*
X678750Y214908D03*
X681870Y214942D03*
X669320Y214986D03*
X671129Y305579D03*
X671166Y302550D03*
X679590Y352829D03*
X679430Y350013D03*
X672752Y366160D03*
X679552Y372873D03*
X677083Y375124D03*
X669540Y386283D03*
X678099Y389915D03*
X674235Y379364D03*
X677946Y387211D03*
X678986Y392661D03*
X669440Y395183D03*
Y408483D03*
X669540Y402783D03*
X678338Y405185D03*
X679138Y397985D03*
X680017Y403143D03*
X678838Y407785D03*
X673368Y416621D03*
X671056Y426300D03*
X683128Y451332D03*
X680228Y451432D03*
X672660Y441007D03*
X673740Y449887D03*
X682764Y444832D03*
X677070Y444820D03*
X670428Y463532D03*
X669728Y468032D03*
X672628D03*
X672190Y457216D03*
X683112Y479786D03*
X679299Y491473D03*
X684876Y497385D03*
X674156Y503662D03*
X678450Y508438D03*
X680790Y504521D03*
X677160Y529422D03*
X675044Y524581D03*
X678315Y540752D03*
X684620Y535923D03*
X678217Y536752D03*
X678360Y557426D03*
X673950Y557314D03*
X677850Y562515D03*
X673700D03*
X677730Y567706D03*
X673590Y567696D03*
X670940Y612070D03*
X683720Y631732D03*
X681310Y666671D03*
X671400Y666151D03*
X678386Y668420D03*
X673386D03*
X669390Y695406D03*
X672630Y720752D03*
X675100Y749300D03*
X672710Y746235D03*
X672500Y749179D03*
X684500Y786665D03*
X676390Y778439D03*
X677490Y782114D03*
X673290Y782855D03*
X677227Y786454D03*
X669320Y783845D03*
X681480Y777388D03*
X681164Y783461D03*
X669810Y786721D03*
X672500Y779579D03*
X683520Y789080D03*
Y792080D03*
X688160Y64459D03*
X689500Y120441D03*
X691148Y140140D03*
X698150Y136791D03*
X691280Y149571D03*
X691314Y145071D03*
X687546Y154228D03*
X699990Y149631D03*
X700060Y144981D03*
X687571Y172292D03*
X693520Y186376D03*
X697850Y186441D03*
X689820Y200159D03*
Y203491D03*
X689480Y191144D03*
Y194615D03*
X691970Y216820D03*
X691690Y212100D03*
X693540Y205721D03*
X697800Y205879D03*
X692010Y221158D03*
X687584Y233034D03*
Y251770D03*
X689864Y392130D03*
X686686Y392522D03*
X687869Y386780D03*
X688118Y381043D03*
X687121Y407004D03*
X689864Y398141D03*
X686686Y397522D03*
X689527Y407843D03*
X685859Y403970D03*
X691037Y401739D03*
X686731Y413349D03*
X689527Y412843D03*
X687130Y464132D03*
X691070Y464058D03*
X689017Y497282D03*
X694823Y498932D03*
X691161Y518684D03*
X692520Y506898D03*
X696494Y513677D03*
X689729Y509580D03*
X696891Y507279D03*
X700719Y516954D03*
X686661Y519199D03*
X698438Y524890D03*
X686770Y543325D03*
X694150Y536155D03*
X690040Y535797D03*
X687183Y539585D03*
X691532Y559789D03*
Y563789D03*
Y567789D03*
Y571789D03*
Y575789D03*
Y579789D03*
Y583789D03*
Y587789D03*
X695600Y590788D03*
X685410Y621250D03*
X688340Y621294D03*
X687660Y631799D03*
X685640Y634154D03*
X692720Y670540D03*
X698830Y670652D03*
X698386Y667241D03*
X693386D03*
X689100Y680291D03*
X688510Y735294D03*
X699600Y776000D03*
X689700Y774500D03*
X707176Y50574D03*
X711676Y51019D03*
X706380Y75482D03*
X708130Y106389D03*
X701687Y212132D03*
X700947Y216868D03*
X700994Y221368D03*
X701770Y331938D03*
X707942Y448676D03*
X714639Y454872D03*
X712239Y452293D03*
X702730Y455483D03*
X704550Y444407D03*
X715528Y459332D03*
X710768Y475972D03*
X715328Y481122D03*
X704766Y498880D03*
X713978Y498075D03*
X716021Y516945D03*
X700829Y504041D03*
X707736Y510140D03*
X707920Y505575D03*
X712281Y525785D03*
X706361Y532632D03*
X716260Y525295D03*
X712820Y519647D03*
X710585Y539103D03*
X701170Y538508D03*
X708258Y549815D03*
X701023Y553658D03*
X710873Y563230D03*
X713300Y578995D03*
X713190Y583032D03*
X712740Y593101D03*
X715282Y620282D03*
X711612Y620383D03*
X712732Y631749D03*
X716064D03*
X713742Y634373D03*
X703570Y673036D03*
X707660Y673204D03*
X708386Y669774D03*
X703386D03*
X713910Y681330D03*
X713445Y677641D03*
X708450Y695489D03*
X705870Y721832D03*
X709500Y736800D03*
X706575Y740425D03*
X704000Y770800D03*
X716245Y765576D03*
X704786Y791274D03*
X708723Y791092D03*
X709040Y787507D03*
X719800Y24920D03*
X726160Y109316D03*
X726190Y105325D03*
X726160Y112508D03*
X726500Y123466D03*
X726400Y130303D03*
X726470Y126659D03*
X731566Y442136D03*
X726580Y455637D03*
X731570Y464043D03*
X726430Y465371D03*
X726830Y460815D03*
X727940Y469943D03*
X731340Y476723D03*
X720140Y478333D03*
X718431Y483368D03*
X721290Y484381D03*
X719370Y472436D03*
X725730Y486788D03*
X729640Y486848D03*
X727602Y500100D03*
X720150Y491632D03*
X729942Y515757D03*
X719332D03*
X719761Y532432D03*
X728661Y558934D03*
X731251Y558975D03*
X726154Y559002D03*
X720445Y558990D03*
X723370Y558906D03*
X720052Y620480D03*
X719092Y631682D03*
X717372Y634474D03*
X727830Y641829D03*
X728690Y649829D03*
X718510Y681526D03*
X721100Y689400D03*
X718445Y677641D03*
X731200Y716200D03*
X729500Y737400D03*
X730800Y728400D03*
X729500Y746300D03*
X718150Y763015D03*
X721100Y762903D03*
X721245Y765576D03*
X727570Y775278D03*
X730990Y775334D03*
X726925Y778490D03*
X731925D03*
X721790Y791408D03*
X722590Y787885D03*
X738620Y109351D03*
X738650Y105360D03*
X744760Y103711D03*
X744790Y106938D03*
X747710Y100293D03*
X738620Y112543D03*
X738370Y123395D03*
X745070Y110183D03*
X738270Y130232D03*
X738340Y126588D03*
X747080Y129815D03*
X747600Y323527D03*
X745220Y327250D03*
X741401Y454832D03*
X736310Y450774D03*
X737350Y464330D03*
Y459823D03*
X742779Y487639D03*
X743364Y478975D03*
X743150Y483502D03*
X738130Y502748D03*
X732817Y489435D03*
X734575Y492575D03*
X745500Y492500D03*
X744020Y566143D03*
X744090Y575066D03*
X743951Y578833D03*
X744050Y571834D03*
X747470Y585542D03*
X747460Y582318D03*
X744000Y647919D03*
X733210Y645829D03*
X732540Y653829D03*
X734460Y788654D03*
Y791654D03*
X762590Y106529D03*
X762630Y103302D03*
X751080Y100293D03*
X754580Y124020D03*
X748070Y110209D03*
X751180D03*
X754610Y127247D03*
X750930Y129815D03*
X750430Y314330D03*
X750350Y311343D03*
X750700Y323771D03*
X753230Y328262D03*
X759400Y334839D03*
X754850Y335055D03*
X755500Y337791D03*
X758223Y446532D03*
X757823Y451032D03*
X758494Y455532D03*
X748723Y455332D03*
X758500Y469500D03*
X757500Y474000D03*
X748300Y496800D03*
X751730Y583047D03*
X752960Y653967D03*
X749520Y658372D03*
X765250Y357789D03*
X765610Y361194D03*
X766840Y561290D03*
X766920Y564080D03*
X766950Y558318D03*
X766820Y569897D03*
X766900Y567233D03*
Y572869D03*
X771110Y578643D03*
X770850Y575760D03*
X770710Y584054D03*
X770850Y587025D03*
G54D212*
G01X193100Y249980D02*
Y249010D01*
X191116Y247026D01*
Y238985D01*
X190898Y238767D01*
X190304D01*
X188899Y240172D01*
Y240208D01*
G01X196290Y248007D02*
X194841D01*
X194252Y248596D01*
X193818D01*
X191916Y246694D01*
Y238653D01*
X191230Y237967D01*
X190058D01*
X188899Y236808D01*
G01X196163Y257697D02*
X195054Y258806D01*
Y258836D01*
X194693Y259197D01*
G01X196163Y260697D02*
X194957Y261903D01*
Y261933D01*
X194693Y262197D01*
G01X210828Y249980D02*
X212127Y248681D01*
Y246910D01*
X213712Y245325D01*
Y240152D01*
X213291Y239731D01*
X212339D01*
X211935Y240135D01*
Y240785D01*
G01X214018Y248007D02*
X213760Y248265D01*
X213215D01*
X212927Y247977D01*
Y247242D01*
X214512Y245657D01*
Y239820D01*
X213623Y238931D01*
X212384D01*
X211935Y238482D01*
Y237385D01*
G01X214559Y266697D02*
Y266672D01*
X216092Y265139D01*
X216109D01*
G01X214559Y263697D02*
X214575D01*
X216109Y262163D01*
Y262139D01*
G01X243083Y260697D02*
X241613Y262167D01*
Y262197D01*
G01X243083Y266697D02*
X241613Y268167D01*
Y268197D01*
G01X258723Y263697D02*
X258004D01*
X256916Y262609D01*
G01X245839Y260697D02*
X246403D01*
X247389Y261683D01*
Y262139D01*
G01X258723Y260697D02*
Y260667D01*
X257253Y259197D01*
G01X245839Y266697D02*
Y267209D01*
X246769Y268139D01*
X247389D01*
G01X271276Y251569D02*
Y250612D01*
X269192Y248528D01*
Y248209D01*
G01X271252Y248656D02*
Y247185D01*
X272242Y246195D01*
Y244842D01*
G01X283784Y258579D02*
X283103Y259260D01*
X282916D01*
X281945Y260231D01*
G01X289927Y270415D02*
Y269489D01*
X290220Y269196D01*
X290670D01*
X291889Y270415D01*
X295054D01*
X297715Y267754D01*
Y263869D01*
X298913Y262671D01*
Y260168D01*
X297715Y258970D01*
Y256281D01*
X298520Y255476D01*
X299880D01*
X300310Y255046D01*
Y253842D01*
G01X287014Y270439D02*
X289620Y271791D01*
X290447D01*
X291023Y271215D01*
X295386D01*
X298515Y268086D01*
Y264201D01*
X299713Y263003D01*
Y259836D01*
X298515Y258638D01*
Y256613D01*
X298852Y256276D01*
X299344D01*
X300310Y257242D01*
G01X287014Y288167D02*
X287447Y288600D01*
Y289130D01*
X288605Y290288D01*
X302150D01*
X304100Y288338D01*
Y287366D01*
X304599Y286867D01*
X305132D01*
G01X288377Y285760D02*
Y288928D01*
X288937Y289488D01*
X301818D01*
X303300Y288006D01*
Y287366D01*
X302801Y286867D01*
X301732D01*
G54D203*
G01X75380Y608914D02*
X73735Y607269D01*
X72945D01*
X71330Y608884D01*
Y608914D01*
X68489D01*
G01X75380Y603914D02*
X73735Y605559D01*
X72945D01*
X71300Y603914D01*
X68489D01*
G01Y623914D02*
X65679D01*
X64034Y625559D01*
X62894D01*
X61205Y623870D01*
G01Y628870D02*
X62806Y627269D01*
X64034D01*
X65679Y628914D01*
X68489D01*
G01X70460Y707975D02*
Y694090D01*
X70550Y693545D01*
X77771Y672148D01*
X79340Y662464D01*
Y656171D01*
X78670Y655501D01*
Y654271D01*
X79340Y653601D01*
Y651466D01*
X79073Y650395D01*
X78356Y649963D01*
X78058Y648767D01*
X78491Y648052D01*
X78193Y646857D01*
X77476Y646425D01*
X77178Y645229D01*
X77611Y644514D01*
X76680Y640766D01*
X74559Y637623D01*
X74320Y637269D01*
X72945D01*
X71300Y638914D01*
X68489D01*
G01Y633914D02*
X71300D01*
X72945Y635559D01*
X75229D01*
X75977Y636666D01*
X78267Y640060D01*
X81050Y651256D01*
Y662602D01*
X79437Y672561D01*
X72215Y693960D01*
X72170Y694231D01*
Y696299D01*
G01X65740Y717159D02*
Y691118D01*
X69412Y679799D01*
X68968Y678931D01*
X69349Y677759D01*
X70217Y677317D01*
X70598Y676145D01*
X70154Y675277D01*
X70535Y674105D01*
X71403Y673663D01*
X71784Y672491D01*
X71340Y671623D01*
X71721Y670451D01*
X72589Y670009D01*
X73109Y668408D01*
X73295Y667268D01*
X72882Y666696D01*
X73083Y665480D01*
X73655Y665071D01*
X73856Y663855D01*
X73444Y663284D01*
X73645Y662068D01*
X74217Y661659D01*
X74490Y660003D01*
X74488Y658150D01*
X73607Y657269D01*
X72945D01*
X71300Y658914D01*
X68489D01*
G01Y653914D02*
X71300D01*
X72945Y655559D01*
X74316D01*
X76198Y657441D01*
X76201Y660142D01*
X74776Y668813D01*
X67450Y691389D01*
Y727094D01*
G01X74862Y807872D02*
Y798986D01*
X75975Y797873D01*
Y771321D01*
X72096Y755555D01*
X71105Y754954D01*
X63925Y756721D01*
X61722Y755387D01*
X60720Y751314D01*
X62053Y749112D01*
X69233Y747345D01*
X69833Y746354D01*
X69170Y743663D01*
X68179Y743062D01*
X60999Y744829D01*
X58796Y743495D01*
X57794Y739422D01*
X59127Y737220D01*
X66307Y735453D01*
X66908Y734462D01*
X65790Y729921D01*
X65740Y729513D01*
Y717159D01*
G01X78799Y807872D02*
Y798987D01*
X77685Y797873D01*
Y771113D01*
X73588Y754459D01*
X71385Y753123D01*
X64205Y754891D01*
X63214Y754290D01*
X62551Y751594D01*
X63150Y750604D01*
X70330Y748837D01*
X71664Y746633D01*
X70662Y742567D01*
X68459Y741231D01*
X61279Y742999D01*
X60288Y742398D01*
X59625Y739702D01*
X60224Y738712D01*
X67403Y736945D01*
X68739Y734742D01*
X67475Y729611D01*
X67450Y729408D01*
Y727094D01*
G01X72170Y696299D02*
Y726964D01*
X82062Y755755D01*
X83103Y756264D01*
X86788Y754997D01*
X89102Y756128D01*
X90466Y760094D01*
X89335Y762407D01*
X85650Y763674D01*
X85141Y764715D01*
X85950Y767067D01*
Y767673D01*
X89475Y784568D01*
X89496Y785616D01*
Y797873D01*
X90610Y798987D01*
Y807872D01*
G01X70460Y707975D02*
Y727250D01*
X80674Y756981D01*
X82989Y758112D01*
X86674Y756845D01*
X87714Y757354D01*
X88618Y759980D01*
X88109Y761019D01*
X84424Y762286D01*
X83293Y764601D01*
X84240Y767353D01*
Y767850D01*
X85311Y773001D01*
X84911Y773608D01*
X85164Y774814D01*
X85772Y775211D01*
X86025Y776417D01*
X85625Y777024D01*
X85878Y778230D01*
X86486Y778627D01*
X86739Y779833D01*
X86339Y780440D01*
X86592Y781646D01*
X87200Y782043D01*
X87768Y784762D01*
X87786Y785634D01*
Y797873D01*
X86673Y798986D01*
Y807872D01*
G01X133410Y607269D02*
X108181D01*
X106536Y608914D01*
X103725D01*
G01Y603914D02*
X106536D01*
X108181Y605559D01*
X115150D01*
G01X157550Y606980D02*
X155380D01*
X155276Y607084D01*
X149604D01*
X148079Y605559D01*
X115150D01*
G01X157550Y614854D02*
X156384D01*
X156329Y614799D01*
X151850D01*
X151294Y614243D01*
X125276D01*
X112250Y627269D01*
X110520D01*
G01D02*
X108181D01*
X106536Y628914D01*
X103725D01*
G01X143110Y612533D02*
X124567D01*
X111541Y625559D01*
X108181D01*
X106536Y623914D01*
X103725D01*
G01X157550Y616823D02*
X155680D01*
X155518Y616985D01*
X143971D01*
X138932Y622024D01*
X130004D01*
X128276Y623752D01*
Y623751D01*
X116469Y635559D01*
X113270D01*
G01D02*
X108181D01*
X106536Y633914D01*
X103725D01*
G01X137230Y623734D02*
X130713D01*
X126566Y627881D01*
Y627880D01*
X117178Y637269D01*
X108181D01*
X106536Y638914D01*
X103725D01*
G01Y658914D02*
X106540D01*
X106870Y658584D01*
Y658580D01*
X108181Y657269D01*
X111120D01*
G01X157550Y624697D02*
X155293D01*
X155190Y624594D01*
X146846D01*
X114171Y657269D01*
X111120D01*
G01X103725Y653914D02*
X106536D01*
X108181Y655559D01*
X113462D01*
X146137Y622884D01*
X150360D01*
G01X157550Y608949D02*
X155320D01*
X155165Y608794D01*
X148895D01*
X147370Y607269D01*
X133410D01*
G01X157550Y618791D02*
X155556D01*
X155460Y618695D01*
X144680D01*
X139641Y623734D01*
X137230D01*
G01X157550Y612886D02*
X155823D01*
X155620Y613089D01*
X152559D01*
X152003Y612533D01*
X143110D01*
G01X163910Y539227D02*
X164584Y538553D01*
X166054D01*
X167027Y539526D01*
G01X163910Y536077D02*
Y536084D01*
X164669Y536843D01*
X166560D01*
X167027Y536376D01*
G01X157550Y622728D02*
X155350D01*
X155200Y622878D01*
Y622884D01*
X150360D01*
G01X176508Y529778D02*
X174720Y531356D01*
G01X176508Y526629D02*
X175741D01*
X174395Y527975D01*
G01X178099Y550267D02*
X176508Y548676D01*
G01Y551825D02*
Y551827D01*
X178083Y553402D01*
G01X225755Y529368D02*
X224491D01*
X221543Y532316D01*
X213455D01*
X211287Y530148D01*
Y528547D01*
G01X228905Y541967D02*
X227195Y543677D01*
X225098D01*
X220602Y548173D01*
X206111D01*
X205286Y548998D01*
Y551130D01*
G01X210709Y541953D02*
X206851D01*
X206396Y541498D01*
Y540313D01*
X206756Y539953D01*
X207309D01*
G01X225755Y535667D02*
X224991Y534903D01*
X224149D01*
X221103Y537949D01*
X216493D01*
X212489Y541953D01*
X210709D01*
G01X225755Y541967D02*
X224465D01*
X220856Y545576D01*
X220848D01*
X219961Y546463D01*
X214581D01*
X214163Y546045D01*
X212933D01*
X212547Y546431D01*
X211253D01*
X210867Y546045D01*
X209637D01*
X209219Y546463D01*
X207989D01*
X207571Y546045D01*
X206341D01*
X205923Y546463D01*
X205390D01*
X203579Y548274D01*
Y550549D01*
X202998Y551130D01*
X202486D01*
G01X228905Y535667D02*
X228609Y535830D01*
X226297Y537099D01*
X224372D01*
X221526Y539945D01*
X216916D01*
X213198Y543663D01*
X206142D01*
X204686Y542207D01*
Y540330D01*
X204309Y539953D01*
G01X228905Y529368D02*
X225947Y527811D01*
X223629D01*
X220834Y530606D01*
X215440D01*
X214118Y529284D01*
Y528583D01*
G01X634962Y200121D02*
X636607Y198476D01*
X638112D01*
X642990Y203354D01*
Y210056D01*
X642440Y210606D01*
Y211836D01*
X642990Y212386D01*
Y213616D01*
X642440Y214166D01*
Y215396D01*
X642990Y215946D01*
Y217176D01*
X642440Y217726D01*
Y218956D01*
X642990Y219506D01*
Y220631D01*
X641136Y222485D01*
X640034D01*
X639165Y223354D01*
Y224456D01*
X638296Y225325D01*
X637194D01*
X636325Y226194D01*
Y227296D01*
X635456Y228165D01*
X634354D01*
X633485Y229034D01*
Y230136D01*
X632616Y231005D01*
X631514D01*
X630645Y231874D01*
Y232976D01*
X629776Y233845D01*
X628674D01*
X627805Y234714D01*
Y235816D01*
X626936Y236685D01*
X625834D01*
X624965Y237554D01*
Y238656D01*
X624096Y239525D01*
X622994D01*
X622125Y240394D01*
Y241496D01*
X611336Y252285D01*
X595184D01*
X594226Y253243D01*
X591979D01*
X591418Y253378D01*
X588865D01*
G01X634962Y195121D02*
X636607Y196766D01*
X638821D01*
X644700Y202645D01*
Y221340D01*
X612045Y253995D01*
X595893D01*
X594935Y254953D01*
X588865D01*
G01Y259677D02*
X592059D01*
X592877Y260495D01*
X595294D01*
G01X588865Y258102D02*
X592903D01*
X593586Y258785D01*
X605890D01*
G01X610066Y261804D02*
X608757Y260495D01*
X595294D01*
G01X624800Y184953D02*
X626445Y183308D01*
X630588D01*
X631518Y184238D01*
Y185002D01*
X632388Y185872D01*
X633152D01*
X634022Y186742D01*
Y187506D01*
X634892Y188376D01*
X635656D01*
X636526Y189246D01*
Y190010D01*
X637396Y190880D01*
X638160D01*
X639030Y191750D01*
Y192514D01*
X639900Y193384D01*
X640664D01*
X649255Y201975D01*
Y223030D01*
X644398Y227887D01*
Y229958D01*
X637095Y237261D01*
X636103D01*
X635232Y238132D01*
Y239124D01*
X634361Y239995D01*
X633369D01*
X632498Y240866D01*
Y241858D01*
X631627Y242729D01*
X630635D01*
X629764Y243600D01*
Y244592D01*
X628893Y245463D01*
X627901D01*
X627030Y246334D01*
Y247326D01*
X626159Y248197D01*
X625167D01*
X624296Y249068D01*
Y250060D01*
X623425Y250931D01*
X622433D01*
X621562Y251802D01*
Y252794D01*
X620691Y253665D01*
X619699D01*
X618828Y254536D01*
Y255528D01*
X615660Y258696D01*
X614108D01*
X613216Y257804D01*
G01X624800Y179953D02*
X626445Y181598D01*
X631297D01*
X650965Y201266D01*
Y223739D01*
X646108Y228596D01*
Y230667D01*
X616369Y260406D01*
X614614D01*
X613216Y261804D01*
G01X610066Y257804D02*
X609085Y258785D01*
X605890D01*
G01X668320Y585031D02*
X659433D01*
X656325Y588139D01*
X653786D01*
X653628Y587981D01*
X651850D01*
G01Y589950D02*
X653560D01*
X653661Y589849D01*
X657034D01*
X660142Y586741D01*
X663843D01*
X664475Y587373D01*
X665705D01*
X666337Y586741D01*
X667567D01*
X668199Y587373D01*
X669429D01*
X670061Y586741D01*
X671291D01*
X671923Y587373D01*
X673153D01*
X673785Y586741D01*
X675015D01*
X675647Y587373D01*
X676877D01*
X677509Y586741D01*
X679564D01*
X685246Y592423D01*
G01X675130Y591687D02*
X659060D01*
X656740Y594007D01*
X653931D01*
X653811Y593887D01*
X651850D01*
G01Y595855D02*
X653830D01*
X653968Y595717D01*
X657449D01*
X659769Y593397D01*
X666470D01*
G01X657270Y603848D02*
X654009D01*
X653890Y603729D01*
X651850D01*
G01Y605698D02*
X653750D01*
X653890Y605558D01*
X657821D01*
X658439Y606177D01*
X659669D01*
X660287Y605558D01*
X661022D01*
X661842Y606378D01*
Y610152D01*
X663643Y611953D01*
X667571D01*
X669372Y610152D01*
Y609078D01*
X669850Y608600D01*
Y607370D01*
X669372Y606892D01*
Y604906D01*
X670172Y604106D01*
X673070D01*
X673870Y604906D01*
Y610745D01*
X675575Y612450D01*
X676665D01*
X677101Y612886D01*
X678331D01*
X678767Y612450D01*
X679997D01*
X680433Y612886D01*
X681663D01*
X682099Y612450D01*
X683679D01*
X684570Y613341D01*
Y615002D01*
G01X691990Y610622D02*
Y608664D01*
X689483Y606157D01*
X681285D01*
X680060Y604932D01*
Y598850D01*
X677303Y596093D01*
X670741D01*
X668863Y597971D01*
X653947D01*
X653800Y597824D01*
X651850D01*
G01X667930Y599681D02*
X663436D01*
X662842Y600276D01*
X661612D01*
X661018Y599681D01*
X659788D01*
X659194Y600276D01*
X657964D01*
X657370Y599681D01*
X653840D01*
X653729Y599792D01*
X651850D01*
G01X666470Y593397D02*
X679034D01*
X685767Y600130D01*
Y601128D01*
X686636Y601997D01*
X687634D01*
X688668Y603031D01*
X690745D01*
X694414Y606700D01*
Y607642D01*
X695284Y608512D01*
X696226D01*
X697096Y609382D01*
Y610324D01*
X697966Y611194D01*
X698908D01*
X699778Y612064D01*
Y613006D01*
X700648Y613876D01*
X701590D01*
X702460Y614746D01*
Y615688D01*
X703330Y616558D01*
X704272D01*
X705031Y617317D01*
Y621695D01*
X703386Y623340D01*
Y626150D01*
G01X657270Y603848D02*
X661731D01*
X663552Y605669D01*
Y609443D01*
X664352Y610243D01*
X666862D01*
X667662Y609443D01*
Y604197D01*
X669463Y602396D01*
X673779D01*
X675580Y604197D01*
Y610036D01*
X676284Y610740D01*
X684388D01*
X686280Y612632D01*
Y617604D01*
X684160Y619724D01*
X677160D01*
X676741Y620143D01*
Y621695D01*
X678386Y623340D01*
Y626150D01*
G01X667930Y599681D02*
X669572D01*
X671450Y597803D01*
X672803D01*
X673451Y598452D01*
X674681D01*
X675329Y597803D01*
X676594D01*
X678350Y599559D01*
Y600512D01*
X677680Y601182D01*
Y602412D01*
X678350Y603082D01*
Y605641D01*
X680576Y607867D01*
X681926D01*
X682478Y608419D01*
X683708D01*
X684260Y607867D01*
X685490D01*
X686042Y608419D01*
X687272D01*
X687824Y607867D01*
X688774D01*
X690280Y609373D01*
Y611516D01*
X689290Y612506D01*
Y617058D01*
X691343Y619111D01*
X694277D01*
X695030Y619864D01*
Y621581D01*
X695031Y621582D01*
Y621695D01*
X693386Y623340D01*
Y626150D01*
G01X668320Y585031D02*
X680273D01*
X690110Y594867D01*
X724188Y617807D01*
X725564Y619146D01*
X726741Y620322D01*
Y621695D01*
X728386Y623340D01*
Y626150D01*
G01X675130Y591687D02*
X679743D01*
X689377Y601321D01*
X691454D01*
X706741Y616608D01*
Y621695D01*
X708386Y623340D01*
Y626150D01*
G01X684570Y615002D02*
Y616895D01*
X683451Y618014D01*
X682675D01*
X682173Y617511D01*
X680943D01*
X680441Y618014D01*
X679211D01*
X678709Y617511D01*
X677479D01*
X676977Y618014D01*
X676451D01*
X675031Y619434D01*
Y621695D01*
X673386Y623340D01*
Y626150D01*
G01X678386Y668420D02*
X676741Y666775D01*
Y665841D01*
X678386Y664196D01*
Y661386D01*
G01X673386Y668420D02*
X675031Y666775D01*
Y665841D01*
X673386Y664196D01*
Y661386D01*
G01X685246Y592423D02*
X689017Y596194D01*
X716150Y614459D01*
X716298Y615216D01*
X717320Y615904D01*
X718076Y615755D01*
X719098Y616443D01*
X719246Y617200D01*
X720268Y617888D01*
X721024Y617739D01*
X723105Y619141D01*
X724363Y620365D01*
X725031Y621032D01*
Y621695D01*
X723386Y623340D01*
Y626150D01*
G01X691990Y610622D02*
Y612225D01*
X691000Y613215D01*
Y616349D01*
X692052Y617401D01*
X694986D01*
X696740Y619155D01*
Y620872D01*
X696741Y620873D01*
Y621695D01*
X698386Y623340D01*
Y626150D01*
G01Y667241D02*
X697390D01*
X696741Y666592D01*
Y665841D01*
X698386Y664196D01*
Y661386D01*
G01X693386Y667241D02*
X694188D01*
X695031Y666398D01*
Y665841D01*
X693386Y664196D01*
Y661386D01*
G01X713445Y677641D02*
X715090Y675996D01*
Y674893D01*
X715950Y673491D01*
X725031Y666706D01*
Y665841D01*
X723386Y664196D01*
Y661386D01*
G01X708386Y669774D02*
X706741Y668129D01*
Y665841D01*
X708386Y664196D01*
Y661386D01*
G01X703386Y669774D02*
X705031Y668129D01*
Y665841D01*
X703386Y664196D01*
Y661386D01*
G01X718445Y677641D02*
X716800Y675996D01*
Y675376D01*
X717236Y674665D01*
X726741Y667563D01*
Y665841D01*
X728386Y664196D01*
Y661386D01*
G01X716245Y765576D02*
X717890Y767221D01*
Y785438D01*
X717710Y785618D01*
Y797873D01*
X716597Y798986D01*
Y807872D01*
G01X721245Y765576D02*
X719600Y767221D01*
Y786147D01*
X719420Y786327D01*
Y797873D01*
X720534Y798987D01*
Y807872D01*
G01X726925Y778490D02*
X728570Y780135D01*
Y783893D01*
X729521Y784844D01*
Y797873D01*
X728408Y798986D01*
Y807872D01*
G01X731925Y778490D02*
X730280Y780135D01*
Y783184D01*
X731231Y784135D01*
Y797873D01*
X732345Y798987D01*
Y807872D01*
G54D140*
X405224Y558626D03*
G54D131*
X385118Y691156D03*
Y696156D03*
Y701156D03*
Y706156D03*
X405918Y691156D03*
Y706156D03*
Y701156D03*
Y696156D03*
X493954Y250584D03*
Y255584D03*
Y260584D03*
Y265584D03*
X522588Y250584D03*
Y265584D03*
Y260584D03*
Y255584D03*
X559199Y601204D03*
Y606204D03*
Y611204D03*
Y616204D03*
X579999Y611204D03*
Y606204D03*
Y601204D03*
Y616204D03*
X613640Y339818D03*
Y344818D03*
Y349818D03*
Y354818D03*
X620131Y645072D03*
Y650072D03*
Y655072D03*
Y660072D03*
X634440Y344818D03*
Y339818D03*
Y354818D03*
Y349818D03*
X640931Y660072D03*
Y655072D03*
Y650072D03*
Y645072D03*
G54D122*
X305097Y647144D03*
X303129D03*
X301160D03*
X299192D03*
X297223D03*
X295255D03*
X293286D03*
X291318D03*
Y708168D03*
X293286D03*
X295255D03*
X297223D03*
X299192D03*
X301160D03*
X303129D03*
X305097D03*
X320846Y647144D03*
X318877D03*
X316908D03*
X314940D03*
X312972D03*
X311003D03*
X309034D03*
X307066D03*
Y708168D03*
X309034D03*
X311003D03*
X312972D03*
X314940D03*
X316908D03*
X318877D03*
X320846D03*
X336594Y647144D03*
X334625D03*
X332657D03*
X330688D03*
X328720D03*
X326751D03*
X324783D03*
X322814D03*
Y708168D03*
X324783D03*
X326751D03*
X328720D03*
X330688D03*
X332657D03*
X334625D03*
X336594D03*
X338562Y647144D03*
Y708168D03*
X525692Y643144D03*
X523723D03*
X521755D03*
X519786D03*
X517818D03*
Y704168D03*
X519786D03*
X521755D03*
X523723D03*
X525692D03*
X541440Y643144D03*
X539472D03*
X537503D03*
X535534D03*
X533566D03*
X531597D03*
X529629D03*
X527660D03*
Y704168D03*
X529629D03*
X531597D03*
X533566D03*
X535534D03*
X537503D03*
X539472D03*
X541440D03*
X557188Y643144D03*
X555220D03*
X553251D03*
X551283D03*
X549314D03*
X547346D03*
X545377D03*
X543408D03*
Y704168D03*
X545377D03*
X547346D03*
X549314D03*
X551283D03*
X553251D03*
X555220D03*
X557188D03*
X565062Y643144D03*
X563094D03*
X561125D03*
X559157D03*
Y704168D03*
X561125D03*
X563094D03*
X565062D03*
G54D20*
X19987Y374226D03*
Y391942D03*
X32250Y374226D03*
Y391942D03*
G54D104*
X190500Y389487D03*
Y392046D03*
Y394605D03*
Y397164D03*
X204358Y392046D03*
Y389487D03*
Y397164D03*
Y394605D03*
G54D113*
X250545Y399984D03*
X322684Y393649D03*
G54D11*
G01X34341Y20757D02*
Y26345D01*
X34410Y26414D01*
G01X37599Y47299D02*
X41599D01*
G01X47292Y441446D02*
X56853D01*
X58140Y442733D01*
Y453263D01*
X56275Y455128D01*
X44040D01*
X35650Y463518D01*
Y467349D01*
X35656Y467355D01*
Y511781D01*
X46850Y522975D01*
Y528584D01*
X51674Y533408D01*
X64816D01*
X66533Y531691D01*
Y530417D01*
G01X72488Y441446D02*
X61680D01*
X60090Y443036D01*
Y453853D01*
X59940Y454003D01*
Y454018D01*
X57030Y456928D01*
X44786D01*
X37456Y464258D01*
Y511035D01*
X44493Y518072D01*
X48175D01*
G01X41599Y47299D02*
Y52760D01*
X44009Y55170D01*
X44010D01*
G01X51325Y518072D02*
Y519048D01*
X49857Y520516D01*
G01X50906Y513859D02*
X52943D01*
X53769Y513033D01*
G01X57135Y513867D02*
X54603D01*
X53769Y513033D01*
G01X51337Y522910D02*
X51325Y522898D01*
Y521984D01*
X49857Y520516D01*
G01X55351Y526057D02*
X55348Y526060D01*
X51337D01*
G01X57135Y515836D02*
X55428D01*
X54445Y516819D01*
Y518140D01*
X54988Y518683D01*
G01X69339Y513867D02*
X71638D01*
X73057Y515286D01*
G01X63383Y530417D02*
Y526417D01*
G01X62253Y522589D02*
Y518985D01*
G01X63383Y526417D02*
X62253Y525287D01*
Y522589D01*
G01X55351Y526057D02*
X59295D01*
X59299Y526053D01*
G01D02*
Y522114D01*
X60284Y521129D01*
Y518985D01*
G01X55351Y522907D02*
Y519046D01*
X54988Y518683D01*
G01X64221Y518985D02*
Y521406D01*
X65808Y522993D01*
X67369D01*
G01X66533Y526417D02*
X67353Y527237D01*
X70696D01*
G01X66190Y518985D02*
Y520195D01*
X66903Y520908D01*
X69284D01*
X70696Y522320D01*
Y527237D01*
G01X76085Y513104D02*
Y512780D01*
X79695Y509170D01*
X80368D01*
G01D02*
X84094D01*
X84103Y509161D01*
G01D02*
Y511052D01*
X85346Y512295D01*
G01X76085Y517104D02*
X74875D01*
X73057Y515286D01*
G01X134151Y47370D02*
X134150D01*
X132050Y49470D01*
Y57559D01*
X141976Y67485D01*
X165769D01*
X172674Y74390D01*
X197571D01*
X211619Y60342D01*
X221215D01*
G01X133539Y76588D02*
X131068D01*
G01X118730Y519031D02*
Y513931D01*
X118830Y513831D01*
G01D02*
Y511517D01*
X118124Y510811D01*
G01X127399Y522895D02*
X125075D01*
X124279Y523691D01*
G01X121880Y519031D02*
X121847Y519064D01*
Y523033D01*
G01D02*
X121872Y523008D01*
X123592D01*
X124277Y523693D01*
X124279Y523691D01*
G01X118730Y519031D02*
X118697Y519064D01*
Y523033D01*
G01X132438Y704733D02*
X130470Y706701D01*
Y717383D01*
G01X132438Y704733D02*
Y699863D01*
G01Y722106D02*
Y717383D01*
G01X129184Y725250D02*
Y721924D01*
X130470Y720638D01*
Y717383D01*
G01X124628Y726984D02*
X124620Y726976D01*
Y722549D01*
X126220Y720949D01*
G01X128501Y717383D02*
X127146D01*
X126220Y718309D01*
Y720949D01*
G01X144203Y15162D02*
X146553D01*
X148450Y17059D01*
Y25731D01*
X150085Y27366D01*
X150592D01*
G01X137301Y47370D02*
X137494Y47177D01*
X138275D01*
X140554Y44898D01*
G01X139932Y35310D02*
X137009D01*
G01X141380Y36758D02*
X139932Y35310D01*
G01X137009D02*
X135362D01*
X134086Y36586D01*
Y39191D01*
G01X135050Y53493D02*
X135104D01*
X137301Y51296D01*
Y47370D01*
G01X137540Y58255D02*
Y56214D01*
X139274Y54480D01*
X141160D01*
G01D02*
Y50045D01*
X142102Y49103D01*
X145750D01*
G01X145210Y54510D02*
Y53296D01*
X143857Y51943D01*
G01X146280Y51294D02*
X144506D01*
X143857Y51943D01*
G01X223314Y54961D02*
X219837Y58438D01*
X210830D01*
X196678Y72590D01*
X174311D01*
X167295Y65574D01*
X142611D01*
X141160Y64123D01*
Y57630D01*
G01X136689Y76588D02*
X140527D01*
G01D02*
Y77665D01*
X146205Y83343D01*
X151618D01*
G01X141682Y269829D02*
X157452D01*
X159058Y268223D01*
X164375D01*
G01X136375Y721064D02*
Y717383D01*
G01X134406D02*
Y714083D01*
X135861Y712628D01*
X138198D01*
G01D02*
X144181D01*
G01X150592Y27366D02*
Y27837D01*
X150045Y28384D01*
Y30176D01*
G01X158165Y27522D02*
Y30386D01*
X157877Y30674D01*
G01X154592Y27366D02*
X152810Y29148D01*
Y29921D01*
G01Y30538D02*
Y29921D01*
G01X155567Y32235D02*
X156316D01*
X157877Y30674D01*
G01X149157Y54430D02*
Y51852D01*
X149025Y51720D01*
G01X157010Y58963D02*
X156289Y58242D01*
Y55906D01*
G01D02*
Y52136D01*
X155256Y51103D01*
G01X160111Y59871D02*
X157918D01*
X157010Y58963D01*
G01X158859Y82480D02*
Y87571D01*
X157972Y88458D01*
X157973Y88460D01*
X156729D01*
X155849Y87580D01*
Y87574D01*
X151618Y83343D01*
G01X162484Y276599D02*
X164247Y274836D01*
Y274751D01*
X164375Y274623D01*
G01X161767Y287242D02*
X163058Y285951D01*
X164375D01*
G01X162181Y303075D02*
X162839Y303733D01*
X164321D01*
X164375Y303679D01*
G01X161687Y310355D02*
Y310646D01*
X162254Y310079D01*
X164375D01*
G01X161513Y317143D02*
X165130D01*
X166330Y315943D01*
X168095D01*
G01X159285Y336220D02*
X162034Y333471D01*
X164375D01*
G01D02*
X166189Y335285D01*
G01X160699Y592020D02*
Y587904D01*
G01X157550Y601075D02*
X154470D01*
X153330Y599935D01*
G01X157550Y610917D02*
X153712D01*
G01X157550Y597138D02*
X153527D01*
G01X157550Y603043D02*
X153422D01*
G01X162668Y627846D02*
Y631897D01*
G01X157550Y620760D02*
X153955D01*
G01X177312Y275869D02*
X176536D01*
X175318Y277087D01*
G01D02*
Y278687D01*
G01X173177Y275511D02*
X174753Y277087D01*
X175318D01*
G01X170272Y277611D02*
Y275760D01*
X170510Y275522D01*
G01X172982Y296004D02*
X175243D01*
X175812Y296573D01*
G01X177470Y294933D02*
X175830Y296573D01*
G01X173177Y293239D02*
X174467D01*
X175162Y293934D01*
G01X170272Y295339D02*
X170150Y295217D01*
X166314D01*
X166122Y295025D01*
G01X168338Y285044D02*
X165561D01*
X164654Y285951D01*
X164375D01*
G01X180254Y310663D02*
X181804Y312213D01*
X181812D01*
G01X168338Y302772D02*
X168336D01*
X167647Y303461D01*
X165890D01*
X165672Y303679D01*
X164375D01*
G01X173177Y310967D02*
X168440D01*
X168321Y311086D01*
G01D02*
X168152Y310917D01*
X166648D01*
X165810Y310079D01*
X164375D01*
G01X170272Y313067D02*
Y313692D01*
X168095Y315869D01*
Y315943D01*
G01X175812Y327853D02*
Y327259D01*
X178812Y324259D01*
G01D02*
X177342Y322789D01*
X177312D01*
G01X175330Y318552D02*
X173343Y320539D01*
X172914D01*
G01X179554Y342047D02*
X179486Y341979D01*
X176768D01*
G01X182335Y339474D02*
X179762Y342047D01*
X179554D01*
G01X169684Y340535D02*
Y339854D01*
X168121Y338291D01*
Y338228D01*
G01X171545Y343866D02*
X174757D01*
G01D02*
Y346866D01*
G01X177029Y347811D02*
X177433Y347407D01*
Y344689D01*
G01X166189Y335285D02*
X166901Y335997D01*
Y337008D01*
X168121Y338228D01*
G01X177604Y355155D02*
X179079D01*
X180422Y353812D01*
Y350586D01*
G01X171993Y417621D02*
X170218D01*
X168499Y419340D01*
X168455D01*
X167527Y420268D01*
G01X167597Y432521D02*
Y431083D01*
X165130Y428616D01*
Y422665D01*
X167527Y420268D01*
G01X179544Y421477D02*
Y423983D01*
X179562Y424001D01*
G01X171993Y420771D02*
Y422617D01*
X173381Y424005D01*
G01X171993Y420771D02*
X175993D01*
G01D02*
Y423979D01*
X177593Y425579D01*
Y427177D01*
G01X179544Y418327D02*
X182132D01*
G01X173151Y427552D02*
Y429350D01*
X173832Y430031D01*
X174739D01*
G01Y433968D02*
X171888D01*
X171082Y433162D01*
X168238D01*
X167597Y432521D01*
G01X174739Y435937D02*
X173305D01*
X172408Y436834D01*
X170683D01*
G01D02*
X167395D01*
G01D02*
Y437797D01*
X164774Y440418D01*
Y441077D01*
G01X179562Y427177D02*
Y424001D01*
G01X174739Y432000D02*
X172748D01*
X170361Y429613D01*
Y428595D01*
G01X167861Y427296D02*
X169062D01*
X170361Y428595D01*
G01X167924Y441077D02*
X176667D01*
X177593Y440151D01*
Y438791D01*
G01X164774Y441077D02*
Y445034D01*
G01X167924D02*
Y446282D01*
X166300Y447906D01*
Y455915D01*
X171310Y460925D01*
X191230D01*
X193942Y458213D01*
X199280D01*
X209918Y447575D01*
X233312D01*
X234852Y446035D01*
Y440011D01*
G01X167924Y441077D02*
Y445034D01*
G01X166605Y592020D02*
Y587860D01*
G01X178416Y592020D02*
Y587849D01*
G01X168573Y627846D02*
Y630442D01*
X167530Y631485D01*
Y631935D01*
G01X174479Y627846D02*
Y631986D01*
G01X193677Y243855D02*
Y245883D01*
X193300Y246260D01*
G01X184318Y247612D02*
Y247287D01*
X183318Y246287D01*
X181263D01*
X181236Y246260D01*
G01X194056Y256697D02*
X195311Y255442D01*
Y254867D01*
G01X184829Y259139D02*
X183279Y260689D01*
Y260697D01*
G01X189312Y273113D02*
X186312D01*
G01X186118Y270787D02*
X187812Y269093D01*
Y268049D01*
G01X184812D02*
X187812D01*
G01X195254Y310663D02*
X196804Y312213D01*
X196812D01*
G01X193313Y325492D02*
X194656Y324149D01*
X195219D01*
G01X181812Y314969D02*
Y314999D01*
X180342Y316469D01*
G01X190475Y341979D02*
X191662Y340792D01*
X192293D01*
G01X187710Y341784D02*
X187905Y341979D01*
X190475D01*
G01X197282Y342047D02*
X197214Y341979D01*
X194497D01*
G01X187404Y343998D02*
X187710Y343692D01*
Y341784D01*
G01X189810Y344689D02*
X189780D01*
X187829Y346640D01*
G01X192293Y340792D02*
X193250Y341749D01*
X194267D01*
X194497Y341979D01*
G01X192519Y352761D02*
Y350917D01*
X192486Y350884D01*
Y350586D01*
G01X186908Y352760D02*
X186822Y352674D01*
Y350586D01*
G01X185117Y414885D02*
X185111Y414891D01*
Y418925D01*
G01X182132Y418327D02*
X182730Y418925D01*
X185111D01*
G01X184920Y508626D02*
X184025Y507731D01*
X182807D01*
G01X180384Y592020D02*
Y588481D01*
X181330Y587535D01*
G01X193376Y605012D02*
X196907D01*
G01X193376Y599106D02*
X196459D01*
X197030Y598535D01*
G01X193376Y597138D02*
X195427D01*
X197230Y595335D01*
G01X182353Y627846D02*
Y631612D01*
G01X193376Y614854D02*
X196649D01*
X197230Y615435D01*
G01X193376Y624697D02*
X195692D01*
X197130Y626135D01*
G01X208129Y257519D02*
X209017Y256631D01*
Y254867D01*
G01X210333Y265197D02*
X211803Y266667D01*
Y266697D01*
G01X208289Y263639D02*
X206847Y262197D01*
X206739D01*
G01X208289Y263639D02*
X206739Y265189D01*
Y265197D01*
G01X201667Y274542D02*
X199822Y272697D01*
X198919D01*
G01X203983Y271197D02*
X206739D01*
G01X208226Y269697D02*
X206739Y271184D01*
Y271197D01*
G01X203983Y268197D02*
X206739D01*
G01X208226Y269697D02*
X206739Y268210D01*
Y268197D01*
G01X209449Y281098D02*
X211024Y279523D01*
G01D02*
X211041D01*
X211947Y278617D01*
X213268D01*
X214174Y279523D01*
G01X211024Y292123D02*
X209449Y290548D01*
G01D02*
X207874Y292123D01*
G01X204724Y285823D02*
X206299Y287398D01*
G01D02*
X207874Y285823D01*
G01X211024D02*
X209449Y287398D01*
G01X204724Y292123D02*
X204441D01*
X203947Y292617D01*
X202176D01*
X201068Y291509D01*
G01X199812Y283689D02*
Y284397D01*
X201412Y285997D01*
G01D02*
X202813Y287398D01*
X203149D01*
G01X201068Y291509D02*
X198312D01*
G01D02*
X196867Y292954D01*
Y294342D01*
G01X207874Y304723D02*
X206299Y306298D01*
G01X203039Y322649D02*
X202069Y321679D01*
X200444D01*
X200211Y321446D01*
G01X203039Y325649D02*
X201578Y324188D01*
X200840D01*
X200572Y323920D01*
G01X208485Y332356D02*
X209760D01*
X210710Y333306D01*
X210859Y333157D01*
Y333149D01*
G01X197243Y346623D02*
Y344518D01*
G01D02*
Y342625D01*
X197282Y342586D01*
Y342047D01*
G01X206817Y358874D02*
X210214Y355477D01*
Y350586D01*
G01X207274Y353124D02*
X207224D01*
Y348839D01*
G01X198987Y353137D02*
X198150Y352300D01*
Y350586D01*
G01X204550D02*
X205557Y349579D01*
Y346640D01*
G01X206657Y356116D02*
X204550Y354009D01*
Y350586D01*
G01X204358Y389487D02*
X208093D01*
X208977Y388603D01*
X211660D01*
G01X204358Y392046D02*
X206244D01*
X207615Y391753D01*
X211660D01*
G01X204358Y397164D02*
X207677D01*
X209202Y398689D01*
X211700D01*
G01X204358Y394605D02*
X208366D01*
X209300Y395539D01*
X211700D01*
G01X221215Y60342D02*
X223314Y62441D01*
G01X227443Y257697D02*
Y257727D01*
X225973Y259197D01*
G01X218899Y281098D02*
X220474Y279523D01*
G01X214174D02*
Y279390D01*
X214947Y278617D01*
X216418D01*
X217324Y279523D01*
G01X214174Y292123D02*
X215749Y290548D01*
G01D02*
X217324Y292123D01*
G01X220474D02*
X223624Y295273D01*
G01X220474Y298423D02*
X222049Y299998D01*
G01D02*
X223624Y301573D01*
G01X218899Y306298D02*
X220474Y304723D01*
G01X223624Y307873D02*
X222049Y306298D01*
G01X217324Y311023D02*
X217353D01*
X218947Y312617D01*
G01X225037Y328707D02*
X224949D01*
G01X226499Y330149D02*
X226479D01*
X225037Y328707D01*
G01X224711Y325922D02*
X225272D01*
X226499Y327149D01*
G01D02*
Y327265D01*
X225057Y328707D01*
X225037D01*
G01X226484Y324149D02*
X224711Y325922D01*
G01X218679Y334649D02*
Y334657D01*
X217129Y336207D01*
G01D02*
X218571Y337649D01*
X218679D01*
G01X215010Y342047D02*
Y341599D01*
X217067Y339542D01*
G01X212225Y341979D02*
X214942D01*
X215010Y342047D01*
G01X217067Y339542D02*
X220060Y342535D01*
X220496D01*
G01X217129Y333207D02*
X218679Y331657D01*
Y331649D01*
G01X223010Y344242D02*
X223457Y344689D01*
X225266D01*
G01X225931Y341979D02*
X225266Y342644D01*
Y344689D01*
G01X222278Y350586D02*
Y350486D01*
X223398Y349367D01*
X223925Y348839D01*
X224952D01*
G01X222777Y353066D02*
X222278Y352567D01*
Y350586D01*
G01X214888Y352909D02*
X215878Y351919D01*
Y350586D01*
G01X214786Y388603D02*
X211660D01*
G01X218090Y390891D02*
X217228Y391753D01*
X211660D01*
G01X215120Y399654D02*
Y399649D01*
X214160Y398689D01*
X211700D01*
G01Y395539D02*
X214406D01*
G01X241727Y250223D02*
X240918Y251032D01*
Y252346D01*
X238958Y254306D01*
Y254311D01*
G01X239569Y257639D02*
X240791Y256417D01*
X242247D01*
X243797Y254867D01*
X244473D01*
G01X231749Y265139D02*
X230199Y266689D01*
Y266697D01*
G01Y260697D02*
X230307D01*
X231749Y262139D01*
G01X230199Y257697D02*
X230307D01*
X231749Y259139D01*
G01X227443Y266697D02*
X230199D01*
G01X236224Y288973D02*
X237799Y287398D01*
G01D02*
X236224Y285823D01*
G01X242524D02*
X240949Y287398D01*
G01D02*
X239374Y285823D01*
G01X233074Y298423D02*
X231499Y296848D01*
G01D02*
X229924Y295273D01*
G01X233074Y292123D02*
X231499Y293698D01*
G01X229924Y295273D02*
X231499Y293698D01*
G01X239374Y298423D02*
X239424D01*
X240949Y296898D01*
Y296848D01*
G01X237800Y299998D02*
X239374Y301572D01*
Y301573D01*
G01X231499Y299998D02*
X233074Y298423D01*
G01X242524Y304723D02*
X242582D01*
X244118Y303187D01*
G01X239374Y304723D02*
X237799Y303148D01*
G01X236224Y301573D02*
X234649Y303148D01*
G01X236224Y307873D02*
X237799Y306298D01*
G01X242524Y301573D02*
X240949Y303148D01*
G01X235468Y342535D02*
Y342349D01*
X233055Y339936D01*
G01D02*
X232457D01*
X230414Y341979D01*
X229953D01*
G01X233697Y353961D02*
Y352465D01*
X233464Y352232D01*
Y351045D01*
X233606Y350903D01*
Y350586D01*
G01X238084Y355992D02*
Y352610D01*
X240057Y350637D01*
X240006Y350586D01*
G01X228057Y352837D02*
X227942Y352722D01*
Y350586D01*
G01X234927Y439936D02*
X234852Y440011D01*
G01X255209Y260639D02*
X253659Y262189D01*
Y262197D01*
G01X255359Y266557D02*
X253999Y265197D01*
X253659D01*
G01Y259197D02*
X253691Y259165D01*
G01D02*
Y256854D01*
X256234Y254311D01*
X256686D01*
G01X250903Y268197D02*
Y271197D01*
G01X255205Y272755D02*
X253659Y271209D01*
Y271197D01*
G01D02*
Y268197D01*
G01X255359Y266557D02*
X253719Y268197D01*
X253659D01*
G01X250903Y271197D02*
Y274197D01*
G01D02*
X253659D01*
G01X255205Y272755D02*
X253763Y274197D01*
X253659D01*
G01X251974Y279523D02*
X252135D01*
X254234Y281622D01*
G01X250399Y281098D02*
X248824Y279523D01*
G01X251974Y276767D02*
X254730D01*
G01D02*
Y279423D01*
X254830Y279523D01*
G01D02*
X254920Y279613D01*
Y280936D01*
X254234Y281622D01*
G01X248824Y279523D02*
X251580Y276767D01*
X251974D01*
G01X259886Y284633D02*
Y284678D01*
X257447Y287117D01*
G01X251974Y285823D02*
X250399Y287398D01*
G01X256886Y284633D02*
Y286556D01*
X257447Y287117D01*
G01X248824Y285823D02*
X250399Y287398D01*
G01X245674Y285823D02*
X248824D01*
G01X255630Y308093D02*
X255887D01*
X257057Y309263D01*
Y309636D01*
G01X251974Y317323D02*
X251544Y317753D01*
X249254D01*
X248824Y317323D01*
G01X245691Y341215D02*
X244927Y341979D01*
X243659D01*
G01X245691Y341215D02*
X247699Y339207D01*
X248509D01*
G01X247218Y333049D02*
X248559D01*
X249959Y331649D01*
G01X252715D02*
X249959D01*
G01X252715D02*
X253501Y332435D01*
X254819D01*
G01X255009Y338318D02*
Y338413D01*
X255745Y339149D01*
X257779D01*
G01X247681Y341979D02*
X247749Y342047D01*
X250466D01*
G01X253196Y342535D02*
Y344915D01*
X252834Y345277D01*
G01X250466Y342047D02*
X252708D01*
X253196Y342535D01*
G01X247681Y341979D02*
X246455D01*
X245691Y341215D01*
G01X254819Y332435D02*
X255493D01*
X257779Y330149D01*
G01X248509Y339207D02*
X249959Y337757D01*
Y337649D01*
G01X246265Y355855D02*
X245670Y355260D01*
Y350586D01*
G01X251334D02*
Y352857D01*
G01X252710Y348183D02*
X251334Y349559D01*
Y350586D01*
G01X252834Y345277D02*
X252710Y345401D01*
Y348183D01*
G01X262955Y12663D02*
X260558Y15060D01*
Y20275D01*
X263260Y22977D01*
Y24932D01*
G01X267421Y10016D02*
X265646D01*
X263927Y11735D01*
X263883D01*
X262955Y12663D01*
G01X268809Y16400D02*
X267421Y15012D01*
Y13166D01*
G01D02*
X271421D01*
G01D02*
Y16374D01*
X273021Y17974D01*
Y19572D01*
G01X268579Y19365D02*
Y21745D01*
X269260Y22426D01*
X270167D01*
G01X266111Y29229D02*
X262823D01*
G01X270167Y28332D02*
X268733D01*
X267836Y29229D01*
X266111D01*
G01X262823D02*
Y30192D01*
X260202Y32813D01*
Y33472D01*
G01X263260Y24932D02*
X263609Y25281D01*
X266234D01*
X267316Y26363D01*
X270167D01*
G01X263289Y19691D02*
X264490D01*
X265789Y20990D01*
G01X270167Y24395D02*
X268176D01*
X265789Y22008D01*
Y20990D01*
G01X329855Y32331D02*
Y43787D01*
X315324Y58318D01*
X270941D01*
X263352Y50729D01*
Y37429D01*
G01Y33472D02*
Y37429D01*
G01Y33472D02*
X272095D01*
X273021Y32546D01*
Y31186D01*
G01X260202Y37429D02*
Y33472D01*
G01X266339Y114763D02*
Y119542D01*
X264980Y120901D01*
Y121886D01*
G01D02*
X268772D01*
X269010Y121648D01*
G01X269620Y243240D02*
X269876Y243496D01*
Y246260D01*
G01X264212D02*
X264085D01*
X262128Y248217D01*
X261372D01*
G01D02*
X261580Y248425D01*
Y251987D01*
G01X269299Y265197D02*
Y268580D01*
X268886Y268993D01*
G01X269299Y259197D02*
Y262197D01*
G01X266543D02*
Y265197D01*
G01X263029Y259139D02*
X261587Y257697D01*
X261479D01*
G01X267020Y257079D02*
X266223Y256282D01*
Y254867D01*
G01D02*
X264336Y252980D01*
X264212D01*
G01X261580Y251987D02*
X263219D01*
X264212Y252980D01*
G01X271886Y281877D02*
X271916D01*
X273386Y280407D01*
G01X268944Y278363D02*
X267394Y276813D01*
X267386D01*
G01X267883Y325837D02*
X267386Y325340D01*
Y323733D01*
G01X270386Y320977D02*
Y323733D01*
G01D02*
X267386D01*
G01X268502Y344181D02*
X268194Y343873D01*
Y342047D01*
G01X270326Y335795D02*
X269995D01*
X268849Y334649D01*
X268355D01*
G01X265599D02*
X268355D01*
G01X269117Y352876D02*
Y350641D01*
X269062Y350586D01*
G01X268155Y346623D02*
X268718Y347186D01*
Y350242D01*
X269062Y350586D01*
G01X259444Y354291D02*
X260094Y353641D01*
Y349153D01*
X260408Y348839D01*
G01X263550Y564014D02*
X261175Y566389D01*
Y569054D01*
G01X263550Y560864D02*
X265019Y562333D01*
G01Y566025D02*
Y572976D01*
X263792Y574203D01*
G01X278354Y244281D02*
X278283D01*
X276304Y246260D01*
X276276D01*
G01X279930Y254867D02*
X280651Y255588D01*
X281954D01*
G01X280886Y313157D02*
X282325D01*
X283716Y314548D01*
G01X288377Y321216D02*
X291316D01*
X292323Y322223D01*
G01X288360Y329530D02*
X288845D01*
X289429Y328946D01*
X290343D01*
X290666Y328623D01*
X292323D01*
G01X277886Y331553D02*
Y331723D01*
X279718Y333555D01*
Y333694D01*
G01X275462Y350586D02*
X277194D01*
G01D02*
X277216Y350608D01*
G01X284428Y661908D02*
X289171D01*
G01X284428Y663876D02*
X279785D01*
G01X284428Y689467D02*
X288880D01*
G01X276201Y691038D02*
X276414Y691251D01*
X280200D01*
X280380Y691431D01*
X284428D01*
Y691436D01*
G01X295110Y262961D02*
X294696Y263375D01*
X292323D01*
G01X295910Y266706D02*
Y267254D01*
X294125Y269039D01*
X292323D01*
G01X297668Y300709D02*
X296699Y301678D01*
X291455D01*
X291312Y301821D01*
X290576D01*
G01X294888Y304456D02*
X292362D01*
X292323Y304495D01*
G01X295200Y321473D02*
X294450Y322223D01*
X292323D01*
G01X294596Y328129D02*
X294102Y328623D01*
X292323D01*
G01X294888Y335326D02*
X294783D01*
X293744Y334287D01*
X292323D01*
G01X305186Y623877D02*
X308735D01*
X308741Y623871D01*
G01X315957Y594127D02*
Y595546D01*
X315215Y596288D01*
Y597255D01*
G01X317722Y614646D02*
Y612848D01*
X317041Y612167D01*
X316134D01*
G01X322949Y601121D02*
X321921D01*
X321297Y600497D01*
X314830D01*
X313280Y602047D01*
Y603407D01*
G01X316134Y608230D02*
X319967D01*
X320101Y608364D01*
X322457D01*
X323573Y609480D01*
G01X319135Y597262D02*
X319032Y597255D01*
X315215D01*
G01X320094Y604114D02*
X321344Y605364D01*
X323478D01*
G01X316134Y606261D02*
X317568D01*
X319715Y604114D01*
X320094D01*
G01X316134Y610198D02*
X318125D01*
X320512Y612585D01*
Y613603D01*
G01X318880Y624577D02*
X320655D01*
X322374Y622858D01*
X322418D01*
X323346Y621930D01*
G01X308741Y623871D02*
X311329D01*
G01X311311Y615021D02*
Y618197D01*
G01X311329Y620721D02*
Y618215D01*
X311311Y618197D01*
G01X323036Y614013D02*
X320922D01*
X320512Y613603D01*
G01X318880Y621427D02*
X314910D01*
G01X318880D02*
Y619581D01*
X317492Y618193D01*
G01X314910Y621427D02*
X314880D01*
Y618219D01*
X313280Y616619D01*
Y615021D01*
G01X314940Y642067D02*
Y647144D01*
G01X307066D02*
Y640271D01*
X307574Y639763D01*
G01X314790Y652049D02*
X314339Y652500D01*
X310280D01*
X309034Y651254D01*
Y647144D01*
G01X318877D02*
Y652628D01*
X317877Y653628D01*
X317130D01*
G01X318877Y708168D02*
Y704326D01*
X320110Y703093D01*
G01D02*
X320846Y703829D01*
Y708168D01*
G01X322940Y713800D02*
X321820Y712680D01*
G01X322814Y708168D02*
Y711686D01*
X321820Y712680D01*
G01X315477Y712926D02*
Y711772D01*
X314940Y711235D01*
Y708168D01*
G01X332088Y537928D02*
Y534093D01*
X331398Y533403D01*
X329348D01*
G01X328448Y536761D02*
Y534303D01*
X329348Y533403D01*
G01X323931Y589733D02*
Y594002D01*
X322949Y594984D01*
Y597198D01*
G01Y601121D02*
Y597198D01*
G01X323573Y609480D02*
Y610235D01*
X325743Y612405D01*
Y619533D01*
X323346Y621930D01*
G01X326099Y597198D02*
Y601121D01*
G01X323478Y605364D02*
Y604401D01*
X326099Y601780D01*
Y601121D01*
G01X415542Y597300D02*
Y585957D01*
X409100Y579515D01*
X358881D01*
X350238Y588158D01*
Y597874D01*
G01D02*
X348900Y599212D01*
G01X339930Y661219D02*
X340006D01*
X341286Y659939D01*
X345452D01*
G01Y661908D02*
Y661900D01*
X348409D01*
X348990Y661319D01*
X353766D01*
X355955Y659130D01*
G01X340525Y686600D02*
X341424Y687499D01*
X345452D01*
G01X355935Y690624D02*
X355127D01*
X353260Y688757D01*
G01X345452Y689467D02*
X349198D01*
X349610Y689055D01*
X352962D01*
X353260Y688757D01*
G01X380786Y517947D02*
Y519308D01*
G01X379286Y524166D02*
Y520808D01*
X380786Y519308D01*
G01X375349Y539433D02*
Y536372D01*
G01Y539433D02*
X376490Y540574D01*
G01X402458Y505903D02*
X401407D01*
X397520Y502016D01*
Y487018D01*
X405504Y479034D01*
X408478D01*
X411286Y476226D01*
X412448D01*
G01Y471896D02*
X410951D01*
X406937Y475910D01*
X404294D01*
X394503Y485701D01*
Y504275D01*
X399165Y508937D01*
X401556D01*
G01X427474Y566125D02*
Y568147D01*
X424387Y571234D01*
X405337D01*
X396590Y562487D01*
Y549310D01*
G01X424324Y566125D02*
Y566541D01*
X423033Y567832D01*
X406276D01*
X399590Y561146D01*
Y553502D01*
G01X401728Y277251D02*
X407572Y283095D01*
X412330D01*
G01X405878Y294071D02*
X406713Y294906D01*
X412330D01*
G01X412699Y466933D02*
X417381D01*
X421400Y462914D01*
X428347D01*
X428747Y463314D01*
G01X408369Y466933D02*
Y469388D01*
X406352Y471405D01*
G01X410315Y614782D02*
Y612984D01*
X409634Y612303D01*
X408727D01*
G01Y606397D02*
X410161D01*
X411058Y605500D01*
X412783D01*
G01D02*
X416071D01*
G01D02*
Y604537D01*
X418692Y601916D01*
Y601257D01*
G01X416454Y621319D02*
X417806Y619967D01*
Y613920D01*
X416071Y612185D01*
Y609542D01*
G01D02*
X412754D01*
X411578Y608366D01*
X408727D01*
G01Y610334D02*
X410718D01*
X413105Y612721D01*
Y613739D01*
G01X415542Y601257D02*
Y597300D01*
G01Y601257D02*
X406799D01*
X405873Y602183D01*
Y603543D01*
G01X411473Y624713D02*
X413060D01*
X416454Y621319D01*
G01X415605Y615038D02*
X414404D01*
X413105Y613739D01*
G01X411473Y621563D02*
X407473D01*
G01D02*
Y618355D01*
X405873Y616755D01*
Y615157D01*
G01X410085Y618329D02*
X411473Y619717D01*
Y621563D01*
G01X428747Y463314D02*
Y458694D01*
G01Y474305D02*
Y468770D01*
G01X423909Y548913D02*
X423845Y548977D01*
Y550973D01*
G01X428039Y548119D02*
Y550949D01*
G01Y547153D02*
Y548119D01*
G01X436290Y553337D02*
X435531D01*
X434371Y552177D01*
Y549287D01*
X431932Y546848D01*
Y544273D01*
X430982Y543323D01*
G01X421461Y546847D02*
Y547703D01*
G01X419161Y550342D02*
Y550003D01*
X421461Y547703D01*
G01X430446Y547403D02*
Y548937D01*
X432351Y550842D01*
Y550933D01*
G01X420883Y556729D02*
X419190Y558422D01*
Y559017D01*
G01X423845Y550973D02*
X422544D01*
X421556Y551961D01*
Y556056D01*
X420883Y556729D01*
G01X423829Y559032D02*
X419205D01*
X419190Y559017D01*
G01X428060Y559112D02*
X427090D01*
X425928Y557950D01*
Y552443D01*
X427422Y550949D01*
X428039D01*
G01X419172Y554393D02*
Y550353D01*
X419161Y550342D01*
G01X432152Y559098D02*
Y557615D01*
X431145Y556608D01*
G01X432351Y550933D02*
X431255D01*
X430133Y552055D01*
Y555596D01*
X431145Y556608D01*
G01X423829Y562182D02*
Y565630D01*
X424324Y566125D01*
G01X418692Y601257D02*
Y597300D01*
G01X450326Y93919D02*
Y95315D01*
X447715Y97926D01*
G01X445663Y101680D02*
Y99978D01*
X447715Y97926D01*
G01X434882Y259473D02*
X441792D01*
G01X439566Y438705D02*
X449877D01*
X453070Y441898D01*
Y457733D01*
X457492Y462155D01*
X466484D01*
X475600Y471271D01*
Y541870D01*
X467007Y550463D01*
X461588D01*
G01X452895Y513410D02*
Y515276D01*
X450010Y518161D01*
X447758D01*
G01X443768D02*
X446415Y515514D01*
X449402D01*
G01X443845Y512785D02*
X443843Y512787D01*
X439749D01*
G01X439762Y515540D02*
Y518106D01*
G01X439749Y512787D02*
Y514064D01*
X439762Y514077D01*
Y515540D01*
G01X445729Y531046D02*
X448378D01*
X449691Y532359D01*
G01X445729Y531046D02*
X445649Y531126D01*
X441651D01*
G01D02*
X438706D01*
X438422Y530842D01*
G01X450540Y521331D02*
X447778D01*
X447758Y521311D01*
G01X443768D02*
Y522924D01*
X440584Y526108D01*
X438380D01*
G01X447758Y521311D02*
X443768D01*
G01X441651Y534276D02*
X439224D01*
X437334Y532386D01*
G01X438845Y528288D02*
X441430D01*
X443450Y526268D01*
X445190Y526518D01*
G01D02*
Y526987D01*
X446915Y528712D01*
X449476D01*
X450823Y527365D01*
Y526483D01*
X451325Y525981D01*
G01X443028Y546277D02*
Y549330D01*
X442763Y549595D01*
G01X445838Y538085D02*
X442029Y534276D01*
X441651D01*
G01X445838Y538085D02*
X449692D01*
G01X446334Y546499D02*
Y550166D01*
X446536Y550368D01*
G01X464762Y438705D02*
X457674D01*
X454870Y441509D01*
Y456987D01*
X458238Y460355D01*
X467230D01*
X477400Y470525D01*
Y542617D01*
X461948Y558069D01*
X449306D01*
X446536Y555299D01*
Y553518D01*
G01X437832Y556374D02*
X436290Y554832D01*
Y553337D01*
G01X436219Y559133D02*
Y557987D01*
X437832Y556374D01*
G01X450790Y550369D02*
X450789Y550368D01*
X446536D01*
G01X462300Y599100D02*
X472600D01*
G01X446799Y657526D02*
Y659396D01*
X449102Y661699D01*
X451840D01*
G01X454263Y81713D02*
Y77675D01*
G01X450917Y97566D02*
X452294Y96189D01*
Y93919D01*
G01X453940Y98586D02*
X454263Y98263D01*
G01D02*
Y93919D01*
G01X456232Y100519D02*
Y93919D01*
G01X454641Y518021D02*
X451534Y521128D01*
X450540D01*
Y521331D01*
G01X456045Y513410D02*
Y514788D01*
X458173Y516916D01*
Y520289D01*
X454641Y523821D01*
G01X452895Y510061D02*
Y513410D01*
G01X449691Y532359D02*
Y531547D01*
X451504Y529734D01*
G01X460722Y532351D02*
X461611Y531462D01*
X463991D01*
Y531504D01*
G01X454641Y523821D02*
X452481Y525981D01*
X451325D01*
G01X456722Y529536D02*
Y532351D01*
G01D02*
X452849D01*
X452841Y532359D01*
G01X456722Y535501D02*
X451092D01*
X449692Y536901D01*
Y538085D01*
G01X460722Y535501D02*
X456722D01*
G01X456643Y539443D02*
X456722Y539364D01*
Y535501D01*
G01X463031Y543563D02*
X459837D01*
G01X459793Y539443D02*
Y543519D01*
X459837Y543563D01*
G01X453700Y545047D02*
X455184Y543563D01*
X456687D01*
G01X450367Y546436D02*
X452311D01*
X453700Y545047D01*
G01X465291Y537985D02*
Y544855D01*
X463433Y546713D01*
X460343D01*
X459328Y547728D01*
X456991D01*
G01D02*
Y543867D01*
X456687Y543563D01*
G01X453854Y555069D02*
X455303D01*
X456744Y553628D01*
X456991D01*
G01X450790Y553519D02*
X452304D01*
X453854Y555069D01*
G01X456991Y553628D02*
X457006Y553613D01*
X461588D01*
G01X450790Y550369D02*
X453617D01*
X453917Y550069D01*
G01X478370Y104470D02*
Y99059D01*
X479806Y97623D01*
X485004D01*
X486240Y98859D01*
Y105425D01*
X487013Y106198D01*
X488438D01*
G01X465291Y534835D02*
Y532804D01*
X463991Y531504D01*
G01X488438Y106198D02*
Y109623D01*
G01X495125Y118424D02*
Y122810D01*
X492713Y125222D01*
G01X488438Y109623D02*
X491917D01*
X494572Y112278D01*
X497232D01*
X499062Y114108D01*
Y118424D01*
G01X492713Y125222D02*
X491875D01*
G01X497093Y185826D02*
Y190191D01*
X496080Y191204D01*
G01X508904Y118424D02*
Y124063D01*
G01X510928Y687436D02*
X506376D01*
G01X515371Y658880D02*
X514399Y657908D01*
X510928D01*
G01X515425Y685783D02*
X515109Y685467D01*
X510928D01*
G01X532526Y118424D02*
Y114270D01*
X533946Y112850D01*
X535960D01*
G01X535230Y648711D02*
X535534Y648407D01*
Y643144D01*
G01X534558Y636985D02*
X534316Y637227D01*
Y638503D01*
X533566Y639253D01*
Y643144D01*
G01X541440D02*
Y647594D01*
G01Y704168D02*
Y707195D01*
X542548Y708303D01*
Y710142D01*
X543193Y710787D01*
G01X558117Y185826D02*
Y180340D01*
X557036Y179259D01*
X555836D01*
G01X545197Y274262D02*
Y276869D01*
X545223Y276895D01*
G01D02*
Y280528D01*
G01X545377Y643144D02*
Y647594D01*
G01X544984Y699419D02*
X545377Y699812D01*
Y704168D01*
G01X547346D02*
Y697581D01*
G01X549314Y704168D02*
Y707186D01*
X547542Y708958D01*
Y711523D01*
G01X576700Y655594D02*
X576342D01*
X575997Y655939D01*
X571952D01*
G01Y657908D02*
X578490D01*
X578920Y658338D01*
Y658250D01*
X579008D01*
G01X565168Y684614D02*
X566283Y683499D01*
X571952D01*
G01X581402Y686026D02*
X579210D01*
X578657Y685473D01*
Y685467D01*
X571952D01*
G01X620366Y292625D02*
X620400Y292591D01*
X624383D01*
G01X626669Y303705D02*
X620366Y297402D01*
Y295775D01*
G01X616024Y597824D02*
X612750D01*
X611520Y596594D01*
G01X616024Y587981D02*
X613708D01*
X612270Y586543D01*
G01X616024Y607666D02*
X612493D01*
G01X616024Y615540D02*
X614079D01*
X612276Y617343D01*
X611854D01*
X611254Y617943D01*
G01X616024Y613572D02*
X612941D01*
X612370Y614143D01*
G01X634212Y281670D02*
Y285042D01*
G01X626977Y288469D02*
Y292591D01*
G01D02*
X624383D01*
G01X630127Y288469D02*
Y292591D01*
G01D02*
X630128Y292592D01*
Y296525D01*
G01D02*
Y299521D01*
X631672Y301066D01*
G01X634212Y285042D02*
X634193Y285061D01*
Y289089D01*
G01D02*
X633790Y289492D01*
Y300078D01*
X634355Y300643D01*
X636349D01*
G01Y302611D02*
X633216D01*
X631672Y301066D01*
G01X627369Y303705D02*
X626669D01*
G01X634921Y584832D02*
Y580163D01*
G01X627047Y584832D02*
Y581066D01*
G01X627986Y625895D02*
X627980D01*
Y625004D01*
X629016Y623968D01*
Y620658D01*
G01X630984D02*
Y624829D01*
G01X645632Y284699D02*
X643001D01*
X642932Y284768D01*
G01X648555Y300643D02*
X649866D01*
X650991Y299518D01*
Y297429D01*
X649995Y296433D01*
G01D02*
Y291433D01*
X648758Y290196D01*
Y288706D01*
G01D02*
Y284723D01*
X648782Y284699D01*
G01D02*
X652868D01*
X653352Y285183D01*
G01X648555Y308517D02*
X650440D01*
X651976Y310053D01*
G01X646732Y584832D02*
Y580781D01*
G01X640827Y584832D02*
Y581786D01*
X641870Y580743D01*
G01X651850Y591918D02*
X655445D01*
G01X651850Y609635D02*
X655978D01*
G01X651850Y611603D02*
X654930D01*
X656070Y612743D01*
G01X651850Y601761D02*
X655688D01*
G01X642795Y620658D02*
Y624818D01*
G01X651850Y615540D02*
X655873D01*
G01X648701Y620658D02*
Y624774D01*
G01X674235Y379364D02*
X671949D01*
X671036Y380277D01*
Y381668D01*
X-44872Y125213D03*
Y141213D03*
Y232533D03*
D03*
Y248533D03*
D03*
Y738493D03*
Y754493D03*
X-26872Y125213D03*
Y141213D03*
Y232533D03*
D03*
Y248533D03*
D03*
Y738493D03*
Y754493D03*
X434102Y232640D03*
Y311875D03*
G54D204*
G01X38493Y-241864D02*
Y-246864D01*
G01X37036Y-241864D02*
X39950D01*
G01X44860Y-246864D02*
X42326D01*
Y-241864D01*
X44860D01*
G01X43846Y-244281D02*
X42326D01*
G01X47426Y-241864D02*
Y-246864D01*
X49960D01*
G01X53793Y-247031D02*
X53666Y-246947D01*
Y-246781D01*
X53793Y-246697D01*
X53920Y-246781D01*
Y-246947D01*
X53793Y-247031D01*
G01Y-244781D02*
X53666Y-244697D01*
Y-244531D01*
X53793Y-244447D01*
X53920Y-244531D01*
Y-244697D01*
X53793Y-244781D01*
G01X58576Y-248531D02*
X57943Y-247697D01*
X57626Y-246864D01*
Y-243531D01*
X57943Y-242697D01*
X58576Y-241864D01*
G01X63993D02*
X63486Y-242031D01*
X63106Y-242447D01*
X62853Y-242947D01*
X62663Y-243614D01*
X62600Y-244364D01*
X62663Y-245114D01*
X62853Y-245781D01*
X63106Y-246281D01*
X63486Y-246697D01*
X63993Y-246864D01*
X64500Y-246697D01*
X64880Y-246281D01*
X65133Y-245781D01*
X65323Y-245114D01*
X65386Y-244364D01*
X65323Y-243614D01*
X65133Y-242947D01*
X64880Y-242447D01*
X64500Y-242031D01*
X63993Y-241864D01*
G01X67700Y-245864D02*
X68080Y-246447D01*
X68586Y-246781D01*
X69156Y-246864D01*
X69663Y-246781D01*
X70170Y-246364D01*
X70486Y-245864D01*
X70550Y-245364D01*
X70423Y-244781D01*
X69980Y-244364D01*
X69536Y-244197D01*
X68966D01*
G01X69536D02*
X69916Y-243947D01*
X70233Y-243531D01*
X70360Y-243031D01*
X70233Y-242531D01*
X69916Y-242114D01*
X69346Y-241864D01*
X68776Y-241947D01*
X68206Y-242281D01*
G01X74510Y-248531D02*
X75143Y-247697D01*
X75460Y-246864D01*
Y-243531D01*
X75143Y-242697D01*
X74510Y-241864D01*
G01X77900Y-245864D02*
X78280Y-246447D01*
X78786Y-246781D01*
X79356Y-246864D01*
X79863Y-246781D01*
X80370Y-246364D01*
X80686Y-245864D01*
X80750Y-245364D01*
X80623Y-244781D01*
X80180Y-244364D01*
X79736Y-244197D01*
X79166D01*
G01X79736D02*
X80116Y-243947D01*
X80433Y-243531D01*
X80560Y-243031D01*
X80433Y-242531D01*
X80116Y-242114D01*
X79546Y-241864D01*
X78976Y-241947D01*
X78406Y-242281D01*
G01X83190Y-242697D02*
X83570Y-242197D01*
X84013Y-241947D01*
X84520Y-241864D01*
X85153Y-242031D01*
X85596Y-242447D01*
X85723Y-242947D01*
X85660Y-243447D01*
X85406Y-243864D01*
X84140Y-244697D01*
X83570Y-245281D01*
X83190Y-246114D01*
X83063Y-246864D01*
X85723D01*
G01X89366D02*
X89493Y-245781D01*
X89683Y-244864D01*
X89936Y-244031D01*
X90253Y-243114D01*
X90760Y-241864D01*
X88226D01*
G01X93770Y-245197D02*
X95416D01*
G01X98490Y-242697D02*
X98870Y-242197D01*
X99313Y-241947D01*
X99820Y-241864D01*
X100453Y-242031D01*
X100896Y-242447D01*
X101023Y-242947D01*
X100960Y-243447D01*
X100706Y-243864D01*
X99440Y-244697D01*
X98870Y-245281D01*
X98490Y-246114D01*
X98363Y-246864D01*
X101023D01*
G01X103400Y-245864D02*
X103780Y-246447D01*
X104286Y-246781D01*
X104856Y-246864D01*
X105363Y-246781D01*
X105870Y-246364D01*
X106186Y-245864D01*
X106250Y-245364D01*
X106123Y-244781D01*
X105680Y-244364D01*
X105236Y-244197D01*
X104666D01*
G01X105236D02*
X105616Y-243947D01*
X105933Y-243531D01*
X106060Y-243031D01*
X105933Y-242531D01*
X105616Y-242114D01*
X105046Y-241864D01*
X104476Y-241947D01*
X103906Y-242281D01*
G01X110653Y-246864D02*
Y-241864D01*
X108310Y-245447D01*
X111476D01*
G01X113600Y-246114D02*
X113980Y-246531D01*
X114423Y-246781D01*
X114993Y-246864D01*
X115563Y-246697D01*
X116006Y-246364D01*
X116323Y-245781D01*
X116386Y-245114D01*
X116260Y-244447D01*
X115943Y-244031D01*
X115500Y-243697D01*
X115056Y-243614D01*
X114613Y-243697D01*
X114043Y-244031D01*
X114233Y-241864D01*
X115943D01*
G01X123990Y-246864D02*
Y-241864D01*
X126396D01*
G01X125510Y-244281D02*
X123990D01*
G01X128710Y-246864D02*
X130293Y-241864D01*
X131876Y-246864D01*
G01X131306Y-245114D02*
X129280D01*
G01X134063Y-246864D02*
X136723Y-241864D01*
G01X134063D02*
X136723Y-246864D01*
G01X140493Y-247031D02*
X140366Y-246947D01*
Y-246781D01*
X140493Y-246697D01*
X140620Y-246781D01*
Y-246947D01*
X140493Y-247031D01*
G01Y-244781D02*
X140366Y-244697D01*
Y-244531D01*
X140493Y-244447D01*
X140620Y-244531D01*
Y-244697D01*
X140493Y-244781D01*
G01X145276Y-248531D02*
X144643Y-247697D01*
X144326Y-246864D01*
Y-243531D01*
X144643Y-242697D01*
X145276Y-241864D01*
G01X150693D02*
X150186Y-242031D01*
X149806Y-242447D01*
X149553Y-242947D01*
X149363Y-243614D01*
X149300Y-244364D01*
X149363Y-245114D01*
X149553Y-245781D01*
X149806Y-246281D01*
X150186Y-246697D01*
X150693Y-246864D01*
X151200Y-246697D01*
X151580Y-246281D01*
X151833Y-245781D01*
X152023Y-245114D01*
X152086Y-244364D01*
X152023Y-243614D01*
X151833Y-242947D01*
X151580Y-242447D01*
X151200Y-242031D01*
X150693Y-241864D01*
G01X154400Y-245864D02*
X154780Y-246447D01*
X155286Y-246781D01*
X155856Y-246864D01*
X156363Y-246781D01*
X156870Y-246364D01*
X157186Y-245864D01*
X157250Y-245364D01*
X157123Y-244781D01*
X156680Y-244364D01*
X156236Y-244197D01*
X155666D01*
G01X156236D02*
X156616Y-243947D01*
X156933Y-243531D01*
X157060Y-243031D01*
X156933Y-242531D01*
X156616Y-242114D01*
X156046Y-241864D01*
X155476Y-241947D01*
X154906Y-242281D01*
G01X161210Y-248531D02*
X161843Y-247697D01*
X162160Y-246864D01*
Y-243531D01*
X161843Y-242697D01*
X161210Y-241864D01*
G01X164600Y-245864D02*
X164980Y-246447D01*
X165486Y-246781D01*
X166056Y-246864D01*
X166563Y-246781D01*
X167070Y-246364D01*
X167386Y-245864D01*
X167450Y-245364D01*
X167323Y-244781D01*
X166880Y-244364D01*
X166436Y-244197D01*
X165866D01*
G01X166436D02*
X166816Y-243947D01*
X167133Y-243531D01*
X167260Y-243031D01*
X167133Y-242531D01*
X166816Y-242114D01*
X166246Y-241864D01*
X165676Y-241947D01*
X165106Y-242281D01*
G01X170016Y-246281D02*
X170460Y-246697D01*
X170966Y-246864D01*
X171473Y-246697D01*
X171916Y-246197D01*
X172233Y-245447D01*
X172360Y-244697D01*
Y-243781D01*
X172233Y-243031D01*
X171916Y-242364D01*
X171536Y-242031D01*
X171093Y-241864D01*
X170586Y-242031D01*
X170206Y-242364D01*
X169953Y-242864D01*
X169826Y-243531D01*
X169953Y-244114D01*
X170270Y-244697D01*
X170650Y-245031D01*
X171093Y-245114D01*
X171600Y-244947D01*
X171980Y-244531D01*
X172360Y-243781D01*
G01X176066Y-246864D02*
X176193Y-245781D01*
X176383Y-244864D01*
X176636Y-244031D01*
X176953Y-243114D01*
X177460Y-241864D01*
X174926D01*
G01X180470Y-245197D02*
X182116D01*
G01X185000Y-245864D02*
X185380Y-246447D01*
X185886Y-246781D01*
X186456Y-246864D01*
X186963Y-246781D01*
X187470Y-246364D01*
X187786Y-245864D01*
X187850Y-245364D01*
X187723Y-244781D01*
X187280Y-244364D01*
X186836Y-244197D01*
X186266D01*
G01X186836D02*
X187216Y-243947D01*
X187533Y-243531D01*
X187660Y-243031D01*
X187533Y-242531D01*
X187216Y-242114D01*
X186646Y-241864D01*
X186076Y-241947D01*
X185506Y-242281D01*
G01X190290Y-244781D02*
X190733Y-244197D01*
X191113Y-243864D01*
X191620Y-243697D01*
X192063Y-243864D01*
X192380Y-244197D01*
X192633Y-244697D01*
X192696Y-245281D01*
X192633Y-245781D01*
X192380Y-246281D01*
X192000Y-246697D01*
X191556Y-246864D01*
X191050Y-246697D01*
X190606Y-246197D01*
X190353Y-245447D01*
X190290Y-244614D01*
X190416Y-243531D01*
X190606Y-242947D01*
X190923Y-242364D01*
X191366Y-241947D01*
X191810Y-241864D01*
X192253Y-242031D01*
X192570Y-242447D01*
G01X196593Y-246864D02*
Y-241864D01*
X195833Y-242864D01*
G01Y-246864D02*
X197353D01*
G01X202453D02*
Y-241864D01*
X200110Y-245447D01*
X203276D01*
G01X26493Y-176864D02*
Y-251864D01*
X526493D01*
Y-176864D01*
X26493D01*
G01X221493D02*
Y-251864D01*
G01Y-226864D02*
X324493D01*
Y-201864D01*
G01X221493D02*
X324493D01*
G01X332000Y-236864D02*
Y-231864D01*
X333266D01*
X333773Y-232114D01*
X334153Y-232447D01*
X334470Y-232947D01*
X334723Y-233531D01*
X334786Y-234364D01*
X334723Y-235197D01*
X334470Y-235781D01*
X334153Y-236281D01*
X333773Y-236614D01*
X333266Y-236864D01*
X332000D01*
G01X336910D02*
X338493Y-231864D01*
X340076Y-236864D01*
G01X339506Y-235114D02*
X337480D01*
G01X343593Y-231864D02*
Y-236864D01*
G01X342136Y-231864D02*
X345050D01*
G01X349960Y-236864D02*
X347426D01*
Y-231864D01*
X349960D01*
G01X348946Y-234281D02*
X347426D01*
G01X353793Y-237031D02*
X353666Y-236947D01*
Y-236781D01*
X353793Y-236697D01*
X353920Y-236781D01*
Y-236947D01*
X353793Y-237031D01*
G01Y-234781D02*
X353666Y-234697D01*
Y-234531D01*
X353793Y-234447D01*
X353920Y-234531D01*
Y-234697D01*
X353793Y-234781D01*
G01X326493Y-176864D02*
Y-251864D01*
G01X324493Y-176864D02*
Y-251864D01*
G01X326493Y-226864D02*
X526493D01*
G01X332126Y-211864D02*
Y-206864D01*
X333646D01*
X334153Y-207114D01*
X334533Y-207697D01*
X334660Y-208364D01*
X334533Y-209031D01*
X334216Y-209531D01*
X333646Y-209781D01*
X332126D01*
G01X337353Y-212031D02*
X339633Y-206864D01*
G01X342136Y-211864D02*
Y-206864D01*
X345050Y-211864D01*
Y-206864D01*
G01X348693Y-212031D02*
X348566Y-211947D01*
Y-211781D01*
X348693Y-211697D01*
X348820Y-211781D01*
Y-211947D01*
X348693Y-212031D01*
G01Y-209781D02*
X348566Y-209697D01*
Y-209531D01*
X348693Y-209447D01*
X348820Y-209531D01*
Y-209697D01*
X348693Y-209781D01*
G01X326493Y-201864D02*
X526493D01*
G01X332126Y-186864D02*
Y-181864D01*
X333646D01*
X334153Y-182114D01*
X334533Y-182697D01*
X334660Y-183364D01*
X334533Y-184031D01*
X334216Y-184531D01*
X333646Y-184781D01*
X332126D01*
G01X337226Y-186864D02*
Y-181864D01*
X338810D01*
X339316Y-182114D01*
X339633Y-182447D01*
X339760Y-183114D01*
X339633Y-183781D01*
X339253Y-184197D01*
X338810Y-184447D01*
X337226D01*
G01X338810D02*
X339760Y-186864D01*
G01X343593D02*
X343086Y-186781D01*
X342643Y-186447D01*
X342263Y-185947D01*
X342010Y-185364D01*
X341883Y-184697D01*
Y-184031D01*
X342010Y-183364D01*
X342263Y-182781D01*
X342643Y-182281D01*
X343086Y-181947D01*
X343593Y-181864D01*
X344100Y-181947D01*
X344543Y-182281D01*
X344923Y-182781D01*
X345176Y-183364D01*
X345303Y-184031D01*
Y-184697D01*
X345176Y-185364D01*
X344923Y-185947D01*
X344543Y-186447D01*
X344100Y-186781D01*
X343593Y-186864D01*
G01X347426Y-185864D02*
X347743Y-186364D01*
X348123Y-186697D01*
X348566Y-186864D01*
X349073Y-186697D01*
X349453Y-186364D01*
X349833Y-185864D01*
X349960Y-185197D01*
Y-181864D01*
G01X355060Y-186864D02*
X352526D01*
Y-181864D01*
X355060D01*
G01X354046Y-184281D02*
X352526D01*
G01X360286Y-182281D02*
X359906Y-182031D01*
X359463Y-181864D01*
X358956D01*
X358386Y-182114D01*
X357943Y-182531D01*
X357626Y-183031D01*
X357373Y-183864D01*
X357310Y-184614D01*
X357436Y-185364D01*
X357626Y-185864D01*
X358006Y-186364D01*
X358450Y-186697D01*
X358893Y-186864D01*
X359336D01*
X359780Y-186697D01*
X360160Y-186447D01*
X360476Y-186114D01*
G01X363993Y-181864D02*
Y-186864D01*
G01X362536Y-181864D02*
X365450D01*
G01X369093Y-187031D02*
X368966Y-186947D01*
Y-186781D01*
X369093Y-186697D01*
X369220Y-186781D01*
Y-186947D01*
X369093Y-187031D01*
G01Y-184781D02*
X368966Y-184697D01*
Y-184531D01*
X369093Y-184447D01*
X369220Y-184531D01*
Y-184697D01*
X369093Y-184781D01*
G01X447126Y-236864D02*
Y-231864D01*
X448710D01*
X449216Y-232114D01*
X449533Y-232447D01*
X449660Y-233114D01*
X449533Y-233781D01*
X449153Y-234197D01*
X448710Y-234447D01*
X447126D01*
G01X448710D02*
X449660Y-236864D01*
G01X454760D02*
X452226D01*
Y-231864D01*
X454760D01*
G01X453746Y-234281D02*
X452226D01*
G01X457010Y-231864D02*
X458593Y-236864D01*
X460176Y-231864D01*
G01X463693Y-237031D02*
X463566Y-236947D01*
Y-236781D01*
X463693Y-236697D01*
X463820Y-236781D01*
Y-236947D01*
X463693Y-237031D01*
G01Y-234781D02*
X463566Y-234697D01*
Y-234531D01*
X463693Y-234447D01*
X463820Y-234531D01*
Y-234697D01*
X463693Y-234781D01*
G01X441493Y-226864D02*
Y-251864D01*
G01X490493Y-226864D02*
Y-251864D01*
G01X-1043962Y-705877D02*
Y2342823D01*
X2300638D01*
Y-705877D01*
X-1043962D01*
G01X37198Y-238524D02*
X37825Y-239049D01*
X38530Y-239364D01*
X39156D01*
X39783Y-239049D01*
X40253Y-238524D01*
X40488Y-237789D01*
X40331Y-237054D01*
X39940Y-236424D01*
X39235Y-236004D01*
X38295Y-235794D01*
X37746Y-235374D01*
X37511Y-234639D01*
X37668Y-233904D01*
X38060Y-233379D01*
X38608Y-233064D01*
X39156D01*
X39705Y-233274D01*
X40175Y-233799D01*
G01X43498Y-239364D02*
Y-233064D01*
G01X46788D02*
Y-239364D01*
G01Y-236214D02*
X43498D01*
G01X50503Y-233064D02*
X52383D01*
G01X51443D02*
Y-239364D01*
G01X50503D02*
X52383D01*
G01X59310D02*
X56176D01*
Y-233064D01*
X59310D01*
G01X58056Y-236109D02*
X56176D01*
G01X62241Y-239364D02*
Y-233064D01*
X65845Y-239364D01*
Y-233064D01*
G01X70186Y-240519D02*
X70500Y-239154D01*
G01X76643Y-233064D02*
Y-239364D01*
G01X74841Y-233064D02*
X78445D01*
G01X80985Y-239364D02*
X82943Y-233064D01*
X84901Y-239364D01*
G01X84196Y-237159D02*
X81690D01*
G01X88303Y-233064D02*
X90183D01*
G01X89243D02*
Y-239364D01*
G01X88303D02*
X90183D01*
G01X93193Y-233064D02*
X94290Y-239364D01*
X95543Y-233064D01*
X96796Y-239364D01*
X97893Y-233064D01*
G01X99885Y-239364D02*
X101843Y-233064D01*
X103801Y-239364D01*
G01X103096Y-237159D02*
X100590D01*
G01X106341Y-239364D02*
Y-233064D01*
X109945Y-239364D01*
Y-233064D01*
G01X119176Y-239364D02*
Y-233064D01*
X121135D01*
X121761Y-233379D01*
X122153Y-233799D01*
X122310Y-234639D01*
X122153Y-235479D01*
X121683Y-236004D01*
X121135Y-236319D01*
X119176D01*
G01X121135D02*
X122310Y-239364D01*
G01X127043Y-239574D02*
X126886Y-239469D01*
Y-239259D01*
X127043Y-239154D01*
X127200Y-239259D01*
Y-239469D01*
X127043Y-239574D01*
G01X133343Y-239364D02*
X132716Y-239259D01*
X132168Y-238839D01*
X131698Y-238209D01*
X131385Y-237474D01*
X131228Y-236634D01*
Y-235794D01*
X131385Y-234954D01*
X131698Y-234219D01*
X132168Y-233589D01*
X132716Y-233169D01*
X133343Y-233064D01*
X133970Y-233169D01*
X134518Y-233589D01*
X134988Y-234219D01*
X135301Y-234954D01*
X135458Y-235794D01*
Y-236634D01*
X135301Y-237474D01*
X134988Y-238209D01*
X134518Y-238839D01*
X133970Y-239259D01*
X133343Y-239364D01*
G01X139643Y-239574D02*
X139486Y-239469D01*
Y-239259D01*
X139643Y-239154D01*
X139800Y-239259D01*
Y-239469D01*
X139643Y-239574D01*
G01X147666Y-233589D02*
X147196Y-233274D01*
X146648Y-233064D01*
X146021D01*
X145316Y-233379D01*
X144768Y-233904D01*
X144376Y-234534D01*
X144063Y-235584D01*
X143985Y-236529D01*
X144141Y-237474D01*
X144376Y-238104D01*
X144846Y-238734D01*
X145395Y-239154D01*
X145943Y-239364D01*
X146491D01*
X147040Y-239154D01*
X147510Y-238839D01*
X147901Y-238419D01*
G01X152243Y-239574D02*
X152086Y-239469D01*
Y-239259D01*
X152243Y-239154D01*
X152400Y-239259D01*
Y-239469D01*
X152243Y-239574D01*
G01X37120Y-229364D02*
Y-223064D01*
G01X40096D02*
X37120Y-226949D01*
G01X40566Y-229364D02*
X38451Y-225164D01*
G01X43420Y-223064D02*
Y-227579D01*
X43733Y-228524D01*
X44360Y-229154D01*
X45143Y-229364D01*
X45926Y-229154D01*
X46553Y-228524D01*
X46866Y-227579D01*
Y-223064D01*
G01X53010Y-229364D02*
X49876D01*
Y-223064D01*
X53010D01*
G01X51756Y-226109D02*
X49876D01*
G01X56803Y-223064D02*
X58683D01*
G01X57743D02*
Y-229364D01*
G01X56803D02*
X58683D01*
G01X68698Y-228524D02*
X69325Y-229049D01*
X70030Y-229364D01*
X70656D01*
X71283Y-229049D01*
X71753Y-228524D01*
X71988Y-227789D01*
X71831Y-227054D01*
X71440Y-226424D01*
X70735Y-226004D01*
X69795Y-225794D01*
X69246Y-225374D01*
X69011Y-224639D01*
X69168Y-223904D01*
X69560Y-223379D01*
X70108Y-223064D01*
X70656D01*
X71205Y-223274D01*
X71675Y-223799D01*
G01X74998Y-229364D02*
Y-223064D01*
G01X78288D02*
Y-229364D01*
G01Y-226214D02*
X74998D01*
G01X80985Y-229364D02*
X82943Y-223064D01*
X84901Y-229364D01*
G01X84196Y-227159D02*
X81690D01*
G01X87441Y-229364D02*
Y-223064D01*
X91045Y-229364D01*
Y-223064D01*
G01X100198Y-229364D02*
Y-223064D01*
G01X103488D02*
Y-229364D01*
G01Y-226214D02*
X100198D01*
G01X106498Y-228524D02*
X107125Y-229049D01*
X107830Y-229364D01*
X108456D01*
X109083Y-229049D01*
X109553Y-228524D01*
X109788Y-227789D01*
X109631Y-227054D01*
X109240Y-226424D01*
X108535Y-226004D01*
X107595Y-225794D01*
X107046Y-225374D01*
X106811Y-224639D01*
X106968Y-223904D01*
X107360Y-223379D01*
X107908Y-223064D01*
X108456D01*
X109005Y-223274D01*
X109475Y-223799D01*
G01X113503Y-223064D02*
X115383D01*
G01X114443D02*
Y-229364D01*
G01X113503D02*
X115383D01*
G01X118785D02*
X120743Y-223064D01*
X122701Y-229364D01*
G01X121996Y-227159D02*
X119490D01*
G01X125241Y-229364D02*
Y-223064D01*
X128845Y-229364D01*
Y-223064D01*
G01X133813Y-226214D02*
X135380D01*
Y-228104D01*
X134910Y-228734D01*
X134361Y-229154D01*
X133578Y-229364D01*
X132795Y-229154D01*
X132246Y-228734D01*
X131776Y-228104D01*
X131463Y-227369D01*
X131306Y-226529D01*
Y-225794D01*
X131463Y-225164D01*
X131776Y-224429D01*
X132246Y-223799D01*
X132716Y-223379D01*
X133343Y-223064D01*
X133891D01*
X134518Y-223274D01*
X134988Y-223694D01*
G01X139486Y-230519D02*
X139800Y-229154D01*
G01X145943Y-223064D02*
Y-229364D01*
G01X144141Y-223064D02*
X147745D01*
G01X150285Y-229364D02*
X152243Y-223064D01*
X154201Y-229364D01*
G01X153496Y-227159D02*
X150990D01*
G01X158543Y-229364D02*
X157916Y-229259D01*
X157368Y-228839D01*
X156898Y-228209D01*
X156585Y-227474D01*
X156428Y-226634D01*
Y-225794D01*
X156585Y-224954D01*
X156898Y-224219D01*
X157368Y-223589D01*
X157916Y-223169D01*
X158543Y-223064D01*
X159170Y-223169D01*
X159718Y-223589D01*
X160188Y-224219D01*
X160501Y-224954D01*
X160658Y-225794D01*
Y-226634D01*
X160501Y-227474D01*
X160188Y-228209D01*
X159718Y-228839D01*
X159170Y-229259D01*
X158543Y-229364D01*
G01X171143D02*
Y-226529D01*
X169576Y-223064D01*
G01X172710D02*
X171143Y-226529D01*
G01X175720Y-223064D02*
Y-227579D01*
X176033Y-228524D01*
X176660Y-229154D01*
X177443Y-229364D01*
X178226Y-229154D01*
X178853Y-228524D01*
X179166Y-227579D01*
Y-223064D01*
G01X181785Y-229364D02*
X183743Y-223064D01*
X185701Y-229364D01*
G01X184996Y-227159D02*
X182490D01*
G01X188241Y-229364D02*
Y-223064D01*
X191845Y-229364D01*
Y-223064D01*
G01X37041Y-219364D02*
Y-213064D01*
X40645Y-219364D01*
Y-213064D01*
G01X45143Y-219364D02*
X44516Y-219259D01*
X43968Y-218839D01*
X43498Y-218209D01*
X43185Y-217474D01*
X43028Y-216634D01*
Y-215794D01*
X43185Y-214954D01*
X43498Y-214219D01*
X43968Y-213589D01*
X44516Y-213169D01*
X45143Y-213064D01*
X45770Y-213169D01*
X46318Y-213589D01*
X46788Y-214219D01*
X47101Y-214954D01*
X47258Y-215794D01*
Y-216634D01*
X47101Y-217474D01*
X46788Y-218209D01*
X46318Y-218839D01*
X45770Y-219259D01*
X45143Y-219364D01*
G01X51443Y-219574D02*
X51286Y-219469D01*
Y-219259D01*
X51443Y-219154D01*
X51600Y-219259D01*
Y-219469D01*
X51443Y-219574D01*
G01X57743Y-219364D02*
Y-213064D01*
X56803Y-214324D01*
G01Y-219364D02*
X58683D01*
G01X64043D02*
X64591Y-219259D01*
X65218Y-218944D01*
X65610Y-218419D01*
X65766Y-217684D01*
X65610Y-216949D01*
X65140Y-216319D01*
X64435Y-216004D01*
X63651D01*
X63181Y-215794D01*
X62790Y-215269D01*
X62633Y-214534D01*
X62868Y-213799D01*
X63416Y-213274D01*
X64043Y-213064D01*
X64670Y-213274D01*
X65218Y-213799D01*
X65453Y-214534D01*
X65296Y-215269D01*
X64905Y-215794D01*
X64435Y-216004D01*
X63651D01*
X62946Y-216319D01*
X62476Y-216949D01*
X62320Y-217684D01*
X62476Y-218419D01*
X62868Y-218944D01*
X63495Y-219259D01*
X64043Y-219364D01*
G01X70343D02*
X70891Y-219259D01*
X71518Y-218944D01*
X71910Y-218419D01*
X72066Y-217684D01*
X71910Y-216949D01*
X71440Y-216319D01*
X70735Y-216004D01*
X69951D01*
X69481Y-215794D01*
X69090Y-215269D01*
X68933Y-214534D01*
X69168Y-213799D01*
X69716Y-213274D01*
X70343Y-213064D01*
X70970Y-213274D01*
X71518Y-213799D01*
X71753Y-214534D01*
X71596Y-215269D01*
X71205Y-215794D01*
X70735Y-216004D01*
X69951D01*
X69246Y-216319D01*
X68776Y-216949D01*
X68620Y-217684D01*
X68776Y-218419D01*
X69168Y-218944D01*
X69795Y-219259D01*
X70343Y-219364D01*
G01X76486Y-220519D02*
X76800Y-219154D01*
G01X80593Y-213064D02*
X81690Y-219364D01*
X82943Y-213064D01*
X84196Y-219364D01*
X85293Y-213064D01*
G01X90810Y-219364D02*
X87676D01*
Y-213064D01*
X90810D01*
G01X89556Y-216109D02*
X87676D01*
G01X93741Y-219364D02*
Y-213064D01*
X97345Y-219364D01*
Y-213064D01*
G01X106498Y-219364D02*
Y-213064D01*
G01X109788D02*
Y-219364D01*
G01Y-216214D02*
X106498D01*
G01X112093Y-213064D02*
X113190Y-219364D01*
X114443Y-213064D01*
X115696Y-219364D01*
X116793Y-213064D01*
G01X118785Y-219364D02*
X120743Y-213064D01*
X122701Y-219364D01*
G01X121996Y-217159D02*
X119490D01*
G01X131855Y-214114D02*
X132325Y-213484D01*
X132873Y-213169D01*
X133500Y-213064D01*
X134283Y-213274D01*
X134831Y-213799D01*
X134988Y-214429D01*
X134910Y-215059D01*
X134596Y-215584D01*
X133030Y-216634D01*
X132325Y-217369D01*
X131855Y-218419D01*
X131698Y-219364D01*
X134988D01*
G01X137841D02*
Y-213064D01*
X141445Y-219364D01*
Y-213064D01*
G01X144220Y-219364D02*
Y-213064D01*
X145786D01*
X146413Y-213379D01*
X146883Y-213799D01*
X147275Y-214429D01*
X147588Y-215164D01*
X147666Y-216214D01*
X147588Y-217264D01*
X147275Y-217999D01*
X146883Y-218629D01*
X146413Y-219049D01*
X145786Y-219364D01*
X144220D01*
G01X156976D02*
Y-213064D01*
X158935D01*
X159561Y-213379D01*
X159953Y-213799D01*
X160110Y-214639D01*
X159953Y-215479D01*
X159483Y-216004D01*
X158935Y-216319D01*
X156976D01*
G01X158935D02*
X160110Y-219364D01*
G01X163120D02*
Y-213064D01*
X164686D01*
X165313Y-213379D01*
X165783Y-213799D01*
X166175Y-214429D01*
X166488Y-215164D01*
X166566Y-216214D01*
X166488Y-217264D01*
X166175Y-217999D01*
X165783Y-218629D01*
X165313Y-219049D01*
X164686Y-219364D01*
X163120D01*
G01X171143Y-219574D02*
X170986Y-219469D01*
Y-219259D01*
X171143Y-219154D01*
X171300Y-219259D01*
Y-219469D01*
X171143Y-219574D01*
G01X61143Y-206664D02*
X58623Y-206247D01*
X56418Y-204581D01*
X54528Y-202081D01*
X53268Y-199164D01*
X52638Y-195831D01*
Y-192497D01*
X53268Y-189164D01*
X54528Y-186247D01*
X56418Y-183748D01*
X58623Y-182081D01*
X61143Y-181664D01*
X63663Y-182081D01*
X65868Y-183748D01*
X67758Y-186247D01*
X69018Y-189164D01*
X69648Y-192497D01*
Y-195831D01*
X69018Y-199164D01*
X67758Y-202081D01*
X65868Y-204581D01*
X63663Y-206247D01*
X61143Y-206664D01*
G01X63663Y-199997D02*
X67443Y-206664D01*
G01X80988Y-189998D02*
Y-201664D01*
X82248Y-204581D01*
X84138Y-206247D01*
X86343Y-206664D01*
X88548Y-206247D01*
X90438Y-204581D01*
X91698Y-201664D01*
G01Y-206664D02*
Y-189998D01*
G01X117213Y-206664D02*
Y-189998D01*
G01Y-192914D02*
X115953Y-191248D01*
X114063Y-190414D01*
X111858Y-189998D01*
X109653Y-190831D01*
X107763Y-192497D01*
X106503Y-194998D01*
X105873Y-198331D01*
X106503Y-201664D01*
X107763Y-204165D01*
X109653Y-205831D01*
X111858Y-206664D01*
X114063Y-206247D01*
X115953Y-204998D01*
X117213Y-203331D01*
G01X131388Y-206664D02*
Y-189998D01*
G01Y-194164D02*
X132648Y-192081D01*
X134538Y-190414D01*
X137058Y-189998D01*
X139263Y-190414D01*
X141153Y-192081D01*
X142098Y-194998D01*
Y-206664D01*
G01X161943Y-181664D02*
Y-206664D01*
G01X157533Y-189998D02*
X166353D01*
G01X192813Y-206664D02*
Y-189998D01*
G01Y-192914D02*
X191553Y-191248D01*
X189663Y-190414D01*
X187458Y-189998D01*
X185253Y-190831D01*
X183363Y-192497D01*
X182103Y-194998D01*
X181473Y-198331D01*
X182103Y-201664D01*
X183363Y-204165D01*
X185253Y-205831D01*
X187458Y-206664D01*
X189663Y-206247D01*
X191553Y-204998D01*
X192813Y-203331D01*
G01X143779Y37407D02*
X142029D01*
X141380Y36758D01*
G01X151507Y46710D02*
Y53107D01*
G01X232493Y-186364D02*
Y-194364D01*
X236493D01*
G01X244293D02*
Y-189031D01*
G01Y-189964D02*
X243893Y-189431D01*
X243293Y-189164D01*
X242593Y-189031D01*
X241893Y-189297D01*
X241293Y-189831D01*
X240893Y-190631D01*
X240693Y-191697D01*
X240893Y-192764D01*
X241293Y-193564D01*
X241893Y-194097D01*
X242593Y-194364D01*
X243293Y-194231D01*
X243893Y-193831D01*
X244293Y-193298D01*
G01X248393Y-196764D02*
X248993Y-197031D01*
X249793Y-196764D01*
X250293Y-196231D01*
X250693Y-195564D01*
X251293Y-193431D01*
X252593Y-189031D01*
G01X249393D02*
X251293Y-193431D01*
G01X256993Y-190764D02*
X260193D01*
X259893Y-189831D01*
X259393Y-189297D01*
X258693Y-189031D01*
X257993Y-189164D01*
X257393Y-189564D01*
X256993Y-190497D01*
X256793Y-191298D01*
Y-192097D01*
X256993Y-192897D01*
X257493Y-193697D01*
X258093Y-194231D01*
X258793Y-194364D01*
X259493Y-194097D01*
X260193Y-193298D01*
G01X265093Y-194364D02*
Y-189031D01*
G01Y-190097D02*
X265593Y-189564D01*
X266093Y-189164D01*
X266793Y-189031D01*
X267293Y-189164D01*
X267893Y-189564D01*
G01X254793Y-236364D02*
X257193D01*
G01X255993D02*
Y-244364D01*
G01X254793D02*
X257193D01*
G01X262593D02*
Y-239031D01*
G01Y-240097D02*
X263093Y-239564D01*
X263593Y-239164D01*
X264293Y-239031D01*
X264793Y-239164D01*
X265393Y-239564D01*
G01X270493Y-240764D02*
X273693D01*
X273393Y-239831D01*
X272893Y-239297D01*
X272193Y-239031D01*
X271493Y-239164D01*
X270893Y-239564D01*
X270493Y-240497D01*
X270293Y-241298D01*
Y-242097D01*
X270493Y-242897D01*
X270993Y-243697D01*
X271593Y-244231D01*
X272293Y-244364D01*
X272993Y-244097D01*
X273693Y-243298D01*
G01X278293Y-244364D02*
Y-239031D01*
G01Y-240364D02*
X278693Y-239697D01*
X279293Y-239164D01*
X280093Y-239031D01*
X280793Y-239164D01*
X281393Y-239697D01*
X281693Y-240631D01*
Y-244364D01*
G01X286493Y-240764D02*
X289693D01*
X289393Y-239831D01*
X288893Y-239297D01*
X288193Y-239031D01*
X287493Y-239164D01*
X286893Y-239564D01*
X286493Y-240497D01*
X286293Y-241298D01*
Y-242097D01*
X286493Y-242897D01*
X286993Y-243697D01*
X287593Y-244231D01*
X288293Y-244364D01*
X288993Y-244097D01*
X289693Y-243298D01*
G01X265993Y-211364D02*
Y-219364D01*
G01X263693Y-211364D02*
X268293D01*
G01X273993Y-219364D02*
X273193Y-219231D01*
X272493Y-218697D01*
X271893Y-217897D01*
X271493Y-216964D01*
X271293Y-215897D01*
Y-214831D01*
X271493Y-213764D01*
X271893Y-212831D01*
X272493Y-212031D01*
X273193Y-211497D01*
X273993Y-211364D01*
X274793Y-211497D01*
X275493Y-212031D01*
X276093Y-212831D01*
X276493Y-213764D01*
X276693Y-214831D01*
Y-215897D01*
X276493Y-216964D01*
X276093Y-217897D01*
X275493Y-218697D01*
X274793Y-219231D01*
X273993Y-219364D01*
G01X279993D02*
Y-211364D01*
X282393D01*
X283193Y-211764D01*
X283793Y-212697D01*
X283993Y-213764D01*
X283793Y-214831D01*
X283293Y-215631D01*
X282393Y-216031D01*
X279993D01*
G01X285993Y-194364D02*
Y-186364D01*
X284793Y-187964D01*
G01Y-194364D02*
X287193D01*
G01X359093Y-237697D02*
X359693Y-236897D01*
X360393Y-236497D01*
X361193Y-236364D01*
X362193Y-236631D01*
X362893Y-237297D01*
X363093Y-238097D01*
X362993Y-238898D01*
X362593Y-239564D01*
X360593Y-240897D01*
X359693Y-241831D01*
X359093Y-243164D01*
X358893Y-244364D01*
X363093D01*
G01X368993Y-236364D02*
X368193Y-236631D01*
X367593Y-237297D01*
X367193Y-238097D01*
X366893Y-239164D01*
X366793Y-240364D01*
X366893Y-241564D01*
X367193Y-242631D01*
X367593Y-243431D01*
X368193Y-244097D01*
X368993Y-244364D01*
X369793Y-244097D01*
X370393Y-243431D01*
X370793Y-242631D01*
X371093Y-241564D01*
X371193Y-240364D01*
X371093Y-239164D01*
X370793Y-238097D01*
X370393Y-237297D01*
X369793Y-236631D01*
X368993Y-236364D01*
G01X376993Y-244364D02*
Y-236364D01*
X375793Y-237964D01*
G01Y-244364D02*
X378193D01*
G01X383093Y-237697D02*
X383693Y-236897D01*
X384393Y-236497D01*
X385193Y-236364D01*
X386193Y-236631D01*
X386893Y-237297D01*
X387093Y-238097D01*
X386993Y-238898D01*
X386593Y-239564D01*
X384593Y-240897D01*
X383693Y-241831D01*
X383093Y-243164D01*
X382893Y-244364D01*
X387093D01*
G01X391193Y-244631D02*
X394793Y-236364D01*
G01X400993Y-244364D02*
Y-236364D01*
X399793Y-237964D01*
G01Y-244364D02*
X402193D01*
G01X408993Y-236364D02*
X408193Y-236631D01*
X407593Y-237297D01*
X407193Y-238097D01*
X406893Y-239164D01*
X406793Y-240364D01*
X406893Y-241564D01*
X407193Y-242631D01*
X407593Y-243431D01*
X408193Y-244097D01*
X408993Y-244364D01*
X409793Y-244097D01*
X410393Y-243431D01*
X410793Y-242631D01*
X411093Y-241564D01*
X411193Y-240364D01*
X411093Y-239164D01*
X410793Y-238097D01*
X410393Y-237297D01*
X409793Y-236631D01*
X408993Y-236364D01*
G01X415193Y-244631D02*
X418793Y-236364D01*
G01X422793Y-242764D02*
X423393Y-243697D01*
X424193Y-244231D01*
X425093Y-244364D01*
X425893Y-244231D01*
X426693Y-243564D01*
X427193Y-242764D01*
X427293Y-241964D01*
X427093Y-241031D01*
X426393Y-240364D01*
X425693Y-240097D01*
X424793D01*
G01X425693D02*
X426293Y-239697D01*
X426793Y-239031D01*
X426993Y-238231D01*
X426793Y-237431D01*
X426293Y-236764D01*
X425393Y-236364D01*
X424493Y-236497D01*
X423593Y-237031D01*
G01X432993Y-244364D02*
Y-236364D01*
X431793Y-237964D01*
G01Y-244364D02*
X434193D01*
G01X358793Y-219364D02*
Y-211364D01*
X360793D01*
X361593Y-211764D01*
X362193Y-212297D01*
X362693Y-213097D01*
X363093Y-214031D01*
X363193Y-215364D01*
X363093Y-216697D01*
X362693Y-217631D01*
X362193Y-218431D01*
X361593Y-218964D01*
X360793Y-219364D01*
X358793D01*
G01X366493D02*
X368993Y-211364D01*
X371493Y-219364D01*
G01X370593Y-216564D02*
X367393D01*
G01X376993Y-211364D02*
Y-219364D01*
G01X374693Y-211364D02*
X379293D01*
G01X383093Y-216031D02*
X383793Y-215097D01*
X384393Y-214564D01*
X385193Y-214297D01*
X385893Y-214564D01*
X386393Y-215097D01*
X386793Y-215897D01*
X386893Y-216831D01*
X386793Y-217631D01*
X386393Y-218431D01*
X385793Y-219097D01*
X385093Y-219364D01*
X384293Y-219097D01*
X383593Y-218298D01*
X383193Y-217097D01*
X383093Y-215764D01*
X383293Y-214031D01*
X383593Y-213097D01*
X384093Y-212164D01*
X384793Y-211497D01*
X385493Y-211364D01*
X386193Y-211631D01*
X386693Y-212297D01*
G01X390393Y-219364D02*
Y-211364D01*
X392993Y-218031D01*
X395593Y-211364D01*
Y-219364D01*
G01X400993Y-211364D02*
Y-219364D01*
G01X398693Y-211364D02*
X403293D01*
G01X406893Y-219364D02*
Y-211364D01*
G01X411093D02*
Y-219364D01*
G01Y-215364D02*
X406893D01*
G01X414793Y-217764D02*
X415393Y-218697D01*
X416193Y-219231D01*
X417093Y-219364D01*
X417893Y-219231D01*
X418693Y-218564D01*
X419193Y-217764D01*
X419293Y-216964D01*
X419093Y-216031D01*
X418393Y-215364D01*
X417693Y-215097D01*
X416793D01*
G01X417693D02*
X418293Y-214697D01*
X418793Y-214031D01*
X418993Y-213231D01*
X418793Y-212431D01*
X418293Y-211764D01*
X417393Y-211364D01*
X416493Y-211497D01*
X415593Y-212031D01*
G01X422493Y-219364D02*
X424993Y-211364D01*
X427493Y-219364D01*
G01X426593Y-216564D02*
X423393D01*
G01X430793Y-219364D02*
Y-211364D01*
X432793D01*
X433593Y-211764D01*
X434193Y-212297D01*
X434693Y-213097D01*
X435093Y-214031D01*
X435193Y-215364D01*
X435093Y-216697D01*
X434693Y-217631D01*
X434193Y-218431D01*
X433593Y-218964D01*
X432793Y-219364D01*
X430793D01*
G01X440993Y-211364D02*
X440193Y-211631D01*
X439593Y-212297D01*
X439193Y-213097D01*
X438893Y-214164D01*
X438793Y-215364D01*
X438893Y-216564D01*
X439193Y-217631D01*
X439593Y-218431D01*
X440193Y-219097D01*
X440993Y-219364D01*
X441793Y-219097D01*
X442393Y-218431D01*
X442793Y-217631D01*
X443093Y-216564D01*
X443193Y-215364D01*
X443093Y-214164D01*
X442793Y-213097D01*
X442393Y-212297D01*
X441793Y-211631D01*
X440993Y-211364D01*
G01X380993Y-186364D02*
Y-194364D01*
G01X378693Y-186364D02*
X383293D01*
G01X387093Y-191031D02*
X387793Y-190097D01*
X388393Y-189564D01*
X389193Y-189297D01*
X389893Y-189564D01*
X390393Y-190097D01*
X390793Y-190897D01*
X390893Y-191831D01*
X390793Y-192631D01*
X390393Y-193431D01*
X389793Y-194097D01*
X389093Y-194364D01*
X388293Y-194097D01*
X387593Y-193298D01*
X387193Y-192097D01*
X387093Y-190764D01*
X387293Y-189031D01*
X387593Y-188097D01*
X388093Y-187164D01*
X388793Y-186497D01*
X389493Y-186364D01*
X390193Y-186631D01*
X390693Y-187297D01*
G01X394393Y-194364D02*
Y-186364D01*
X396993Y-193031D01*
X399593Y-186364D01*
Y-194364D01*
G01X401993Y-197031D02*
X407993D01*
G01X415193Y-187031D02*
X414593Y-186631D01*
X413893Y-186364D01*
X413093D01*
X412193Y-186764D01*
X411493Y-187431D01*
X410993Y-188231D01*
X410593Y-189564D01*
X410493Y-190764D01*
X410693Y-191964D01*
X410993Y-192764D01*
X411593Y-193564D01*
X412293Y-194097D01*
X412993Y-194364D01*
X413693D01*
X414393Y-194097D01*
X414993Y-193697D01*
X415493Y-193164D01*
G01X418393Y-194364D02*
Y-186364D01*
X420993Y-193031D01*
X423593Y-186364D01*
Y-194364D01*
G01X425993Y-197031D02*
X431993D01*
G01X434793Y-194364D02*
Y-186364D01*
X436793D01*
X437593Y-186764D01*
X438193Y-187297D01*
X438693Y-188097D01*
X439093Y-189031D01*
X439193Y-190364D01*
X439093Y-191697D01*
X438693Y-192631D01*
X438193Y-193431D01*
X437593Y-193964D01*
X436793Y-194364D01*
X434793D01*
G01X473793Y-244364D02*
Y-236364D01*
X475793D01*
X476593Y-236764D01*
X477193Y-237297D01*
X477693Y-238097D01*
X478093Y-239031D01*
X478193Y-240364D01*
X478093Y-241697D01*
X477693Y-242631D01*
X477193Y-243431D01*
X476593Y-243964D01*
X475793Y-244364D01*
X473793D01*
G01X503493D02*
Y-236364D01*
X502293Y-237964D01*
G01Y-244364D02*
X504693D01*
G01X509593Y-241031D02*
X510293Y-240097D01*
X510893Y-239564D01*
X511693Y-239297D01*
X512393Y-239564D01*
X512893Y-240097D01*
X513293Y-240897D01*
X513393Y-241831D01*
X513293Y-242631D01*
X512893Y-243431D01*
X512293Y-244097D01*
X511593Y-244364D01*
X510793Y-244097D01*
X510093Y-243298D01*
X509693Y-242097D01*
X509593Y-240764D01*
X509793Y-239031D01*
X510093Y-238097D01*
X510593Y-237164D01*
X511293Y-236497D01*
X511993Y-236364D01*
X512693Y-236631D01*
X513193Y-237297D01*
G01X537416Y468168D02*
X540256D01*
X541828Y469740D01*
X545513D01*
G54D21*
X20435Y561223D03*
X17876D03*
X15317D03*
X12758D03*
Y584223D03*
X15317D03*
X17876D03*
X20435D03*
X20507Y622914D03*
X17948D03*
X15389D03*
X12830D03*
X10271D03*
Y645914D03*
X12830D03*
X15389D03*
X17948D03*
X20507D03*
X36567Y79540D03*
X34008D03*
X31449D03*
Y102540D03*
X34008D03*
X36567D03*
X38349Y561223D03*
X35790D03*
X33231D03*
X30672D03*
X28112D03*
X25553D03*
X22994D03*
Y584223D03*
X25553D03*
X28112D03*
X30672D03*
X33231D03*
X35790D03*
X38349D03*
X38421Y622914D03*
X35862D03*
X33303D03*
X30744D03*
X28185D03*
X25625D03*
X23066D03*
Y645914D03*
X25625D03*
X28185D03*
X30744D03*
X33303D03*
X35862D03*
X38421D03*
X51922Y79540D03*
X49363D03*
X46803D03*
X44244D03*
X41685D03*
X39126D03*
Y102540D03*
X41685D03*
X44244D03*
X46803D03*
X49363D03*
X51922D03*
X46026Y561223D03*
X43467D03*
X40908D03*
Y584223D03*
X43467D03*
X46026D03*
X43539Y622914D03*
X40980D03*
Y645914D03*
X43539D03*
X64717Y79540D03*
X62158D03*
X59599D03*
X57040D03*
X54481D03*
Y102540D03*
X57040D03*
X59599D03*
X62158D03*
X64717D03*
G54D132*
X395227Y633135D03*
Y640615D03*
X403101Y636875D03*
X535735Y259622D03*
Y267102D03*
X543609Y263362D03*
G54D114*
X260887Y399450D03*
X268761Y403190D03*
Y395710D03*
X634852Y474939D03*
X634787Y501470D03*
X634887Y488270D03*
X642726Y471199D03*
X642761Y484530D03*
X642726Y478679D03*
X642661Y497730D03*
X642761Y492010D03*
X642661Y505210D03*
X680949Y524536D03*
Y532016D03*
X688823Y528276D03*
G54D123*
X332490Y328505D03*
Y338347D03*
X695230Y201790D03*
Y190373D03*
X748713Y125542D03*
Y114125D03*
G54D30*
X41930Y184229D03*
G54D150*
X454263Y87816D03*
G54D141*
X428747Y455592D03*
Y477403D03*
G54D105*
X196909Y515342D03*
X208209Y504075D03*
X199565Y506454D03*
X205294Y514368D03*
X205247Y508713D03*
X205195Y522335D03*
X221770Y373780D03*
X217818Y368665D03*
X241215Y374601D03*
X237076Y364113D03*
X239309Y482753D03*
X253960Y135933D03*
X247183Y163107D03*
X253083Y182257D03*
X255643Y192767D03*
X256248Y364633D03*
X257226Y374363D03*
X251856Y373544D03*
X249722Y483208D03*
X244390Y483760D03*
X255055Y483635D03*
X267073Y145007D03*
X263575Y364050D03*
X272031Y374583D03*
X263324Y483388D03*
X283593Y144477D03*
X287993Y364451D03*
X295383Y140527D03*
X293053Y154997D03*
X306782Y292461D03*
X293606Y364305D03*
X314893Y140897D03*
X307574Y149601D03*
X315600Y189807D03*
X307420Y354376D03*
X324393Y146984D03*
X328973Y142937D03*
X335295Y717169D03*
X356515Y683743D03*
X378092Y683915D03*
X399606Y377165D03*
X413386Y363385D03*
X403543Y367322D03*
Y387008D03*
X413386Y390945D03*
X427166Y377165D03*
X423229Y367322D03*
Y387008D03*
X447440Y696900D03*
X461244Y696882D03*
X453940Y697445D03*
X477209Y696918D03*
X466683Y697054D03*
X471768Y696891D03*
X643610Y724087D03*
X643000Y734200D03*
X658050Y672117D03*
X658369Y677774D03*
X659029Y710048D03*
X746000Y475000D03*
G54D12*
X-34986Y133213D03*
X-36758D03*
X-34986Y240533D03*
X-36758D03*
Y746493D03*
X-34986D03*
G54D205*
G01Y240533D02*
Y241487D01*
X-35262Y241763D01*
Y251603D01*
X-27952Y293183D01*
X-52146Y430539D01*
X-43434Y480087D01*
X-56462Y553913D01*
X-41265Y639943D01*
Y641923D01*
G01X-42472D02*
Y640012D01*
X-57681Y553913D01*
X-46718Y491789D01*
X-44654Y480094D01*
X-53366Y430544D01*
X-29171Y293183D01*
X-36444Y251811D01*
X-36462Y251708D01*
Y241783D01*
X-36758Y241487D01*
Y240533D01*
G01X130324Y272096D02*
Y272593D01*
X131032Y273301D01*
X133011D01*
X134505Y272227D01*
X135212Y271318D01*
X136263Y269964D01*
X138540Y267029D01*
X142873Y263703D01*
X145711D01*
X153617Y264986D01*
X156009D01*
Y264987D01*
X163667D01*
X164569Y264085D01*
X166470D01*
X170102Y265191D01*
G01X130324Y277096D02*
Y275335D01*
X131158Y274501D01*
X133398D01*
X135347Y273101D01*
X135854Y272448D01*
X136704Y272343D01*
X137626Y271157D01*
X137517Y270306D01*
X139394Y267887D01*
X140600Y266962D01*
X141333Y267060D01*
X142525Y266145D01*
X142620Y265411D01*
X143281Y264903D01*
X145614D01*
X146378Y265028D01*
X146799Y265611D01*
X148282Y265853D01*
X148865Y265430D01*
X150348Y265672D01*
X150769Y266255D01*
X152252Y266497D01*
X152835Y266074D01*
X153520Y266186D01*
X154809D01*
X155337Y266715D01*
X156837D01*
X157365Y266186D01*
X158749D01*
X158750Y266187D01*
X164165D01*
X165067Y265285D01*
X166218D01*
X166332Y265399D01*
G01X144400Y244061D02*
X145550Y245211D01*
X148797D01*
X150502Y243054D01*
X158177Y236862D01*
X158370Y236797D01*
X158825Y236633D01*
X158840Y236627D01*
X158847Y236609D01*
X158850Y236608D01*
X170205Y235186D01*
X175648D01*
X180218Y239756D01*
Y245238D01*
G01X144400Y247561D02*
X145550Y246411D01*
X149379D01*
X151360Y243904D01*
X158762Y237932D01*
X158765Y237931D01*
X159234Y237761D01*
X159247Y237756D01*
X159250Y237758D01*
X159270Y237765D01*
X170280Y236386D01*
X171083D01*
X171732Y237035D01*
X172922D01*
X173570Y236386D01*
X175150D01*
X176432Y237668D01*
Y238444D01*
X177174Y239186D01*
X177950D01*
X179018Y240254D01*
Y245238D01*
G01X178812Y257697D02*
X175785D01*
X175756Y257668D01*
G01X178812Y265293D02*
X181602Y262656D01*
G01X169684Y255495D02*
X167682D01*
X167322Y255855D01*
G01X168121Y257802D02*
Y260194D01*
X167698Y260617D01*
G01X180312Y275869D02*
Y275907D01*
X178025Y278194D01*
Y279018D01*
G01X174078Y271435D02*
X172672Y272841D01*
X172426D01*
G01X170829Y271452D02*
X172196Y270085D01*
X172426D01*
G01X178812Y268049D02*
X178941Y268178D01*
Y270160D01*
G01X180348Y255062D02*
X179924Y255486D01*
Y256391D01*
X181176Y257643D01*
G01X181812Y265293D02*
X182512Y265993D01*
X183604D01*
X184117Y265480D01*
Y264852D01*
G01X181812Y268049D02*
Y268181D01*
X183440Y269809D01*
Y269816D01*
G01X183312Y275869D02*
Y277920D01*
X183198Y278034D01*
G01X193376Y603043D02*
X195896D01*
X196280Y602659D01*
X199905D01*
X202829Y599735D01*
X208430D01*
G01X193376Y601075D02*
X195896D01*
X196280Y601459D01*
X198210D01*
G01X193376Y606980D02*
X195685D01*
X196080Y607375D01*
X199452D01*
X200742Y606085D01*
X202074D01*
X204024Y604135D01*
G01X193376Y608949D02*
X195556D01*
X195930Y608575D01*
X199950D01*
X201240Y607285D01*
X202174D01*
X204024Y609135D01*
G01X193376Y610917D02*
X195896D01*
X196280Y611301D01*
X199817D01*
X201972Y613456D01*
X206963D01*
X208904Y611515D01*
G01X193376Y612886D02*
X195895D01*
X196280Y612501D01*
X199319D01*
X201474Y614656D01*
X207045D01*
X208904Y616515D01*
G01X198919Y266697D02*
X200811D01*
X201518Y265990D01*
G01X198919Y269697D02*
X200708D01*
X201518Y268887D01*
G01X204724Y317323D02*
X206299Y315748D01*
G01X203058Y315593D02*
X201868Y316783D01*
Y317323D01*
G01X212378Y600957D02*
X211156Y599735D01*
X208430D01*
G01X212378Y596957D02*
X210800Y598535D01*
X202331D01*
X199407Y601459D01*
X198210D01*
G01X215528Y596957D02*
X216796Y598225D01*
X218108D01*
X219960Y596373D01*
G01X215528Y600957D02*
X217060Y599425D01*
X218012D01*
X219960Y601373D01*
G01X238019Y262197D02*
X238127D01*
X239569Y263639D01*
G01X235263Y262197D02*
Y262227D01*
X233793Y263697D01*
G01X235263Y259197D02*
Y259301D01*
X233867Y260697D01*
X233793D01*
G01X238019Y259197D02*
X238127D01*
X239569Y260639D01*
G01X250903Y262197D02*
Y262227D01*
X249433Y263697D01*
G01X250903Y259197D02*
Y259227D01*
X249433Y260697D01*
G01X272999Y501022D02*
X274499Y499522D01*
Y494878D01*
X273532Y493911D01*
Y480036D01*
X283731Y469837D01*
X286755D01*
X287567Y470649D01*
G01X272999Y497872D02*
X273299Y497572D01*
Y495376D01*
X272332Y494409D01*
Y493398D01*
X271746Y492812D01*
Y491312D01*
X272332Y490726D01*
Y489226D01*
X271746Y488640D01*
Y487140D01*
X272332Y486554D01*
Y479538D01*
X274009Y477861D01*
Y477111D01*
X275070Y476050D01*
X275820D01*
X283233Y468637D01*
X286579D01*
X287567Y467649D01*
G01X276149Y497872D02*
X276601Y497420D01*
Y495626D01*
X277118Y495109D01*
Y494150D01*
X277539Y493729D01*
X278498D01*
X278841Y493386D01*
Y492308D01*
X278221Y491688D01*
Y490878D01*
X278841Y490258D01*
Y489445D01*
X278167Y488772D01*
Y487773D01*
X278841Y487099D01*
Y486247D01*
X278185Y485591D01*
Y484091D01*
X278841Y483435D01*
Y481504D01*
X278534Y481197D01*
X277470D01*
G01X276149Y501022D02*
X277801Y498283D01*
Y496124D01*
X280041Y493884D01*
Y482126D01*
X280970Y481197D01*
G01X279298Y497872D02*
Y497197D01*
X286509Y489986D01*
Y484932D01*
X285859Y484282D01*
Y483065D01*
X286509Y482415D01*
Y480499D01*
X285882Y479872D01*
Y478759D01*
X286509Y478132D01*
Y475934D01*
X288740Y473703D01*
X290490D01*
G01X294389Y476239D02*
X293053Y474903D01*
X289238D01*
X287709Y476432D01*
Y483619D01*
G01X279298Y501022D02*
Y499989D01*
X280784Y498503D01*
Y497409D01*
X287709Y490484D01*
Y483619D01*
G01X297539Y476239D02*
X299071Y474707D01*
X302731D01*
X303631Y475607D01*
G01Y472607D02*
X302731Y473507D01*
X299155D01*
X297580Y471932D01*
G01X294430D02*
X292659Y473703D01*
X290490D01*
G01X434882Y261442D02*
X440102D01*
X440537Y261877D01*
X441884D01*
X445628Y265621D01*
Y268311D01*
X446338Y269021D01*
X449360D01*
X449860Y268521D01*
Y267121D01*
G01X434882Y263410D02*
X440102D01*
X440435Y263077D01*
X441386D01*
X444428Y266119D01*
Y268809D01*
X445840Y270221D01*
X449360D01*
X449860Y270721D01*
Y272121D01*
G01X509464Y457144D02*
X507648D01*
X507427Y456923D01*
X502438D01*
X501138Y455623D01*
X493990D01*
X489221Y450854D01*
Y404146D01*
X499109Y394258D01*
Y390565D01*
X497111Y388567D01*
G01X509464Y455569D02*
X507376D01*
X507222Y455723D01*
X502936D01*
X501636Y454423D01*
X494488D01*
X490421Y450356D01*
Y441679D01*
X490937Y441163D01*
Y439663D01*
X490421Y439147D01*
Y437647D01*
X490937Y437131D01*
Y435631D01*
X490421Y435115D01*
Y433615D01*
X490937Y433099D01*
Y431599D01*
X490421Y431083D01*
Y429583D01*
X490937Y429067D01*
Y427567D01*
X490421Y427051D01*
Y425551D01*
X490937Y425035D01*
Y423535D01*
X490421Y423019D01*
Y404644D01*
X500309Y394756D01*
Y390369D01*
X502111Y388567D01*
G01X509464Y460294D02*
X507701D01*
X507472Y460523D01*
X502538D01*
X500938Y458923D01*
X488868D01*
X484400Y454455D01*
Y451746D01*
X484990Y451156D01*
Y449656D01*
X484400Y449066D01*
Y445072D01*
X484910Y444562D01*
Y443062D01*
X484400Y442552D01*
Y441052D01*
X484910Y440542D01*
Y439042D01*
X484400Y438532D01*
Y437032D01*
X484910Y436522D01*
Y435022D01*
X484400Y434512D01*
Y424050D01*
X486300Y422150D01*
G01X509464Y461869D02*
X507791D01*
X507645Y461723D01*
X502040D01*
X500440Y460123D01*
X488370D01*
X483200Y454953D01*
Y424050D01*
X481300Y422150D01*
G01X509464Y468168D02*
X507849D01*
X507704Y468023D01*
X503140D01*
X502040Y466923D01*
X489571D01*
X488683Y466035D01*
X483380D01*
X482880Y466535D01*
Y467935D01*
G01X509464Y466593D02*
X507934D01*
X507704Y466823D01*
X503638D01*
X502538Y465723D01*
X490069D01*
X489181Y464835D01*
X483380D01*
X482880Y464335D01*
Y462935D01*
G01X509464Y472892D02*
X506798D01*
X506610Y472704D01*
X505357D01*
X500938Y477123D01*
X482102D01*
X480118Y479107D01*
G01X509464Y471317D02*
X506797D01*
X506610Y471504D01*
X504859D01*
X500440Y475923D01*
X481934D01*
X480118Y474107D01*
G01X495228Y553447D02*
X492326D01*
X492139Y553634D01*
X491147D01*
X488138Y550625D01*
Y548625D01*
X486638Y547125D01*
X485084D01*
X483209Y545250D01*
G01X495228Y555022D02*
X492428D01*
X492240Y554834D01*
X490649D01*
X486938Y551123D01*
Y549123D01*
X486140Y548325D01*
X485134D01*
X483209Y550250D01*
G01X495228Y559746D02*
X492388D01*
X492209Y559925D01*
X489838D01*
X487838Y557925D01*
X484403D01*
X483838Y557360D01*
Y556148D01*
G01X495228Y561321D02*
X492418D01*
X492222Y561125D01*
X489340D01*
X487340Y559125D01*
X484638D01*
X483838Y559925D01*
Y561148D01*
G01X495228Y577069D02*
X492438D01*
X492250Y576881D01*
X490696D01*
X486638Y572823D01*
Y570223D01*
X485740Y569325D01*
X484638D01*
X483838Y570125D01*
Y571194D01*
G01X495228Y575494D02*
X492438D01*
X492251Y575681D01*
X491194D01*
X487838Y572325D01*
Y569725D01*
X486238Y568125D01*
X484638D01*
X483838Y567325D01*
Y566194D01*
G01X495228Y581793D02*
X492310D01*
X492123Y581980D01*
X489213D01*
X486638Y584555D01*
Y586225D01*
X485738Y587125D01*
G01X495228Y583368D02*
X492341D01*
X492153Y583180D01*
X489711D01*
X487838Y585053D01*
Y586225D01*
X488738Y587125D01*
X490738D01*
G01X513204Y476632D02*
Y479298D01*
X513392Y479486D01*
Y482043D01*
X510430Y485005D01*
Y485011D01*
X509350Y486091D01*
X509342D01*
X508120Y487313D01*
Y498163D01*
X507224Y499059D01*
X506230D01*
G01X514779Y476632D02*
Y479299D01*
X514592Y479486D01*
Y482541D01*
X511630Y485503D01*
Y485509D01*
X509848Y487291D01*
X509840D01*
X509320Y487811D01*
Y498052D01*
X510327Y499059D01*
X511230D01*
G01X495228Y548723D02*
X498140D01*
X499038Y547825D01*
X501338D01*
X503338Y549825D01*
G01X495228Y545573D02*
X498106D01*
X499138Y546605D01*
Y546625D01*
X501538D01*
X503338Y544825D01*
G01X519938Y493125D02*
X520860D01*
X521838Y492147D01*
Y483321D01*
X521238Y482721D01*
Y478608D01*
X521078Y478448D01*
Y476632D01*
G01X524938Y493125D02*
X524134D01*
X523038Y492029D01*
Y482823D01*
X522438Y482223D01*
Y478833D01*
X522653Y478618D01*
Y476632D01*
G01X519503D02*
Y478460D01*
X519338Y478625D01*
Y482923D01*
X518438Y483823D01*
Y487921D01*
X516910Y489449D01*
Y498798D01*
X520323Y502211D01*
X522760D01*
X523418Y501553D01*
X524918D01*
X525576Y502211D01*
X527076D01*
X527734Y501553D01*
X529234D01*
X529892Y502211D01*
X531392D01*
X532050Y501553D01*
X533550D01*
X534208Y502211D01*
X535708D01*
X536366Y501553D01*
X537866D01*
X538524Y502211D01*
X554366D01*
X558172Y506017D01*
X562470D01*
X564370Y504117D01*
G01X517928Y476632D02*
Y478318D01*
X518138Y478528D01*
Y482425D01*
X517238Y483325D01*
Y487423D01*
X515710Y488951D01*
Y499296D01*
X519825Y503411D01*
X553868D01*
X557674Y507217D01*
X562470D01*
X564370Y509117D01*
G01X525474Y515304D02*
X525480D01*
X526870Y516694D01*
Y518640D01*
X526872Y518642D01*
Y520396D01*
X525085Y522183D01*
G01X525474Y512154D02*
X525480D01*
X526870Y510764D01*
Y508905D01*
X528840Y506935D01*
X536615D01*
X541524Y511844D01*
X543700D01*
X544370Y511174D01*
Y510267D01*
G01X510779Y534746D02*
Y530290D01*
X511050Y530019D01*
Y522842D01*
X516330Y517562D01*
Y512563D01*
X515568Y511801D01*
X514430D01*
G01X512354Y534746D02*
Y530290D01*
X512250Y530186D01*
Y523340D01*
X517530Y518060D01*
Y512310D01*
X518039Y511801D01*
X519430D01*
G01X518653Y534746D02*
Y531900D01*
X518466Y531713D01*
Y528158D01*
X519985Y526639D01*
G01X529474Y515304D02*
X529470D01*
X528070Y516704D01*
Y518208D01*
X528074D01*
Y518640D01*
X528072Y518642D01*
Y520894D01*
X524139Y524827D01*
X521797D01*
X519985Y526639D01*
G01X517079Y534746D02*
Y531822D01*
X517266Y531635D01*
Y527660D01*
X521299Y523627D01*
X523641D01*
X525085Y522183D01*
G01X537416Y465018D02*
X539524D01*
X539729Y465223D01*
X542236D01*
X543187Y466174D01*
X570589D01*
X572440Y464323D01*
G01X537416Y466593D02*
X539524D01*
X539694Y466423D01*
X541738D01*
X542689Y467374D01*
X570491D01*
X572440Y469323D01*
G01X538038Y488323D02*
X537117D01*
X536138Y487344D01*
Y483723D01*
X531938Y479523D01*
Y478601D01*
X532101Y478438D01*
Y476632D01*
G01X533038Y488323D02*
X533973D01*
X534938Y487358D01*
Y484221D01*
X530738Y480021D01*
Y478403D01*
X530527Y478192D01*
Y476632D01*
G01X578840Y512108D02*
X576940Y510208D01*
Y508802D01*
X564357Y496219D01*
X533850D01*
X530838Y493207D01*
Y484023D01*
X528738Y481923D01*
Y478564D01*
X528952Y478350D01*
Y476632D01*
G01X573840Y512108D02*
X575740Y510208D01*
Y509300D01*
X563859Y497419D01*
X533352D01*
X529638Y493705D01*
Y484521D01*
X527538Y482421D01*
Y478604D01*
X527377Y478443D01*
Y476632D01*
G01X529474Y512154D02*
X529470D01*
X528070Y510754D01*
Y509403D01*
X529338Y508135D01*
X531104D01*
X531610Y508641D01*
X533110D01*
X533616Y508135D01*
X536117D01*
X537213Y509231D01*
Y509987D01*
X538274Y511048D01*
X539030D01*
X541026Y513044D01*
X543810D01*
X544370Y513604D01*
Y515267D01*
G01X574530Y270863D02*
Y273480D01*
X574718Y274167D01*
Y278761D01*
X572874Y280605D01*
Y299948D01*
X571217Y301605D01*
Y313414D01*
X576240Y318437D01*
X585641D01*
X587980Y320776D01*
Y322370D01*
X587104Y323246D01*
X585984D01*
G01X576105Y270863D02*
Y273593D01*
X575918Y274167D01*
Y279259D01*
X574074Y281103D01*
Y300446D01*
X572417Y302103D01*
Y312916D01*
X576738Y317237D01*
X586139D01*
X589180Y320278D01*
Y322554D01*
X589872Y323246D01*
X590984D01*
G01X585553Y270863D02*
Y273512D01*
X585366Y274167D01*
Y277383D01*
X591774Y283791D01*
Y284989D01*
G01X583979Y270863D02*
Y273644D01*
X584166Y274167D01*
Y276414D01*
G01X589107Y289518D02*
X590574Y288051D01*
Y284289D01*
X584166Y277881D01*
Y276414D01*
G01X577679Y270863D02*
Y273421D01*
X577836Y273956D01*
Y276956D01*
X578514Y277634D01*
Y309582D01*
X576650Y311446D01*
G01X579254Y270863D02*
Y273407D01*
X579036Y273956D01*
Y276458D01*
X579714Y277136D01*
Y309510D01*
X581650Y311446D01*
G01X589107Y292668D02*
X590467Y294028D01*
Y303174D01*
X588607Y305034D01*
G01X588780Y611056D02*
X590624Y612900D01*
X592007D01*
X593362Y611545D01*
G01X588780Y616056D02*
X590736Y614100D01*
X591917D01*
X593362Y615545D01*
G01X593107Y289518D02*
X591774Y288185D01*
Y284989D01*
G01X593107Y292668D02*
X591667Y294108D01*
Y303094D01*
X593607Y305034D01*
G01X593867Y595695D02*
X595724Y597552D01*
X608710D01*
X611334Y600176D01*
X612872D01*
X613256Y599792D01*
X616024D01*
G01X596512Y611545D02*
X597910Y612943D01*
X600696D01*
G01X616024Y605698D02*
X614570D01*
X614015Y605143D01*
X613368D01*
X612936Y605575D01*
X604380D01*
X602314Y607641D01*
G01X616024Y603729D02*
X614340D01*
X614126Y603943D01*
X612870D01*
X612438Y604375D01*
X604048D01*
X602314Y602641D01*
G01X593867Y600695D02*
X595810Y598752D01*
X608210D01*
X610834Y601376D01*
X613120D01*
X613505Y601761D01*
X616024D01*
G01Y609635D02*
X613504D01*
X613120Y610019D01*
X608773D01*
X605849Y612943D01*
X600696D01*
G01X596512Y615545D02*
X597914Y614143D01*
X606347D01*
X609271Y611219D01*
X610796D01*
G01X643071Y395810D02*
X640793D01*
X640608Y395625D01*
X638854D01*
X638688Y395459D01*
X630910D01*
X621617Y391657D01*
X610978D01*
X609078Y393557D01*
G01X643071Y394235D02*
X640938D01*
X640748Y394425D01*
X639352D01*
X639186Y394259D01*
X631146D01*
X621853Y390457D01*
X610978D01*
X609078Y388557D01*
G01X618845Y398052D02*
X617445Y399452D01*
X614615D01*
X612641Y397478D01*
G01X618845Y402052D02*
X617445Y400652D01*
X614467D01*
X612641Y402478D01*
G01X616024Y611603D02*
X613504D01*
X613120Y611219D01*
X610796D01*
G01X643071Y403684D02*
X640893D01*
X640518Y404059D01*
X638750D01*
X635902Y406907D01*
X632591D01*
X630691Y405007D01*
G01X621995Y402052D02*
X623700Y400347D01*
X625835D01*
G01X643071Y400535D02*
X639805D01*
X639617Y400347D01*
X625835D01*
G01X621995Y398052D02*
X623090Y399147D01*
X637543D01*
G01X643071Y405259D02*
X639248D01*
X636400Y408107D01*
X632591D01*
X630691Y410007D01*
G01X643071Y398960D02*
X639804D01*
X639617Y399147D01*
X637543D01*
G54D106*
X193473Y688002D03*
X189733D03*
X185993D03*
Y678356D03*
X193473D03*
X207473Y688002D03*
X203733D03*
X199993D03*
Y678356D03*
X207473D03*
X226993Y688002D03*
Y678356D03*
X220845Y688002D03*
X217105D03*
X213365D03*
Y678356D03*
X220845D03*
X234473Y688002D03*
X230733D03*
X234473Y678356D03*
X240493Y688002D03*
Y678356D03*
X247973Y688002D03*
X244233D03*
X247973Y678356D03*
X257733Y688002D03*
X253993D03*
Y678356D03*
X261473Y688002D03*
Y678356D03*
G54D22*
X13820Y597179D03*
X9820Y605979D03*
X17820D03*
X70796Y258779D03*
X66796Y267579D03*
X74796D03*
X97449Y181016D03*
X93449Y189816D03*
X101449D03*
X175180Y688329D03*
X179180Y679529D03*
X171180D03*
X175689Y715673D03*
X171689Y724473D03*
X179689D03*
X187440Y699556D03*
X183440Y708356D03*
X191440D03*
X197440D03*
X201440Y699556D03*
X205440Y708356D03*
X211440D03*
X215440Y699556D03*
X219440Y708356D03*
X225940D03*
X229940Y699556D03*
X233940Y708356D03*
X244440Y699556D03*
X240440Y708356D03*
X248440D03*
X258940Y699556D03*
X254940Y708356D03*
X262940D03*
X353298Y638032D03*
X357298Y629232D03*
X361298Y638032D03*
X381218Y629998D03*
X373218D03*
X377218Y638798D03*
X430315Y611073D03*
X426315Y619873D03*
X444135Y611073D03*
X440135Y619873D03*
X448135D03*
X434315D03*
X465165Y595260D03*
X457935Y611073D03*
X461165Y604060D03*
X453935Y619873D03*
X461935D03*
X475795Y281667D03*
X479795Y272867D03*
X471795D03*
X479648Y612832D03*
X469165Y604060D03*
X479832Y628841D03*
X483648Y604032D03*
X487648Y612832D03*
X494282Y628836D03*
X483832Y620041D03*
X487832Y628841D03*
X498282Y620036D03*
X502282Y628836D03*
X512238Y620174D03*
X508238Y628974D03*
X526278Y629595D03*
X522278Y620795D03*
X516238Y628974D03*
X530278Y620795D03*
G54D115*
X271890Y432642D03*
G54D40*
X65684Y233920D03*
X65974Y247944D03*
X76210Y163577D03*
X85010Y167577D03*
Y159577D03*
X77944Y181967D03*
X86744Y185967D03*
Y177967D03*
X77944Y195733D03*
X86744Y199733D03*
Y191733D03*
X81873Y209852D03*
X74484Y229920D03*
X81933Y223734D03*
X74484Y237920D03*
X74774Y251944D03*
Y243944D03*
X90733Y219734D03*
X90673Y213852D03*
Y205852D03*
X90733Y227734D03*
X133447Y667464D03*
Y675464D03*
X144203Y15162D03*
X135403Y11162D03*
Y19162D03*
X142247Y671464D03*
X179419Y667816D03*
X170619Y663816D03*
Y671816D03*
X425881Y631477D03*
X434681Y627477D03*
Y635477D03*
X491413Y214434D03*
X482613Y210434D03*
Y218434D03*
X746023Y450832D03*
X737223Y446832D03*
Y454832D03*
G54D133*
X399337Y716398D03*
Y713839D03*
Y711280D03*
X391857D03*
Y713839D03*
Y716398D03*
G54D142*
X428747Y458694D03*
Y474305D03*
G54D31*
X45282Y338300D03*
G54D124*
X336088Y459022D03*
Y492880D03*
X351836Y459022D03*
X349868D03*
X347899D03*
X345931D03*
X343962D03*
X341994D03*
X340025D03*
X338057D03*
Y492880D03*
X340025D03*
X341994D03*
X343962D03*
X345931D03*
X347899D03*
X349868D03*
X351836D03*
X357742Y459022D03*
X355773D03*
X353805D03*
Y492880D03*
X355773D03*
X357742D03*
G54D151*
X456991Y549828D03*
G54D160*
X510779Y534746D03*
X509205D03*
X507630D03*
X506055D03*
X504480D03*
X502905D03*
X501331D03*
Y595770D03*
X502905D03*
X504480D03*
X506055D03*
X507630D03*
X509205D03*
X510779D03*
X526527Y534746D03*
X524953D03*
X523378D03*
X521803D03*
X520228D03*
X518653D03*
X517079D03*
X515504D03*
X513929D03*
X512354D03*
Y595770D03*
X513929D03*
X515504D03*
X517079D03*
X518653D03*
X520228D03*
X521803D03*
X523378D03*
X524953D03*
X526527D03*
X542275Y534746D03*
X540701D03*
X539126D03*
X537551D03*
X535976D03*
X534401D03*
X532827D03*
X531252D03*
X529677D03*
X528102D03*
Y595770D03*
X529677D03*
X531252D03*
X532827D03*
X534401D03*
X535976D03*
X537551D03*
X539126D03*
X540701D03*
X542275D03*
X550149Y534746D03*
X548575D03*
X547000D03*
X545425D03*
X543850D03*
Y595770D03*
X545425D03*
X547000D03*
X548575D03*
X550149D03*
G36*
G01X-32014Y133813D02*
Y131402D01*
G02X-33794Y130113I-858J-689D01*
G01X-34950D01*
G02X-36794I-922J600D01*
G01X-37950D01*
G02X-39730Y131402I-922J600D01*
G01Y133813D01*
X-38030D01*
Y132113D01*
X-33714D01*
Y133813D01*
X-32014D01*
G37*
G36*
G01Y241133D02*
Y238722D01*
G02X-33794Y237433I-858J-689D01*
G01X-34950D01*
G02X-36794I-922J600D01*
G01X-37950D01*
G02X-39730Y238722I-922J600D01*
G01Y241133D01*
X-38030D01*
Y239433D01*
X-33714D01*
Y241133D01*
X-32014D01*
G37*
G54D206*
G01X647414Y412752D02*
Y415579D01*
X646328Y416665D01*
Y425939D01*
X648208Y427819D01*
G01X645840Y413102D02*
Y415399D01*
X645088Y416151D01*
Y425939D01*
X643208Y427819D01*
G01X655642Y144915D02*
X657571Y146844D01*
X658933D01*
X660281Y145496D01*
X662460D01*
G01X666336Y145428D02*
X665431D01*
X665363Y145496D01*
X662460D01*
G01X655642Y149915D02*
X657473Y148084D01*
X658933D01*
X660281Y149432D01*
X662460D01*
G01X666336Y149428D02*
X662464D01*
X662460Y149432D01*
G01X655695Y159567D02*
X657575Y161447D01*
X659343D01*
X660691Y160099D01*
X662673D01*
G01X666649Y160091D02*
X662681D01*
X662673Y160099D01*
G01X666649Y164091D02*
X666593Y164035D01*
X662673D01*
G01D02*
X660691D01*
X659343Y162687D01*
X657575D01*
X655695Y164567D01*
G01X655030Y228744D02*
X656884Y226890D01*
X658971D01*
X660319Y228238D01*
X662294D01*
G01X666313Y228335D02*
X662391D01*
X662294Y228238D01*
G01X655030Y223744D02*
X656936Y225650D01*
X658971D01*
X660319Y224302D01*
X662294D01*
G01X666313Y224335D02*
X662327D01*
X662294Y224302D01*
G01X657838Y243407D02*
X659752Y241493D01*
X661560D01*
X662908Y242841D01*
G01X666899Y242845D02*
X662912D01*
X662908Y242841D01*
G01X657838Y238407D02*
X659684Y240253D01*
X661560D01*
X662908Y238905D01*
G01X666899Y238845D02*
X662968D01*
X662908Y238905D01*
G01X661588Y412752D02*
Y415012D01*
X661459Y415141D01*
Y423721D01*
X663339Y425601D01*
G01X660013Y412752D02*
Y415145D01*
X660219Y415351D01*
Y423721D01*
X658339Y425601D01*
G01X691286Y158536D02*
Y154347D01*
X688430Y151491D01*
Y149781D01*
X685493Y146844D01*
X676421D01*
X675073Y145496D01*
X673484D01*
G01X669486Y145428D02*
X670229D01*
X670297Y145496D01*
X673484D01*
G01X683806Y158536D02*
Y154795D01*
X687190Y151411D01*
Y150295D01*
X684979Y148084D01*
X676421D01*
X675073Y149432D01*
X673484D01*
G01X669486Y149428D02*
X673480D01*
X673484Y149432D01*
G01X723275Y173455D02*
X719895Y170075D01*
X718437D01*
X716743Y168381D01*
Y163012D01*
X715005Y161274D01*
X698656D01*
X696166Y163764D01*
X692162D01*
X690381Y161983D01*
X685329D01*
X683806Y160460D01*
Y158536D01*
G01X673697Y164035D02*
X675483D01*
X676831Y162687D01*
X680251D01*
X681622Y164058D01*
X682493D01*
X683806Y165371D01*
Y168182D01*
G01X669799Y164091D02*
X673641D01*
X673697Y164035D01*
G01Y160099D02*
X675483D01*
X676831Y161447D01*
X680765D01*
X682136Y162818D01*
X683016D01*
X684719Y164521D01*
X689624D01*
X691286Y166183D01*
Y168182D01*
G01X669799Y160091D02*
X673689D01*
X673697Y160099D01*
G01X712975Y173455D02*
X709595Y170075D01*
X705181D01*
X696444Y178812D01*
X689091D01*
X687075Y176796D01*
Y175573D01*
X683806Y172304D01*
Y168182D01*
G01X673318Y224302D02*
X675111D01*
X676459Y225650D01*
X685531D01*
X688468Y228587D01*
Y230297D01*
X691324Y233153D01*
Y237342D01*
G01X669463Y224335D02*
X673285D01*
X673318Y224302D01*
G01Y228238D02*
X675111D01*
X676459Y226890D01*
X685017D01*
X687228Y229101D01*
Y230217D01*
X683844Y233601D01*
Y237342D01*
G01X669463Y228335D02*
X673221D01*
X673318Y228238D01*
G01X691324Y246988D02*
Y244989D01*
X689662Y243327D01*
X684757D01*
X683054Y241624D01*
X682174D01*
X680803Y240253D01*
X675280D01*
X673932Y238905D01*
G01X670049Y238845D02*
X673872D01*
X673932Y238905D01*
G01X723275Y252261D02*
X719895Y248881D01*
X718475D01*
X716781Y247187D01*
Y241818D01*
X715043Y240080D01*
X698694D01*
X696204Y242570D01*
X692200D01*
X690419Y240789D01*
X685367D01*
X683844Y239266D01*
Y237342D01*
G01Y246988D02*
Y244177D01*
X682531Y242864D01*
X681660D01*
X680289Y241493D01*
X675280D01*
X673932Y242841D01*
G01X670049Y242845D02*
X673928D01*
X673932Y242841D01*
G01X712975Y252261D02*
X709595Y248881D01*
X705219D01*
X698111Y255989D01*
X689585D01*
X688538Y254942D01*
X687074D01*
X683844Y251712D01*
Y246988D01*
G01X689527Y412843D02*
X687601Y410917D01*
X677479D01*
X676545Y409983D01*
X674155D01*
G01X689527Y407843D02*
X687693Y409677D01*
X677993D01*
X676725Y408409D01*
X673805D01*
G01X723275Y165455D02*
X719895Y168835D01*
X718951D01*
X717983Y167867D01*
Y162498D01*
X715519Y160034D01*
X698142D01*
X695652Y162524D01*
X692654D01*
X691286Y161156D01*
Y158536D01*
G01X712975Y165455D02*
X709595Y168835D01*
X704667D01*
X695930Y177572D01*
X689605D01*
X688315Y176282D01*
Y175439D01*
X691286Y172468D01*
Y168182D01*
G01X712975Y244261D02*
X709595Y247641D01*
X704705D01*
X697597Y254749D01*
X690099D01*
X689490Y254140D01*
Y253455D01*
X691324Y251621D01*
Y246988D01*
G01X723275Y244261D02*
Y244299D01*
X719933Y247641D01*
X718989D01*
X718021Y246673D01*
Y241304D01*
X715557Y238840D01*
X698180D01*
X695690Y241330D01*
X692692D01*
X691324Y239962D01*
Y237342D01*
G36*
G01X-34847Y238433D02*
G03X-36897I-1025J-400D01*
G01X-37847D01*
G03Y237633I-1025J-400D01*
G01X-36897D01*
G03X-34847I1025J400D01*
G01X-33897D01*
G03Y238433I1025J400D01*
G01X-34847D01*
G37*
G54D32*
X44279Y374032D03*
Y392536D03*
X162364Y720437D03*
Y738941D03*
G54D170*
X557454Y624762D03*
X548793D03*
Y631652D03*
X557454D03*
G54D152*
X451840Y639199D03*
Y641758D03*
Y644317D03*
Y646876D03*
Y649436D03*
Y651995D03*
Y654554D03*
Y657113D03*
Y661699D03*
Y664258D03*
Y666817D03*
Y669376D03*
Y671936D03*
Y674495D03*
Y677054D03*
Y679613D03*
X474840Y644317D03*
Y641758D03*
Y639199D03*
Y657113D03*
Y654554D03*
Y651995D03*
Y649436D03*
Y646876D03*
Y674495D03*
Y671936D03*
Y669376D03*
Y666817D03*
Y664258D03*
Y661699D03*
Y679613D03*
Y677054D03*
X600118Y115098D03*
Y117657D03*
Y120216D03*
Y122775D03*
Y125334D03*
Y127893D03*
Y130452D03*
Y133012D03*
Y135571D03*
Y138130D03*
Y140689D03*
Y143248D03*
Y145807D03*
Y148366D03*
X623118Y122775D03*
Y120216D03*
Y117657D03*
Y115098D03*
Y138130D03*
Y135571D03*
Y133012D03*
Y130452D03*
Y127893D03*
Y125334D03*
Y148366D03*
Y145807D03*
Y143248D03*
Y140689D03*
X627463Y675600D03*
Y678159D03*
Y680718D03*
Y683277D03*
Y685836D03*
Y688395D03*
Y690954D03*
Y693514D03*
Y696073D03*
Y698632D03*
Y701191D03*
Y703750D03*
Y706309D03*
Y708868D03*
X650463Y675600D03*
Y690954D03*
Y688395D03*
Y685836D03*
Y683277D03*
Y680718D03*
Y678159D03*
Y706309D03*
Y703750D03*
Y701191D03*
Y698632D03*
Y696073D03*
Y693514D03*
Y708868D03*
G54D143*
X426950Y492873D03*
G54D23*
X12178Y612129D03*
X9028D03*
X20020Y658951D03*
X31260Y30414D03*
X34410D03*
Y26414D03*
X31260D03*
X38807Y547034D03*
X37197Y597285D03*
X28105Y595792D03*
X24955D03*
X36937Y608125D03*
X35960Y658951D03*
X32810D03*
X23170D03*
X45355Y14588D03*
X42205D03*
X45355Y18588D03*
X42205D03*
X49817Y494570D03*
X52967D03*
X51325Y518072D03*
X48175D03*
X41957Y547034D03*
X44507Y597285D03*
X47657D03*
X40347D03*
X40087Y608125D03*
X53751Y643928D03*
X40317Y658951D03*
X43467D03*
X53751Y648428D03*
X58654Y115158D03*
X61804D03*
X69485Y188946D03*
X60663Y189182D03*
X63813D03*
X57029Y257049D03*
X60179D03*
X66533Y526417D03*
X63383D03*
Y530417D03*
X66533D03*
X58108Y619407D03*
X54958D03*
X58108Y614907D03*
X54958D03*
X56901Y643928D03*
Y648428D03*
X77895Y172605D03*
X74745D03*
X72635Y188946D03*
X85460Y232861D03*
X82310D03*
X80074Y389621D03*
X76924D03*
X80074Y385722D03*
X76924D03*
X80094Y393857D03*
X76944D03*
X80094Y397913D03*
X76944D03*
X79235Y513104D03*
X76085D03*
X79235Y517104D03*
X76085D03*
Y521104D03*
X79235D03*
X99318Y225836D03*
X96168D03*
X95807Y420074D03*
X92657D03*
X110624Y392023D03*
X113774D03*
X110624Y387978D03*
X113774D03*
X109393Y406383D03*
X106243D03*
X132164Y418152D03*
X129014D03*
X132178Y422320D03*
X129028D03*
X129701Y462738D03*
X132851D03*
X129701Y470738D03*
X132851D03*
X129701Y466738D03*
X132851D03*
Y458733D03*
X129701D03*
X118830Y513831D03*
X121980D03*
X121847Y523033D03*
X118697D03*
X121880Y519031D03*
X118730D03*
X130549Y522895D03*
X124467Y675871D03*
X127617D03*
Y670879D03*
X124467D03*
X120953Y665638D03*
X124103D03*
X129184Y729750D03*
X132334D03*
X129184Y725250D03*
X132334D03*
X137232Y43439D03*
X134082D03*
X134086Y39191D03*
X137236D03*
X134151Y47370D03*
X137301D03*
X143677Y76588D03*
X140527D03*
X133539D03*
X136689D03*
X144701Y296735D03*
X141551D03*
X142943Y284987D03*
X146093D03*
X142943Y288987D03*
X146093D03*
Y292987D03*
X142943D03*
X141262Y300625D03*
X144412D03*
X138857Y310543D03*
X142007D03*
X139238Y327933D03*
X142388D03*
X138857Y323543D03*
X142007D03*
X138857Y319043D03*
X142007D03*
X138857Y314543D03*
X142007D03*
X139381Y332046D03*
X142531D03*
X144660Y407428D03*
X141510D03*
X144660Y411428D03*
X141510D03*
X136852Y513804D03*
X133702D03*
X137177Y738726D03*
X140327D03*
X137278Y725173D03*
X140428D03*
X137177Y730726D03*
X140327D03*
X137177Y734726D03*
X140327D03*
X137177Y742726D03*
X140327D03*
X153937Y12151D03*
X150787D03*
X150713Y17718D03*
X153863D03*
X153139Y55906D03*
X156289D03*
X152553Y74863D03*
X149403D03*
X164447Y432521D03*
X164245Y436834D03*
X164774Y441077D03*
Y445034D03*
X167597Y432521D03*
X167395Y436834D03*
X167924Y441077D03*
X173095Y444739D03*
X176245D03*
X167924Y445034D03*
X172654Y477790D03*
X175804D03*
X177038Y643933D03*
X173888D03*
X166388D03*
X169538D03*
X175619Y705976D03*
X172469D03*
X175619Y701976D03*
X172469D03*
X175619Y697976D03*
X172469D03*
X178289Y694040D03*
X175139D03*
X175619Y709976D03*
X172469D03*
X180078Y730521D03*
X176928D03*
X188261Y418925D03*
X185111D03*
X185117Y414885D03*
X188267D03*
X189173Y444392D03*
X186023D03*
X191163Y672526D03*
X194313D03*
X184312Y693887D03*
X187462D03*
X201995Y373701D03*
X198845D03*
X203584Y469953D03*
X200434D03*
Y474253D03*
X203584D03*
X207178Y576893D03*
X204028D03*
X207178Y572893D03*
X204028D03*
Y580893D03*
X207178D03*
Y584893D03*
X204028D03*
Y588893D03*
X207178D03*
X209299Y621977D03*
Y625977D03*
Y629977D03*
Y637977D03*
Y633977D03*
X208882Y671772D03*
X205732D03*
X212378Y596957D03*
X215528D03*
X212378Y600957D03*
X215528D03*
X212449Y621977D03*
Y625977D03*
Y629977D03*
Y637977D03*
Y633977D03*
X219229Y671772D03*
X222379D03*
X242631Y387964D03*
X238077Y439936D03*
X234927D03*
X233017Y671672D03*
X236167D03*
X245781Y387964D03*
X258477Y443592D03*
X255327D03*
X246816Y583156D03*
X243666D03*
X246816Y587156D03*
X243666D03*
X249349Y596382D03*
X246199D03*
X253796Y602262D03*
X256946D03*
X246475Y671772D03*
X249625D03*
X258991Y693945D03*
X255841D03*
X260110Y24932D03*
X263260D03*
X259673Y29229D03*
X262823D03*
X263352Y33472D03*
X260202D03*
X268483Y37453D03*
X271633D03*
X263352Y37429D03*
X260202D03*
X261754Y390871D03*
X264904D03*
X274625Y403203D03*
Y394703D03*
Y399203D03*
X273051Y656491D03*
Y652214D03*
Y648117D03*
Y664156D03*
X259895Y671772D03*
X263045D03*
X273051Y691038D03*
X285703Y6670D03*
X282553D03*
X278653Y6636D03*
X275503D03*
X284601Y36787D03*
X281451D03*
X277775Y403203D03*
Y394703D03*
Y399203D03*
X276201Y656491D03*
Y652214D03*
Y648117D03*
Y664156D03*
Y691038D03*
X285666Y717269D03*
X282516D03*
X301187Y398429D03*
X304337D03*
X294430Y471932D03*
X297580D03*
X294389Y476239D03*
X297539D03*
X301700Y597806D03*
X304850D03*
X302036Y623877D03*
X305186D03*
X300799Y717212D03*
X303949D03*
X296717Y721080D03*
X299867D03*
X316473Y295851D03*
X313323D03*
X313324Y303888D03*
X316474D03*
X313173Y307843D03*
X316323D03*
X316585Y299946D03*
X313435D03*
X319225Y326386D03*
X316075D03*
X316392Y338320D03*
X313242D03*
Y342418D03*
X316392D03*
Y354376D03*
X313242D03*
X316392Y358376D03*
X313242D03*
Y350376D03*
X316392D03*
X313242Y346376D03*
X316392D03*
X311015Y362506D03*
X314165D03*
X320130Y380571D03*
X316980D03*
X316963Y463789D03*
X320113D03*
X320106Y475619D03*
X316956D03*
X315513Y563003D03*
X318663D03*
X316957Y556488D03*
X320107D03*
X316957Y552188D03*
X320107D03*
X312065Y597255D03*
X315215D03*
X333005Y32331D03*
X329855D03*
X327058Y353801D03*
X330208D03*
X327008Y349221D03*
X330158D03*
X322599Y421643D03*
X325749D03*
Y429583D03*
X322599D03*
X325749Y425585D03*
X322599D03*
X325298Y536761D03*
X322949Y597198D03*
X326099D03*
X326723Y609480D03*
X323573D03*
X322949Y601121D03*
X326099D03*
X326628Y605364D03*
X323478D03*
X352578Y69305D03*
X346795Y299266D03*
X343645D03*
X342699Y312712D03*
X345849D03*
X343376Y308727D03*
X346526D03*
X345571Y322472D03*
X342421D03*
X339537Y424850D03*
X342687D03*
X351032Y424560D03*
X345750Y599212D03*
X348900D03*
X353667Y644166D03*
X366175Y15721D03*
X363025D03*
X355728Y69305D03*
X368743Y370508D03*
X354182Y424560D03*
X369484Y543467D03*
X356817Y644166D03*
X359105Y659130D03*
X355955D03*
X359103Y675130D03*
X355953D03*
X359105Y663128D03*
X355955D03*
X359085Y690624D03*
X355935D03*
X359103Y679133D03*
X355953D03*
X355955Y707128D03*
X359105D03*
Y703128D03*
X355955D03*
X359105Y699128D03*
X355955D03*
X359112Y695128D03*
X355962D03*
X360246Y723537D03*
X357096D03*
X359105Y711128D03*
X355955D03*
X369428Y723622D03*
X369336Y731459D03*
X357096Y735537D03*
X360246D03*
Y727537D03*
X357096D03*
X369336Y727459D03*
Y735459D03*
X360246Y739537D03*
X357096D03*
X369336Y739459D03*
X360246Y743537D03*
X357096D03*
X369336Y743459D03*
X374033Y17789D03*
X377183D03*
X371893Y370508D03*
X378061Y467075D03*
X374911D03*
X372634Y543467D03*
X376036Y547579D03*
X372886D03*
X376036Y551579D03*
X372886D03*
X370344Y658121D03*
X373494D03*
X370359Y654157D03*
X373509D03*
X370283Y650156D03*
X373433D03*
X370283Y646156D03*
X373433D03*
X370283Y666156D03*
X373433D03*
X370283Y670156D03*
X373433D03*
X370283Y674214D03*
X373433D03*
X370283Y678222D03*
X373433D03*
X370283Y686248D03*
X373433D03*
X370283Y690248D03*
X373433D03*
X370283Y682248D03*
X373433D03*
X370283Y702248D03*
X373433D03*
X370283Y706248D03*
X373433D03*
X370283Y698248D03*
X373433D03*
X370283Y694248D03*
X373433D03*
X384500Y715442D03*
X372578Y723622D03*
X372486Y731459D03*
Y727459D03*
Y735459D03*
Y739459D03*
Y743459D03*
X385724Y17519D03*
X388874D03*
X392789D03*
X395939D03*
X400589Y69610D03*
X390221Y69643D03*
X393371D03*
X400154Y532016D03*
X400064Y528015D03*
X400026Y524091D03*
X400037Y536127D03*
X400237Y540127D03*
X394293Y597942D03*
X397443D03*
X394599Y624109D03*
X397749D03*
X397743Y628233D03*
X394593D03*
X387650Y715442D03*
X403739Y69610D03*
X403304Y532016D03*
X403214Y528015D03*
X403176Y524091D03*
X416011Y550342D03*
X403187Y536127D03*
X403387Y540127D03*
X405831Y554402D03*
X408981D03*
X416040Y559017D03*
X416022Y554393D03*
X410348Y597288D03*
X407198D03*
X415542Y597300D03*
X416071Y609542D03*
X415542Y601257D03*
X416071Y605500D03*
X408163Y640872D03*
X411313D03*
X416504Y644754D03*
X416419Y652732D03*
Y656883D03*
Y648699D03*
Y673094D03*
Y669027D03*
Y677128D03*
Y681122D03*
X406646Y713835D03*
X403496D03*
X428204Y507319D03*
X431354D03*
X431006Y511581D03*
X427856D03*
X419161Y550342D03*
X419190Y559017D03*
X419172Y554393D03*
X424324Y566125D03*
X427474D03*
X431417Y587579D03*
X418692Y597300D03*
X419221Y609542D03*
X418692Y601257D03*
X425151Y604520D03*
X428301D03*
X432169D03*
X419221Y605500D03*
X428311Y640680D03*
X425161D03*
X419654Y644754D03*
X426270Y646100D03*
X429420D03*
X419569Y652732D03*
Y656883D03*
Y648699D03*
Y673094D03*
Y669027D03*
X422935Y685427D03*
X426085D03*
X419569Y677128D03*
Y681122D03*
X417427Y704664D03*
X420577D03*
Y696713D03*
X417427D03*
X420577Y700669D03*
X417427D03*
X447026Y184438D03*
X447760Y249404D03*
X447426Y245162D03*
Y241162D03*
Y237162D03*
X445190Y526518D03*
X448340D03*
X436290Y553337D03*
X439440D03*
X434567Y587579D03*
X435319Y604520D03*
X440040Y605071D03*
X443190D03*
X439642Y642843D03*
X442792D03*
X438863Y655595D03*
X442013D03*
Y651595D03*
X438863D03*
X439636Y646871D03*
X442786D03*
X442015Y667628D03*
X438865D03*
X442015Y671628D03*
X438865D03*
X442015Y675628D03*
X438865D03*
X442015Y679628D03*
X438865D03*
X461617Y74997D03*
X454582Y74774D03*
X457732D03*
X454433Y69194D03*
X457583D03*
X461791Y102736D03*
X458641D03*
X450176Y184438D03*
X450910Y249404D03*
X460351Y249696D03*
X457201D03*
X450576Y245162D03*
Y241162D03*
Y237162D03*
X450184Y257495D03*
X453334D03*
X456045Y513410D03*
X452895D03*
X452841Y532359D03*
X449691D03*
X449692Y538085D03*
X452842D03*
X456687Y543563D03*
X459837D03*
X459793Y539443D03*
X456643D03*
X463345Y581679D03*
X464767Y74997D03*
X467630Y98747D03*
X464480D03*
X467626Y94743D03*
X464476D03*
X470570Y163503D03*
X467420D03*
X470623Y157235D03*
X467473D03*
X466495Y581679D03*
X469992Y613207D03*
X466842D03*
X491304Y227953D03*
X488154D03*
X484992Y223746D03*
X488142D03*
X492157Y242877D03*
X495307D03*
X487013Y539525D03*
X483863D03*
X485465Y643604D03*
X488615D03*
X486806Y634796D03*
X483656D03*
X485363Y639623D03*
X488513D03*
X490623Y634603D03*
X493773D03*
X485465Y655604D03*
X488615D03*
X485465Y651604D03*
X488615D03*
Y647604D03*
X485465D03*
Y675604D03*
X488615D03*
X485465Y671604D03*
X488615D03*
X485465Y667604D03*
X488615D03*
X485465Y679628D03*
X488615D03*
X493447Y706582D03*
Y714582D03*
Y718582D03*
Y710582D03*
X496123Y230820D03*
X499273D03*
X505430Y436725D03*
X508580D03*
X497745Y449761D03*
X500895D03*
X497818Y445294D03*
X500968D03*
X509230Y441125D03*
X500763Y613598D03*
X503913D03*
X507551Y634818D03*
X504401D03*
Y638780D03*
X507551D03*
X498060Y660178D03*
X501210D03*
X500185Y650626D03*
X497035D03*
X500174Y646569D03*
X497024D03*
X496855Y687669D03*
X500005D03*
X496597Y706582D03*
Y714582D03*
Y718582D03*
Y710582D03*
X515780Y436725D03*
X512630D03*
X512380Y441125D03*
X515280Y609042D03*
X512130D03*
X521613Y615387D03*
X524763D03*
X516939Y634449D03*
X513789D03*
X541660Y211632D03*
X540132Y234993D03*
Y238993D03*
Y246993D03*
Y242993D03*
X535631Y624227D03*
X538781D03*
X535631Y620227D03*
X538781D03*
X544810Y211632D03*
X543282Y234993D03*
Y238993D03*
Y246993D03*
Y242993D03*
X548347Y274262D03*
X545197D03*
X550545Y292524D03*
X547395D03*
X550245Y296824D03*
X547095D03*
X550245Y301124D03*
X547095D03*
X553840Y439007D03*
X550690D03*
X550671Y443048D03*
X553821D03*
X550965Y460656D03*
X554115D03*
X550865Y456156D03*
X554015D03*
X548784Y617102D03*
X545634D03*
X572363Y103123D03*
X564984Y210682D03*
X561834D03*
X564984Y214682D03*
X561834D03*
X563615Y460956D03*
X560465D03*
X563515Y456156D03*
X560365D03*
X564213Y528325D03*
X561063D03*
X564213Y532225D03*
X561063D03*
Y524325D03*
X564213D03*
X568963Y545425D03*
X572113D03*
Y540825D03*
X568963D03*
Y552025D03*
X572113D03*
X569063Y559825D03*
X572213D03*
X568963Y555925D03*
X572113D03*
X568963Y567725D03*
X572113D03*
X568963Y571725D03*
X572113D03*
X568263Y575625D03*
X571413D03*
X568263Y579525D03*
X571413D03*
X568463Y591325D03*
X571613D03*
X568363Y583525D03*
X571513D03*
X568363Y587425D03*
X571513D03*
X575513Y103123D03*
X587043Y117732D03*
X587315Y121836D03*
X587043Y132232D03*
Y128232D03*
X586661Y171906D03*
X589811D03*
X586586Y179955D03*
X589736D03*
X586661Y175906D03*
X589811D03*
X585013Y540625D03*
X581863D03*
Y545225D03*
X585013D03*
X584413Y559445D03*
X581263D03*
X584483Y555235D03*
X581333D03*
X578873Y567253D03*
X582023D03*
X584736Y657848D03*
X581586D03*
X588768Y653385D03*
X584552Y686026D03*
X581402D03*
X584535Y690080D03*
X581385D03*
X584535Y694080D03*
X581385D03*
X603043Y104732D03*
X590193Y117732D03*
X590465Y121836D03*
X590193Y132232D03*
Y128232D03*
X598999Y236295D03*
X602149D03*
X599132Y271893D03*
X602282D03*
Y276393D03*
X599132D03*
X602976Y532108D03*
X599826D03*
Y544108D03*
X602976D03*
X599826Y540108D03*
X602976D03*
X599826Y536108D03*
X602976D03*
X599490Y578903D03*
X602640D03*
X599490Y574903D03*
X602640D03*
X599490Y582903D03*
X602640D03*
Y586903D03*
X599490D03*
X602607Y591105D03*
X599457D03*
X596512Y611545D03*
X593362D03*
X596512Y615545D03*
X593362D03*
X591918Y653385D03*
X610543Y104732D03*
X613693D03*
X618623Y104704D03*
X606193Y104732D03*
X610066Y261804D03*
X613216D03*
X610066Y257804D03*
X613216D03*
X618845Y402052D03*
Y398052D03*
X616829Y546764D03*
X619979D03*
X610044Y655572D03*
X606894D03*
Y650572D03*
X610044D03*
Y660572D03*
X606894D03*
X618059Y675183D03*
X614909D03*
X621773Y104704D03*
X633074Y132241D03*
X636224D03*
X634193Y289089D03*
X637343D03*
X626977Y292591D03*
X630127D03*
X634212Y285042D03*
X637362D03*
X630128Y296525D03*
X626978D03*
X626977Y288469D03*
X630127D03*
X631528Y387178D03*
X628378D03*
X633005Y383132D03*
X629855D03*
X621995Y402052D03*
Y398052D03*
X629708Y418774D03*
X626558D03*
X635286Y516730D03*
X632362Y568745D03*
X635512D03*
X645608Y288706D03*
X648758D03*
X648782Y284699D03*
X646013Y354885D03*
X642863D03*
X642963Y349785D03*
X646113D03*
X642114Y465888D03*
X638964D03*
Y461888D03*
X642114D03*
X638964Y457888D03*
X642114D03*
X638436Y516730D03*
X643012Y568745D03*
X639862D03*
X651226Y660492D03*
Y655072D03*
Y650072D03*
Y645072D03*
Y716674D03*
X648076D03*
X651226Y720674D03*
X648076D03*
X651226Y724674D03*
X648076D03*
X651226Y728674D03*
X648076D03*
X666336Y149428D03*
Y145428D03*
X666649Y164091D03*
Y160091D03*
X666313Y228335D03*
Y224335D03*
X666899Y242845D03*
Y238845D03*
X658272Y311365D03*
X655122D03*
X660861Y369552D03*
X664011D03*
X667861D03*
X654855Y470065D03*
X658005D03*
X657905Y487265D03*
X654755D03*
X657936Y482930D03*
X654786D03*
X657936Y478630D03*
X654786D03*
X658005Y491665D03*
X654855D03*
X661848Y617431D03*
X664998D03*
X654376Y660492D03*
Y655072D03*
Y650072D03*
Y645072D03*
X669486Y149428D03*
Y145428D03*
X669799Y164091D03*
Y160091D03*
X672020Y185259D03*
X675170D03*
X669463Y228335D03*
Y224335D03*
X670049Y242845D03*
Y238845D03*
X671011Y369552D03*
X678264Y369598D03*
X675114D03*
X672248Y532470D03*
X675398D03*
X678159Y519375D03*
X675009D03*
X672248Y540752D03*
X675398D03*
Y536752D03*
X672248D03*
Y544752D03*
X675398D03*
X672248Y548752D03*
X675398D03*
X693962Y145071D03*
X697112D03*
X693962Y149571D03*
X697112D03*
X698050Y216868D03*
X694900D03*
X698050Y221368D03*
X694900D03*
X707736Y513230D03*
X704586D03*
X712820Y513434D03*
X715970D03*
X701023Y549815D03*
X704173D03*
X703151Y535399D03*
X706301D03*
X731507Y460479D03*
X731670Y467368D03*
X731227Y500100D03*
X731425Y496000D03*
X731227Y504054D03*
X716586Y535030D03*
X719736D03*
X728875Y682700D03*
X725725D03*
X728975Y690800D03*
X725825D03*
X728875Y686700D03*
X725725D03*
X728975Y698800D03*
X725825D03*
X728975Y694800D03*
X725825D03*
X728975Y702800D03*
X725825D03*
X724325Y707800D03*
X727475D03*
X724325Y719800D03*
X727475D03*
X724325Y715800D03*
X727475D03*
X724325Y711800D03*
X727475D03*
X724325Y727800D03*
X727475D03*
X724325Y723800D03*
X727475D03*
X734657Y460479D03*
X734820Y467368D03*
X736954Y483641D03*
X740104D03*
X736976Y478975D03*
X740126D03*
X736925Y475000D03*
X740075D03*
X736835Y487639D03*
X739985D03*
X745075Y496800D03*
X741925D03*
X734377Y500100D03*
X741925Y501000D03*
X745075D03*
X734575Y496000D03*
X739425Y492500D03*
X742575D03*
X734377Y504054D03*
X737675Y641829D03*
X740825D03*
X737675Y653829D03*
X740825D03*
X737675Y649829D03*
X740825D03*
X737675Y645829D03*
X740825D03*
X754998Y446532D03*
X751848D03*
X754998Y455532D03*
X751848D03*
X754998Y451032D03*
X751848D03*
X755075Y475000D03*
X751925D03*
Y479000D03*
X755075D03*
X752075Y492500D03*
X748925D03*
Y488500D03*
X752075D03*
X761984Y559513D03*
X758834D03*
G54D50*
X68489Y603914D03*
Y608914D03*
Y613914D03*
Y623914D03*
Y628914D03*
Y618914D03*
Y633914D03*
Y638914D03*
Y643914D03*
Y653914D03*
Y658914D03*
Y648914D03*
X103725Y603914D03*
Y608914D03*
Y613914D03*
Y623914D03*
Y628914D03*
Y618914D03*
Y633914D03*
Y638914D03*
Y643914D03*
Y653914D03*
Y658914D03*
Y648914D03*
G54D116*
X266383Y636830D03*
G54D161*
X514780Y28803D03*
X524780D03*
X514780Y38803D03*
X524780D03*
X534780Y28803D03*
X544780D03*
X534780Y38803D03*
X544780D03*
X554780Y28803D03*
X577371D03*
X587371D03*
X577371Y38803D03*
X587371D03*
X597371Y28803D03*
X607371D03*
X597371Y38803D03*
X607371D03*
X617371Y28803D03*
X639963D03*
Y38803D03*
X649963Y28803D03*
Y38803D03*
X659963Y28803D03*
X669963D03*
X659963Y38803D03*
X669963D03*
X679963Y28803D03*
G54D125*
X329986Y465124D03*
Y467093D03*
Y469061D03*
Y471030D03*
Y472998D03*
Y474967D03*
Y476935D03*
Y478904D03*
Y480872D03*
Y482841D03*
Y484809D03*
Y486778D03*
X363844Y471030D03*
Y469061D03*
Y467093D03*
Y465124D03*
Y486778D03*
Y484809D03*
Y482841D03*
Y480872D03*
Y478904D03*
Y476935D03*
Y474967D03*
Y472998D03*
G54D134*
X414961Y98622D03*
G54D107*
G01X18603Y611764D02*
X16634D01*
X15850Y610980D01*
G01X33841Y9183D02*
X34341Y9683D01*
Y12883D01*
G01X39740Y28062D02*
X37674D01*
X35322Y30414D01*
X34724D01*
G01D02*
X36588Y32278D01*
G01X36848Y25198D02*
X35632Y26414D01*
X34410D01*
G01X31782Y20757D02*
Y25892D01*
X31260Y26414D01*
G01X34724Y30414D02*
X34410D01*
G01X38349Y561223D02*
Y555730D01*
G01X35862Y622914D02*
Y617052D01*
G01X40087Y608125D02*
Y615097D01*
X38421Y616763D01*
Y622914D01*
G01X41957Y547034D02*
Y550787D01*
X40908Y551836D01*
Y561223D01*
G01X57040Y79540D02*
Y73421D01*
G01X62981Y69712D02*
X59599Y73094D01*
Y79540D01*
G01X74470Y175666D02*
X73585D01*
X71730Y177521D01*
Y177594D01*
G01X71758Y222064D02*
X71750Y222072D01*
Y224748D01*
X72150Y225148D01*
G01X98840Y218734D02*
Y221193D01*
X96990Y223043D01*
G01X106517Y204167D02*
Y210796D01*
G01X162317Y249877D02*
X162407Y249967D01*
X164830D01*
X164920Y249877D01*
G01Y253205D02*
X163000D01*
X161918Y254287D01*
G01X164920Y259605D02*
X160449D01*
G01X161918Y293869D02*
X163436Y292351D01*
X164375D01*
G01X164418Y348187D02*
X164920Y347685D01*
Y343641D01*
G01X166646Y484538D02*
X163377D01*
G01X157611Y517180D02*
X153973D01*
X153967Y517186D01*
G01X157611Y510881D02*
X154543D01*
X154038Y511386D01*
G01X149477Y532733D02*
X150180Y533436D01*
X155400D01*
G01X157611Y554975D02*
Y557468D01*
G01X168308Y82480D02*
Y88412D01*
G01X167127Y114763D02*
Y120603D01*
G01X174213Y114763D02*
Y120569D01*
G01X174138Y243873D02*
Y244359D01*
X174518Y244739D01*
X174520D01*
Y246805D01*
G01X171320D02*
X174520D01*
G01X171320Y243601D02*
Y246805D01*
G01X167467Y243242D02*
X168120Y243895D01*
Y246805D01*
G01X164920Y249877D02*
Y250005D01*
G01Y253205D02*
X168120D01*
G01X171320D02*
X171899D01*
X173561Y254867D01*
G01X169684Y340535D02*
X168154D01*
X167383Y341306D01*
G01X168120Y343641D02*
X164920D01*
G01X168120D02*
X171320D01*
G01X167383Y341306D02*
X168120Y342043D01*
Y343641D01*
G01X171320Y350041D02*
X170719Y350642D01*
X168110D01*
G01X171320Y346841D02*
Y350041D01*
G01X177672Y358103D02*
X176016D01*
X174520Y356607D01*
Y350041D01*
G01X177720D02*
Y352522D01*
G01X168110Y350642D02*
X168120Y350632D01*
Y346841D01*
G01X173892Y482546D02*
X173890D01*
X172650Y481306D01*
Y477790D01*
G01X174063Y525054D02*
X171606Y527511D01*
G01X188387Y114763D02*
Y119545D01*
X186730Y121202D01*
G01X186925Y355812D02*
X188217D01*
X189496Y354533D01*
Y348839D01*
G01X181470Y487664D02*
X185747D01*
G01X204724Y295273D02*
X203658D01*
X202303Y296628D01*
Y299136D01*
X202525Y299358D01*
G01X207874Y311023D02*
X209449Y312598D01*
G01X201267Y386396D02*
Y380168D01*
X197938Y376839D01*
G01X220276Y82480D02*
Y88440D01*
G01X236776Y508891D02*
X238354Y510469D01*
Y510471D01*
G01X235204D02*
X233626Y508893D01*
Y508891D01*
G01X238354Y513620D02*
Y513618D01*
X236776Y512040D01*
G01X232054Y510471D02*
Y510469D01*
X230476Y508891D01*
G01X238354Y516770D02*
Y516768D01*
X236776Y515190D01*
G01X241503Y519919D02*
Y519917D01*
X239925Y518339D01*
G01X241503Y523069D02*
Y523067D01*
X239925Y521489D01*
G01X241503Y532518D02*
X241494D01*
X239925Y534087D01*
G01X241503Y541967D02*
X241494D01*
X239925Y543536D01*
G01X241503Y538817D02*
X241494D01*
X239925Y540386D01*
G01X241503Y535667D02*
X241494D01*
X239925Y537236D01*
G01X246073Y92197D02*
X249350Y88920D01*
Y82480D01*
X253347D01*
G01X259443Y120773D02*
X259253Y120583D01*
Y114763D01*
G01X244118Y309387D02*
X245674Y310943D01*
Y311023D01*
G01X254102Y513620D02*
Y513618D01*
X252524Y512040D01*
G01X257251Y513620D02*
Y513618D01*
X255673Y512040D01*
G01X252524Y527789D02*
X254102Y529367D01*
Y529368D01*
G01X252524Y524639D02*
X254102Y526217D01*
Y526219D01*
G01X255673Y534088D02*
X257243Y532518D01*
X257251D01*
G01X252524Y534088D02*
X254094Y532518D01*
X254102D01*
G01X249374Y534088D02*
X250944Y532518D01*
X250952D01*
G01X255673Y524639D02*
X257251Y526217D01*
Y526219D01*
G01X255673Y527789D02*
X257251Y529367D01*
Y529368D01*
G01X249374Y527789D02*
X250952Y529367D01*
Y529368D01*
G01X249374Y524639D02*
X250952Y526217D01*
Y526219D01*
G01X255673Y537237D02*
X257243Y535667D01*
X257251D01*
G01X249374Y537237D02*
X250944Y535667D01*
X250952D01*
G01X252524Y537237D02*
X254094Y535667D01*
X254102D01*
G01X255673Y540387D02*
X257243Y538817D01*
X257251D01*
G01X249374Y540387D02*
X250944Y538817D01*
X250952D01*
G01X252524Y540387D02*
X254094Y538817D01*
X254102D01*
G01X257251Y548266D02*
X257242D01*
X255673Y549835D01*
G01X254102Y548266D02*
X254093D01*
X252524Y549835D01*
G01X249344Y556134D02*
X249374D01*
X250943Y554565D01*
X250952D01*
G01Y557715D02*
X250955D01*
X252554Y559314D01*
G01X260434Y82480D02*
Y77202D01*
X261750Y75886D01*
G01X267520Y76976D02*
X268080Y76416D01*
G01X267520Y82480D02*
Y76976D01*
G01X268702Y114763D02*
Y107928D01*
G01X269299Y265197D02*
X269874D01*
X271898Y263173D01*
G01D02*
X270922Y262197D01*
X269299D01*
G01X269850Y501022D02*
Y500993D01*
X271402Y499441D01*
G01X269850Y513620D02*
Y513612D01*
X271422Y512040D01*
G01X266700Y513620D02*
Y513612D01*
X268272Y512040D01*
G01X272999Y504171D02*
X273002D01*
X274582Y502591D01*
G01X261972Y521489D02*
X260401Y523060D01*
Y523069D01*
G01X268272Y534088D02*
X266702Y532518D01*
X266700D01*
G01X265122Y534088D02*
X263552Y532518D01*
X263550D01*
G01X261972Y534088D02*
X260402Y532518D01*
X260401D01*
G01X268272Y524639D02*
X266700Y526211D01*
Y526219D01*
G01X268272Y527789D02*
X266700Y529361D01*
Y529368D01*
G01X265122Y527789D02*
X263550Y529361D01*
Y529368D01*
G01X265122Y524639D02*
X263550Y526211D01*
Y526219D01*
G01X261972Y524639D02*
X260401Y526210D01*
Y526219D01*
G01X261972Y527789D02*
X260401Y529360D01*
Y529368D01*
G01X268272Y521489D02*
X266700Y523061D01*
Y523069D01*
G01X265122Y521489D02*
X263550Y523061D01*
Y523069D01*
G01X268272Y540387D02*
X266702Y538817D01*
X266700D01*
G01X265122Y540387D02*
X263552Y538817D01*
X263550D01*
G01X261972Y540387D02*
X260402Y538817D01*
X260401D01*
G01X265122Y537237D02*
X263552Y535667D01*
X263550D01*
G01X268272Y537237D02*
X266702Y535667D01*
X266700D01*
G01X261972Y537237D02*
X260402Y535667D01*
X260401D01*
G01X269850Y548266D02*
X269851D01*
X271421Y549836D01*
G01X266700Y548266D02*
X266702D01*
X268272Y549836D01*
G01X276969Y82480D02*
Y76247D01*
G01X286418Y82480D02*
Y77742D01*
X285543Y76867D01*
G01X287599Y114763D02*
Y108831D01*
G01X278880Y108482D02*
X278150Y109212D01*
Y114763D01*
G01X284024Y534092D02*
X282450Y532518D01*
X282448D01*
G01X276149D02*
X276151D01*
X277725Y534092D01*
G01Y527792D02*
X276149Y529368D01*
G01Y526219D02*
X276152D01*
X277725Y527792D01*
G01X276149Y535667D02*
X276151D01*
X277725Y537241D01*
G01X276149Y541967D02*
X276151D01*
X277725Y543541D01*
G01X276149Y538817D02*
X276151D01*
X277725Y540391D01*
G01X295867Y82480D02*
Y76567D01*
G01X302953Y82480D02*
Y76167D01*
G01X297048Y114763D02*
Y119188D01*
X299149Y121289D01*
X299590D01*
G01X304135Y114763D02*
Y120423D01*
X299850Y124708D01*
G01X302870Y633981D02*
Y634088D01*
X303870Y635088D01*
Y636749D01*
X306884Y639763D01*
X307574D01*
G01X321851Y76887D02*
Y82480D01*
G01X312402D02*
Y76587D01*
G01X321283Y76327D02*
X321291D01*
X321851Y76887D01*
G01X329643Y89887D02*
X329638D01*
X328938Y89187D01*
Y82480D01*
G01X336024D02*
Y88176D01*
G01X343111Y82480D02*
Y88429D01*
G01X350198Y82480D02*
Y88277D01*
G01X344073Y124397D02*
X342103D01*
X339568Y121862D01*
Y114763D01*
G01X344073Y124397D02*
X344074D01*
X346654Y121817D01*
Y114763D01*
G01X355955Y707128D02*
X352138D01*
X351810Y706800D01*
G01X359646Y82480D02*
Y88174D01*
G01X366733Y82480D02*
Y88477D01*
G01X367914Y114763D02*
Y120469D01*
X367560Y120823D01*
G01X365070Y658065D02*
X364393D01*
X362615Y656287D01*
X360718D01*
X359105Y657900D01*
Y659130D01*
G01X373820Y82480D02*
Y88400D01*
G01X380906Y82480D02*
Y88134D01*
G01X377363Y114763D02*
Y121108D01*
G01X402166Y82480D02*
Y76580D01*
X400583Y74997D01*
Y69610D01*
G01X397790D02*
X400583D01*
G01D02*
X400589D01*
G01X397442Y82480D02*
Y90667D01*
G01X399804Y82480D02*
Y88778D01*
G01X387993Y82480D02*
Y87832D01*
X389393Y89232D01*
X389400D01*
G01X400237Y540127D02*
X396048D01*
G01X400037Y536127D02*
X395922D01*
G01X409149Y71906D02*
X406891Y74164D01*
Y82480D01*
G01X404528D02*
Y88702D01*
G01X408072Y114763D02*
Y109146D01*
G01X411608Y510870D02*
Y510054D01*
X409985Y508431D01*
G01X408163Y640872D02*
X405462D01*
X403970Y642364D01*
G01X403101Y636875D02*
Y641495D01*
X403970Y642364D01*
G01X432152Y562248D02*
X432138Y562262D01*
X428060D01*
G01D02*
Y565539D01*
X427474Y566125D01*
G01X432152Y562248D02*
X436184D01*
X436219Y562283D01*
G01X432351Y554083D02*
Y554608D01*
X434187Y556444D01*
G01X428039Y554099D02*
Y556539D01*
G01X423845Y554123D02*
Y556519D01*
X423861Y556535D01*
G01X431417Y587579D02*
Y588392D01*
X435080Y592055D01*
G01X445729Y534196D02*
X447530D01*
X448329Y534995D01*
G01X448340Y526518D02*
Y524447D01*
X447781Y523888D01*
G01X436219Y562283D02*
X439887D01*
X441326Y560844D01*
Y556050D01*
G01X435080Y592055D02*
Y593683D01*
X437540Y596143D01*
X459343D01*
X462300Y599100D01*
G01X472600D02*
X473300Y599800D01*
X480900D01*
X481500Y599200D01*
X485600D01*
X487300Y600900D01*
Y602886D01*
X490600Y606186D01*
Y608136D01*
G01X452842Y538085D02*
Y539872D01*
X454022Y541052D01*
G01X474860Y581398D02*
X477798D01*
X481900Y585500D01*
Y590100D01*
X484900Y593100D01*
X486400D01*
X488700Y595400D01*
Y596560D01*
X489700Y597560D01*
Y600140D01*
X489760Y600200D01*
X489800D01*
G01X466495Y581679D02*
X474579D01*
X474860Y581398D01*
G01X488142Y223746D02*
Y217705D01*
X491413Y214434D01*
G01X488154Y227953D02*
Y223758D01*
X488142Y223746D01*
G01X491540Y739081D02*
Y736090D01*
X491890Y735740D01*
G01X495840Y739081D02*
Y736312D01*
X496000Y736152D01*
G01X504940Y727581D02*
Y725297D01*
X506105Y724132D01*
G01X526440Y434581D02*
Y432077D01*
G01X520940Y739081D02*
Y737181D01*
X519440Y735681D01*
G01X512140Y739081D02*
Y736554D01*
G01X531440Y434581D02*
Y432178D01*
G01X529940Y739081D02*
Y737804D01*
X528440Y736304D01*
Y735681D01*
G01X555148Y735583D02*
X555440Y735875D01*
Y739081D01*
G01X587040Y688218D02*
Y688220D01*
X585180Y690080D01*
X584535D01*
G01Y694080D02*
X586995D01*
G01X621344Y683277D02*
X627463D01*
G01X617242Y679547D02*
X621263D01*
X622434Y680718D01*
X627463D01*
G01X634251Y683493D02*
X634028Y683270D01*
X627463D01*
Y683277D01*
G01X654376Y655072D02*
X657550D01*
G01X687049Y467975D02*
X689017Y469943D01*
G01X698860Y467975D02*
X696892Y469943D01*
X696891D01*
G01X698860Y471912D02*
X696891Y473881D01*
G01X690986Y471912D02*
X692955Y473881D01*
G01X698860Y479786D02*
X696891Y477817D01*
G01X698860Y483723D02*
X696892Y481755D01*
X696891D01*
G01X689700Y774500D02*
X695300D01*
X699800Y770000D01*
Y762800D01*
X710100Y752500D01*
X717100D01*
X719500Y750100D01*
Y747000D01*
G01X699600Y776000D02*
X704900D01*
X708300Y772600D01*
Y766600D01*
X715300Y759600D01*
X730600D01*
X735900Y754300D01*
Y702000D01*
G01X704000Y770800D02*
Y763800D01*
X711800Y756000D01*
X728000D01*
X733300Y750700D01*
Y733000D01*
X731700Y731400D01*
X722000D01*
X720300Y729700D01*
Y718700D01*
G01X735900Y695300D02*
Y702000D01*
G01X733000Y692400D02*
X735900Y695300D01*
X204724Y279523D03*
X207874D03*
X211024D03*
X204724Y282673D03*
Y285823D03*
Y288973D03*
Y292123D03*
Y295273D03*
X207874Y282673D03*
Y285823D03*
Y288973D03*
Y292123D03*
Y295273D03*
X211024Y282673D03*
Y285823D03*
Y288973D03*
Y292123D03*
Y295273D03*
X204724Y301573D03*
Y298423D03*
Y311023D03*
Y307873D03*
Y304723D03*
X207874Y301573D03*
Y298423D03*
Y311023D03*
Y307873D03*
Y304723D03*
X211024Y301573D03*
Y298423D03*
Y311023D03*
Y307873D03*
Y304723D03*
X204724Y314173D03*
X207874Y317323D03*
Y314173D03*
X211024Y317323D03*
Y314173D03*
X204724Y317323D03*
X223624Y279523D03*
X220474D03*
X214174D03*
X217324D03*
X226774D03*
X223624Y282673D03*
X220474D03*
X217324D03*
X214174D03*
X223624Y285823D03*
Y288973D03*
Y292123D03*
Y295273D03*
X220474Y285823D03*
Y288973D03*
Y292123D03*
Y295273D03*
X217324Y285823D03*
Y288973D03*
Y292123D03*
Y295273D03*
X214174Y285823D03*
Y288973D03*
Y292123D03*
Y295273D03*
X226774Y282673D03*
Y295273D03*
Y292123D03*
Y288973D03*
Y285823D03*
X223624Y301573D03*
Y298423D03*
X220474Y301573D03*
Y298423D03*
X217324Y301573D03*
Y298423D03*
X214174Y301573D03*
Y298423D03*
X223624Y311023D03*
Y307873D03*
Y304723D03*
X220474Y311023D03*
Y307873D03*
Y304723D03*
X217324Y311023D03*
Y307873D03*
Y304723D03*
X214174Y311023D03*
Y307873D03*
Y304723D03*
X226774Y298423D03*
Y301573D03*
Y304723D03*
Y307873D03*
Y311023D03*
X223624Y317323D03*
Y314173D03*
X220474Y317323D03*
Y314173D03*
X217324Y317323D03*
Y314173D03*
X214174Y317323D03*
Y314173D03*
X226774D03*
Y317323D03*
X229924Y279523D03*
X236224D03*
X233074D03*
X242524D03*
X239374D03*
X229924Y282673D03*
X236224D03*
X233074D03*
X242524D03*
X239374D03*
X229924Y295273D03*
Y292123D03*
Y288973D03*
Y285823D03*
X236224D03*
Y288973D03*
Y292123D03*
Y295273D03*
X233074Y285823D03*
Y288973D03*
Y292123D03*
Y295273D03*
X242524Y285823D03*
Y288973D03*
Y292123D03*
Y295273D03*
X239374Y285823D03*
Y288973D03*
Y292123D03*
Y295273D03*
X229924Y298423D03*
Y301573D03*
X236224D03*
Y298423D03*
X233074Y301573D03*
Y298423D03*
X242524Y301573D03*
Y298423D03*
X239374Y301573D03*
Y298423D03*
X229924Y304723D03*
Y307873D03*
Y311023D03*
X236224D03*
Y307873D03*
Y304723D03*
X233074Y311023D03*
Y307873D03*
Y304723D03*
X242524Y311023D03*
Y307873D03*
Y304723D03*
X239374Y311023D03*
Y307873D03*
Y304723D03*
X229924Y314173D03*
Y317323D03*
X236224D03*
Y314173D03*
X233074Y317323D03*
Y314173D03*
X242524Y317323D03*
Y314173D03*
X239374Y317323D03*
Y314173D03*
X245674Y279523D03*
X248824D03*
X251974D03*
X245674Y282673D03*
Y285823D03*
Y288973D03*
Y292123D03*
Y295273D03*
X248824Y282673D03*
X251974D03*
X248824Y285823D03*
Y288973D03*
Y292123D03*
Y295273D03*
X251974D03*
Y292123D03*
Y288973D03*
Y285823D03*
X245674Y301573D03*
Y298423D03*
Y311023D03*
Y307873D03*
Y304723D03*
X248824Y301573D03*
Y298423D03*
X251974D03*
Y301573D03*
X248824Y311023D03*
Y307873D03*
Y304723D03*
X251974D03*
Y307873D03*
Y311023D03*
X245674Y317323D03*
Y314173D03*
X248824Y317323D03*
Y314173D03*
X251974D03*
Y317323D03*
G54D41*
X57994Y278657D03*
X73742D03*
G54D207*
G01X140554Y44898D02*
X141745Y43707D01*
X143779D01*
G01X146782Y34404D02*
Y32910D01*
X146286Y32414D01*
X144276D01*
G01X145750Y49103D02*
X146782Y48071D01*
Y46710D01*
G01X148357D02*
Y49217D01*
X146280Y51294D01*
G01X150045Y30176D02*
X149932Y30289D01*
Y34404D01*
G01X151507D02*
Y31841D01*
X152810Y30538D01*
G01X153082Y34404D02*
Y33289D01*
X154136Y32235D01*
X155567D01*
G01X149932Y46710D02*
Y50813D01*
X149025Y51720D01*
G01X155256Y51103D02*
X153082Y48929D01*
Y46710D01*
G01X178087Y525054D02*
X174063D01*
G01X246284Y249980D02*
Y251200D01*
X245202Y252282D01*
Y252547D01*
X245018Y252731D01*
Y253432D01*
X245873Y254287D01*
Y254542D01*
X246467Y255136D01*
Y255442D01*
G01X251141Y250206D02*
Y250788D01*
X251909Y251556D01*
Y252472D01*
X252699Y253262D01*
X253061D01*
X253930Y254131D01*
Y254311D01*
G01X248495Y254867D02*
Y256065D01*
X249433Y257003D01*
Y257697D01*
G01X253930Y254311D02*
Y254679D01*
X250912Y257697D01*
X249433D01*
G01X417520Y525128D02*
X416029Y523637D01*
Y521083D01*
G01X413175Y530307D02*
X416650D01*
G01X417450Y536606D02*
X413175D01*
G01X404336Y545280D02*
X407834D01*
G01X411834D02*
X411911Y545203D01*
X415451D01*
X417604Y543050D01*
Y541035D01*
G01X407834Y545280D02*
X411834D01*
G01X428628Y515757D02*
Y521153D01*
G01X417604D02*
Y518503D01*
X416789Y517688D01*
G01X422050Y517028D02*
X422836Y517814D01*
G01X425478Y521153D02*
Y519224D01*
X424068Y517814D01*
X422836D01*
G01X427053Y521153D02*
Y518457D01*
X425999Y517403D01*
G01D02*
Y516211D01*
G01X416650Y530307D02*
X417520Y531177D01*
G01X430203Y521083D02*
Y518900D01*
G01X428745Y536999D02*
X429927Y538181D01*
X433127D01*
G01X417617Y536773D02*
X417450Y536606D01*
G01X423903Y541035D02*
Y548907D01*
X423909Y548913D01*
G01X425478Y541035D02*
Y545458D01*
X426068Y546048D01*
G01X419179Y541035D02*
Y544152D01*
X417979Y545352D01*
G01X427053Y541035D02*
Y544184D01*
X428014Y545145D01*
Y547128D01*
X428039Y547153D01*
G01X420754Y541035D02*
Y545203D01*
X418355Y547602D01*
X416515D01*
G01X430982Y543323D02*
X430203Y542544D01*
Y541105D01*
G01X422329Y541035D02*
Y545979D01*
X421461Y546847D01*
G01X428628Y541035D02*
Y543645D01*
X430446Y545463D01*
Y547403D01*
G01X438422Y530842D02*
X437887Y530307D01*
X433057D01*
G01X438380Y526108D02*
X437993D01*
X436944Y527157D01*
X433057D01*
G01X437334Y532386D02*
X436829Y531881D01*
X433057D01*
G01Y528732D02*
X438401D01*
X438845Y528288D01*
G01X433057Y525582D02*
X435835D01*
X437660Y523757D01*
X439762D01*
G01D02*
Y521256D01*
G01X446334Y543349D02*
Y542225D01*
X441268Y537159D01*
X439744D01*
X436041Y533456D01*
X433057D01*
G01Y536606D02*
X434970D01*
X435998Y537634D01*
Y539726D01*
G01X433057Y535031D02*
X435600D01*
X437935Y537366D01*
Y538055D01*
G01X438722Y538842D02*
X437935Y538055D01*
G01X450367Y543286D02*
X446397D01*
X446334Y543349D01*
G01X495228Y547148D02*
X490661D01*
G01X490538Y567825D02*
X490838Y567525D01*
Y565725D01*
X492092Y564471D01*
X495228D01*
G01X490658Y579025D02*
Y579085D01*
X491792Y580219D01*
X495228D01*
G01Y570770D02*
X490693D01*
G01X509464Y452420D02*
Y450265D01*
G01Y458719D02*
X505442D01*
G01X509464Y463443D02*
X507158D01*
X506838Y463123D01*
X503638D01*
X502938Y463823D01*
G01X509464Y465018D02*
X505843D01*
G01X504480Y534746D02*
Y529927D01*
X503958Y529405D01*
G01X507638Y525200D02*
Y534738D01*
X507630Y534746D01*
G01X495228Y542423D02*
X499336D01*
X500138Y543225D01*
G01D02*
X499365Y543998D01*
X495228D01*
G01X503448Y540235D02*
X503748D01*
X506055Y537928D01*
Y534746D01*
G01X505718Y542865D02*
Y541335D01*
X509205Y537848D01*
Y534746D01*
G01X500038Y555925D02*
X499366Y556597D01*
X495228D01*
G01Y550297D02*
X499610D01*
X500038Y550725D01*
G01D02*
X498891Y551872D01*
X495228D01*
G01Y562896D02*
X500009D01*
X500138Y563025D01*
G01Y558625D02*
X499684Y558171D01*
G01D02*
X495228D01*
G01Y573919D02*
X498332D01*
X499338Y574925D01*
X500438D01*
G01X495228Y578644D02*
X500419D01*
G01X495228Y572345D02*
X500218D01*
G01D02*
X500538Y572025D01*
G01X495228Y569195D02*
X500108D01*
X500338Y569425D01*
G01X495228Y567620D02*
X499143D01*
X500338Y566425D01*
G01X495228Y566045D02*
X499958D01*
X500338Y566425D01*
G01X495228Y584943D02*
X499086D01*
X499868Y585725D01*
G01D02*
X499075Y586518D01*
X495228D01*
G01X522653Y448680D02*
Y446008D01*
X523838Y444823D01*
Y442723D01*
G01X516353Y448680D02*
Y443517D01*
G01Y476632D02*
Y480708D01*
G01X525802Y476632D02*
Y479988D01*
X525603Y480187D01*
G01X523938Y528725D02*
X523378Y529285D01*
Y534746D01*
G01X513480Y541499D02*
Y538324D01*
X513929Y537875D01*
Y534746D01*
G01X520228D02*
Y538235D01*
X518938Y539525D01*
Y540425D01*
G01X515504Y534746D02*
Y538089D01*
X516380Y538965D01*
Y540364D01*
G01X521938Y540325D02*
Y539625D01*
X521803Y539490D01*
Y534746D01*
G01X526527D02*
Y538314D01*
X528138Y539925D01*
G01X524953Y534746D02*
Y539740D01*
X525338Y540125D01*
G01X519638Y600425D02*
X518653Y599440D01*
Y595770D01*
G01X523538Y600325D02*
X523378Y600165D01*
Y595770D01*
G01X512354D02*
Y590825D01*
G01X526527Y595770D02*
Y591436D01*
X527638Y590325D01*
G01X515504Y595770D02*
Y591041D01*
X515413Y590950D01*
G01X520228Y595770D02*
Y590335D01*
G01X524638Y590225D02*
X524953Y590540D01*
G01D02*
Y595770D01*
G01X528952Y448680D02*
Y446709D01*
X529283Y446378D01*
Y445078D01*
X530038Y444323D01*
G01D02*
X530527Y444812D01*
Y448680D01*
G01X533676D02*
Y446585D01*
X534738Y445523D01*
G01X537416Y452420D02*
X539338D01*
X541035Y450723D01*
X541838D01*
G01X542738Y463123D02*
X542418Y463443D01*
X537416D01*
G01X542738Y455823D02*
X541838D01*
X540517Y457144D01*
X537416D01*
G01Y460294D02*
X541267D01*
X542238Y459323D01*
X543338D01*
G01X540938Y473623D02*
X540207Y472892D01*
X537416D01*
G01X533676Y476632D02*
X535729D01*
G01X527138Y529525D02*
X528102Y530489D01*
Y534746D01*
G01X529677D02*
Y530286D01*
X530438Y529525D01*
G01X542275Y534746D02*
Y530362D01*
X541538Y529625D01*
G01X534401Y534746D02*
Y529562D01*
G01X534638Y539825D02*
X535976Y538487D01*
Y534746D01*
G01X541238Y539625D02*
X540701Y539088D01*
Y534746D01*
G01X533038Y590325D02*
Y590825D01*
X532827Y591036D01*
Y595770D01*
G01X540701D02*
Y590162D01*
G01X535776Y590487D02*
X535976Y590687D01*
G01X530338Y590325D02*
X529677Y590986D01*
G01X535976Y590687D02*
Y595770D01*
G01X529677Y590986D02*
Y595770D01*
G01X553895Y243929D02*
X550040D01*
G01X553895Y247079D02*
X550090D01*
G01X553895Y258102D02*
X547929D01*
G01X557207Y270863D02*
Y274828D01*
G01X544138Y530125D02*
X545425Y531412D01*
Y534746D01*
G01X560838Y540325D02*
Y540925D01*
X559340Y542423D01*
X556252D01*
G01Y543998D02*
X561065D01*
G01X556252Y547148D02*
X551161D01*
G01X543850Y534746D02*
Y538437D01*
X545138Y539725D01*
G01X556252Y545573D02*
X552686D01*
X551338Y544225D01*
G01X551538Y540325D02*
X552062Y540849D01*
G01D02*
X556252D01*
G01X551438Y561225D02*
X551534Y561321D01*
X556252D01*
G01Y551872D02*
X552110D01*
X551338Y551100D01*
G01X556252Y562896D02*
X552367D01*
X551438Y563825D01*
G01X551538Y568525D02*
X552208Y569195D01*
X556252D01*
G01Y570770D02*
X552193D01*
X551238Y571725D01*
G01X550938Y587325D02*
X551745Y586518D01*
X556252D01*
G01X548138Y600425D02*
X548575Y599988D01*
Y595770D01*
G01X544638Y600525D02*
X545425Y599738D01*
Y595770D01*
G01X547000D02*
Y590163D01*
G01X543850Y595770D02*
Y590313D01*
G01X551238Y584025D02*
X552156Y584943D01*
G01D02*
X556252D01*
G01X569805Y235893D02*
Y231864D01*
X569874Y231795D01*
G01X563506Y235893D02*
Y232027D01*
G01X566656Y270863D02*
Y275077D01*
X566774Y275195D01*
G01X576105Y235893D02*
Y231626D01*
G01X588865Y247079D02*
X592858D01*
G01X588865Y240780D02*
X593459D01*
G01X592874Y250995D02*
X592066Y251803D01*
X588865D01*
G01Y256528D02*
X594007D01*
X594174Y256695D01*
G01X588865Y261252D02*
X591610D01*
X592753Y262395D01*
X593874D01*
G01X582404Y270863D02*
Y273865D01*
X581474Y274795D01*
G01X580829Y270863D02*
Y274150D01*
X581474Y274795D01*
G01X643071Y392661D02*
X638365D01*
X637738Y392034D01*
G01X643071Y387936D02*
X638462D01*
X636990Y386464D01*
G01X643071Y397385D02*
X637740D01*
X637614Y397259D01*
G01X643071Y402109D02*
X637714D01*
X636938Y402885D01*
G01X652139Y412752D02*
Y416384D01*
X651138Y417385D01*
G01D02*
X650564Y416811D01*
Y412752D01*
G01X648989D02*
Y416725D01*
X648493Y417221D01*
G01X661588Y382018D02*
Y379131D01*
X659543Y377086D01*
G01X663162Y382018D02*
Y377811D01*
X662390Y377039D01*
G01X667887Y382018D02*
Y378816D01*
X669215Y377488D01*
G01X666312Y412752D02*
Y417742D01*
G01D02*
X664737Y416167D01*
Y412752D01*
G01X653714D02*
Y415731D01*
X653649Y417582D01*
G01X658438Y412752D02*
Y415951D01*
X658295Y417662D01*
G01X667887Y412752D02*
Y416221D01*
X668779Y417113D01*
Y417135D01*
G01X663162Y412752D02*
Y417487D01*
X663674Y417999D01*
G01X673805Y389511D02*
X677695D01*
X678099Y389915D01*
G01D02*
X676928Y391086D01*
X673805D01*
G01Y387936D02*
X677221D01*
X677946Y387211D01*
G01X673805Y403684D02*
X676837D01*
X678338Y405185D01*
G01D02*
X678264Y405259D01*
X673805D01*
G01Y402109D02*
X678983D01*
X680017Y403143D01*
G01X673805Y397385D02*
X678538D01*
X679138Y397985D01*
G01X673805Y406834D02*
X677370D01*
X678047Y407511D01*
X678564D01*
X678838Y407785D01*
G01X673805Y392661D02*
X678986D01*
G54D171*
X571380Y253378D03*
G54D108*
X209378Y469399D03*
Y462707D03*
X218040Y469399D03*
Y462707D03*
X513167Y422944D03*
X504505D03*
Y429636D03*
X513167D03*
G36*
G01X-39730Y745893D02*
Y748304D01*
G02X-37950Y749593I858J689D01*
G01X-36794D01*
G02X-34950I922J-600D01*
G01X-33794D01*
G02X-32014Y748304I922J-600D01*
G01Y745893D01*
X-33714D01*
Y747593D01*
X-38030D01*
Y745893D01*
X-39730D01*
G37*
G54D153*
X481102Y34528D03*
G54D60*
X98426Y105512D03*
Y719685D03*
G54D42*
X58466Y293171D03*
X66892D03*
X83475Y279475D03*
X95060Y159811D03*
X91320Y167685D03*
X98800D03*
X87215Y271601D03*
X90955Y279475D03*
X142500Y460406D03*
X138760Y468280D03*
X146240D03*
X146364Y726705D03*
X150104Y734579D03*
X153844Y726705D03*
X238069Y633421D03*
X234329Y641295D03*
X241809D03*
X258553Y438319D03*
X254813Y430445D03*
X262293D03*
X321514Y415629D03*
X325254Y407755D03*
X328994Y415629D03*
X369934Y326749D03*
X377414D03*
X373674Y334623D03*
X698881Y529230D03*
X716021Y521256D03*
X712281Y529130D03*
X702621Y521356D03*
X706361Y529230D03*
X719761Y529130D03*
G54D135*
X412330Y243725D03*
Y245694D03*
Y247662D03*
Y249631D03*
Y251599D03*
Y253569D03*
Y255537D03*
Y257505D03*
Y259473D03*
Y261442D03*
Y263410D03*
Y265379D03*
Y267347D03*
Y269316D03*
Y271284D03*
Y273253D03*
Y275222D03*
Y277190D03*
Y279158D03*
Y281127D03*
Y283095D03*
Y285064D03*
Y287032D03*
Y289001D03*
Y290969D03*
Y292938D03*
Y294906D03*
Y296875D03*
Y298843D03*
Y300812D03*
X434882Y243725D03*
Y245694D03*
Y247662D03*
Y249631D03*
Y251599D03*
Y253569D03*
Y255537D03*
Y257505D03*
Y259473D03*
Y261442D03*
Y263410D03*
Y265379D03*
Y267347D03*
Y269316D03*
Y271284D03*
Y273253D03*
Y275222D03*
Y277190D03*
Y279158D03*
Y281127D03*
Y283095D03*
Y285064D03*
Y287032D03*
Y289001D03*
Y290969D03*
Y292938D03*
Y294906D03*
Y296875D03*
Y298843D03*
Y300812D03*
G54D24*
X22935Y602945D03*
Y599795D03*
X18603Y611764D03*
Y614914D03*
X27018Y13036D03*
Y16186D03*
X37599Y44149D03*
X33677Y34564D03*
Y37714D03*
X37599Y47299D03*
X34140Y547324D03*
Y544174D03*
X30140Y547324D03*
Y544174D03*
X26145Y547371D03*
Y544221D03*
X32270Y608415D03*
Y605265D03*
X28270Y608415D03*
Y605265D03*
X41599Y44149D03*
X45578D03*
X49559D03*
X41599Y47299D03*
X45578D03*
X49559D03*
X46981Y65593D03*
Y62443D03*
X50981Y65593D03*
Y62443D03*
X54703Y115946D03*
Y119096D03*
X46811Y115664D03*
Y118814D03*
X50906Y510709D03*
Y513859D03*
X51337Y526060D03*
Y522910D03*
X46140Y547324D03*
Y544174D03*
X50140D03*
Y547324D03*
X44270Y608415D03*
Y605265D03*
X48270D03*
Y608415D03*
X66981Y65593D03*
Y62443D03*
X62981D03*
Y65593D03*
X54981D03*
Y62443D03*
X67831Y145032D03*
Y141882D03*
X61022Y180712D03*
Y183862D03*
X65169Y183921D03*
Y180771D03*
X60729Y204326D03*
Y207476D03*
X64906Y207595D03*
Y204445D03*
X60032Y228683D03*
Y231833D03*
X60182Y249949D03*
X60177Y246022D03*
Y242872D03*
X60029Y235880D03*
Y239030D03*
X60182Y253099D03*
X55351Y522907D03*
Y526057D03*
X59299Y529203D03*
Y526053D03*
X79360Y43076D03*
Y39926D03*
X70745Y170036D03*
X71730Y180744D03*
Y177594D03*
X70745Y173186D03*
X71778Y212026D03*
Y215176D03*
X71758Y218914D03*
Y222064D03*
X80369Y250679D03*
X80391Y243309D03*
Y246459D03*
X80369Y253829D03*
X72368Y290582D03*
Y293732D03*
X82368D03*
Y290582D03*
X75573Y503994D03*
Y507144D03*
X80368Y509170D03*
Y506020D03*
X84103Y509161D03*
X99968Y371107D03*
Y374257D03*
X95968Y371107D03*
Y374257D03*
X91458Y509198D03*
Y506048D03*
X102257Y172049D03*
Y175199D03*
X113620Y398184D03*
Y401334D03*
X109342Y413499D03*
Y410349D03*
X112072Y483758D03*
Y486908D03*
X108026Y486861D03*
Y483711D03*
X114372Y512558D03*
Y515708D03*
X109972Y512558D03*
Y515708D03*
X126072Y483758D03*
Y486908D03*
X129607Y689212D03*
Y692362D03*
X146380Y27366D03*
Y24216D03*
X137009Y32160D03*
Y35310D03*
X145210Y54510D03*
Y57660D03*
X149157Y57580D03*
Y54430D03*
X141160Y57630D03*
Y54480D03*
X137704Y408853D03*
Y412003D03*
X137759Y689175D03*
Y681175D03*
Y684325D03*
X133607Y689212D03*
X137759Y692325D03*
X133607Y692362D03*
X158181Y14450D03*
Y17600D03*
X154592Y24216D03*
Y27366D03*
X150592D03*
Y24216D03*
X158165Y27522D03*
X163933Y37475D03*
Y34325D03*
X160111Y56721D03*
X151101Y445079D03*
Y441929D03*
X151145Y463434D03*
Y466584D03*
X162663Y575608D03*
Y572458D03*
X158430Y575710D03*
Y572560D03*
X157963Y636958D03*
Y640108D03*
X164812Y666374D03*
Y669524D03*
X175335Y14913D03*
Y18063D03*
X171254Y14872D03*
Y18022D03*
X179361Y401571D03*
Y404721D03*
X167861Y424146D03*
X171993Y420771D03*
Y417621D03*
X175993D03*
Y420771D03*
X179544Y421477D03*
X167861Y427296D03*
X166646Y484538D03*
Y487688D03*
X179263Y575708D03*
Y572558D03*
X170930Y575710D03*
Y572560D03*
X166663Y575608D03*
Y572458D03*
X175263Y575708D03*
Y572558D03*
X172455Y732775D03*
Y735925D03*
X183419Y397314D03*
Y394164D03*
X183361Y401571D03*
Y404721D03*
X191803Y433565D03*
Y436715D03*
X196410Y643700D03*
X191910D03*
X187410D03*
X196410Y653700D03*
Y656850D03*
X187410Y653700D03*
Y656850D03*
X196410Y646850D03*
X191910D03*
X187410D03*
X189940Y715931D03*
Y719081D03*
X185440Y715931D03*
Y719081D03*
X194440Y715898D03*
Y719048D03*
Y739081D03*
Y727581D03*
Y730731D03*
X189940Y727581D03*
Y730731D03*
X185440Y727581D03*
Y730731D03*
X189940Y739081D03*
X185440D03*
X194440Y742231D03*
X189940D03*
X185440D03*
X211660Y391753D03*
Y388603D03*
X208729Y379173D03*
Y382323D03*
X211700Y398689D03*
Y395539D03*
X202009Y465628D03*
Y462478D03*
X205410Y643700D03*
X200910D03*
X205410Y653700D03*
Y656850D03*
X200910Y653700D03*
Y656850D03*
X205410Y646850D03*
X200910D03*
X198940Y715931D03*
Y719081D03*
X207940Y715931D03*
Y719081D03*
X203440Y715898D03*
Y719048D03*
X207940Y739081D03*
X203440D03*
X198940D03*
X207940Y727581D03*
Y730731D03*
X203440Y727581D03*
Y730731D03*
X198940Y727581D03*
Y730731D03*
X207940Y742231D03*
X203440D03*
X198940D03*
X212729Y379173D03*
Y382323D03*
X216729Y379173D03*
Y382323D03*
X220729Y379173D03*
Y382323D03*
X224729Y379173D03*
Y382323D03*
X221228Y396690D03*
Y393540D03*
X225228Y396690D03*
Y393540D03*
X223953Y469967D03*
Y466817D03*
X219640Y479308D03*
Y476158D03*
X221129Y639089D03*
Y635939D03*
X225179Y639089D03*
Y635939D03*
X221440Y739081D03*
X225940Y727581D03*
Y730731D03*
X212440Y739081D03*
X216940D03*
X212440Y730731D03*
Y727581D03*
X225940Y739081D03*
X221440Y730731D03*
Y727581D03*
X216940Y730731D03*
Y727581D03*
X221440Y742231D03*
X212440D03*
X216940D03*
X225940D03*
X232729Y382323D03*
Y379173D03*
X228729Y382323D03*
Y379173D03*
X236729Y382323D03*
Y379173D03*
X240729Y382323D03*
Y379173D03*
X228242Y469924D03*
Y466774D03*
X242009Y466578D03*
Y469728D03*
X237609Y466578D03*
Y469728D03*
X233309Y466578D03*
Y469728D03*
X241909Y478128D03*
Y474978D03*
X237609Y478128D03*
Y474978D03*
X233309Y478128D03*
Y474978D03*
X229199Y635939D03*
Y639089D03*
X229584Y649349D03*
Y646199D03*
X237451D03*
Y649349D03*
X241670Y649253D03*
Y646103D03*
X233584Y649349D03*
Y646199D03*
X234940Y727581D03*
Y730731D03*
X239440Y739081D03*
X230440D03*
X239440Y730731D03*
Y727581D03*
X234940Y739081D03*
X230440Y730731D03*
Y727581D03*
X239440Y742231D03*
X230440D03*
X234940D03*
X253511Y60208D03*
Y57058D03*
X244729Y379173D03*
Y382323D03*
X248729Y379173D03*
Y382323D03*
X252729D03*
Y379173D03*
X256729D03*
Y382323D03*
X254798Y420929D03*
Y424079D03*
X258798Y420929D03*
Y424079D03*
X251309Y466078D03*
Y469228D03*
X255509Y465978D03*
Y469128D03*
X246109Y478128D03*
Y474978D03*
X255509Y478128D03*
Y474978D03*
X251309Y478128D03*
Y474978D03*
X257109Y582978D03*
Y586128D03*
X246313Y632759D03*
Y629609D03*
X246293Y645233D03*
Y648383D03*
X257440Y739081D03*
X252940Y727581D03*
Y730731D03*
X243940Y727581D03*
Y730731D03*
X248440Y739081D03*
Y730731D03*
Y727581D03*
X252940Y739081D03*
X257440Y730731D03*
Y727581D03*
X243940Y739081D03*
X257440Y742231D03*
X248440D03*
X252940D03*
X243940D03*
X267421Y13166D03*
Y10016D03*
X271421D03*
Y13166D03*
X274972Y13872D03*
X263289Y19691D03*
Y16541D03*
X267987Y68029D03*
Y71179D03*
X271987Y68029D03*
Y71179D03*
X260729Y379173D03*
Y382323D03*
X272729Y379173D03*
Y382323D03*
X264729D03*
Y379173D03*
X268729Y382323D03*
Y379173D03*
X262798Y420929D03*
Y424079D03*
X266732Y420093D03*
Y416943D03*
X260609Y465978D03*
Y469128D03*
Y478128D03*
Y474978D03*
X269109Y478128D03*
Y474978D03*
X273809Y582978D03*
Y586128D03*
X269609Y582978D03*
Y586128D03*
X261940Y739081D03*
X266440D03*
X270940D03*
X266440Y730731D03*
Y727581D03*
X270940Y730731D03*
Y727581D03*
X261940Y730731D03*
Y727581D03*
Y742231D03*
X266440D03*
X270940D03*
X287233Y25708D03*
Y28858D03*
X275987Y68029D03*
Y71179D03*
X283987Y68029D03*
Y71179D03*
X279987Y68029D03*
Y71179D03*
X287987Y68029D03*
Y71179D03*
X289142Y372173D03*
Y369023D03*
X288729Y382323D03*
Y379173D03*
X280729D03*
Y382323D03*
X276729Y379173D03*
Y382323D03*
X284729D03*
Y379173D03*
X286710Y398785D03*
Y395635D03*
X276347Y448426D03*
Y451576D03*
X278109Y582978D03*
Y586128D03*
X282309Y582978D03*
Y586128D03*
X275440Y739081D03*
X279940Y727581D03*
Y730731D03*
X284440Y739081D03*
X288940Y727581D03*
Y730731D03*
X275440D03*
Y727581D03*
X279940Y739081D03*
X288940D03*
X284440Y730731D03*
Y727581D03*
X275440Y742231D03*
X284440D03*
X279940D03*
X288940D03*
X305142Y372173D03*
Y369023D03*
X297142Y372173D03*
Y369023D03*
X293142Y372173D03*
Y369023D03*
X301142Y372173D03*
Y369023D03*
X292729Y382323D03*
Y379173D03*
X298972Y608639D03*
Y605489D03*
X302440Y739081D03*
X297940Y727581D03*
Y730731D03*
X293440Y739081D03*
X297940D03*
X293440Y730731D03*
Y727581D03*
X302440Y742231D03*
X293440D03*
X297940D03*
X316466Y68029D03*
Y71179D03*
X312466Y68029D03*
Y71179D03*
X308466Y68029D03*
Y71179D03*
X320466Y68029D03*
Y71179D03*
X320374Y292653D03*
Y295803D03*
X314640Y319227D03*
Y316077D03*
X318640Y319227D03*
Y316077D03*
X310640Y319227D03*
Y316077D03*
X321110Y334011D03*
Y330861D03*
X309142Y369023D03*
Y372173D03*
X312824Y387863D03*
Y391013D03*
X313222Y378983D03*
Y382133D03*
X316938Y407069D03*
Y410219D03*
X319135Y594112D03*
Y597262D03*
X318880Y621427D03*
Y624577D03*
X314910D03*
Y621427D03*
X311329Y620721D03*
X314848Y636418D03*
Y639568D03*
X307574Y636613D03*
Y639763D03*
X314940Y719731D03*
Y716581D03*
X311440Y739081D03*
X320440D03*
X315940D03*
X306940Y727581D03*
Y730731D03*
X311440D03*
Y727581D03*
X320440Y730731D03*
Y727581D03*
X315940Y730731D03*
Y727581D03*
X306940Y739081D03*
X311440Y742231D03*
X320440D03*
X315940D03*
X306940D03*
X324466Y68029D03*
Y71179D03*
X324441Y295764D03*
Y292614D03*
X332348Y307752D03*
Y310902D03*
X322640Y319227D03*
Y316077D03*
X326640Y319227D03*
Y316077D03*
X330640Y319227D03*
Y316077D03*
X325700Y327721D03*
Y337951D03*
Y334801D03*
Y330871D03*
X331302Y429920D03*
Y426770D03*
X337012Y509444D03*
Y506294D03*
X332512Y509444D03*
Y506294D03*
X327739Y509656D03*
Y506506D03*
X336688Y537828D03*
Y540978D03*
X332088Y541078D03*
Y537928D03*
X336267Y572677D03*
Y569527D03*
X323036Y614013D03*
Y617163D03*
X323583Y636439D03*
Y639589D03*
X322940Y719731D03*
Y716581D03*
X324940Y739081D03*
X333940D03*
X329440D03*
X324940Y730731D03*
Y727581D03*
X333940Y730731D03*
Y727581D03*
X329440Y730731D03*
Y727581D03*
X324940Y742231D03*
X333940D03*
X329440D03*
X349490Y60647D03*
Y63797D03*
X341512Y509444D03*
Y506294D03*
X346012Y509444D03*
Y506294D03*
X350512Y509444D03*
Y506294D03*
X340388Y569570D03*
Y572720D03*
X347606Y713349D03*
Y710199D03*
X346940Y739081D03*
X342940Y727581D03*
Y730731D03*
X338440Y739081D03*
X351940Y727581D03*
Y730731D03*
X342940Y739081D03*
X347440Y730731D03*
Y727581D03*
X338440Y730731D03*
Y727581D03*
X350940Y739081D03*
X346940Y742231D03*
X338440D03*
X342940D03*
X350940D03*
X358940Y60647D03*
Y63797D03*
X365026Y329623D03*
Y326473D03*
X358210Y446344D03*
Y449494D03*
X368943Y509323D03*
Y512473D03*
X368238Y516378D03*
Y519528D03*
X365433Y540086D03*
Y543236D03*
X361433Y540086D03*
Y543236D03*
X367477Y627663D03*
Y630813D03*
X379051Y60991D03*
X370053Y60823D03*
X379051Y64141D03*
X370053Y63973D03*
X374207Y473374D03*
Y476524D03*
X374203Y484874D03*
Y488024D03*
X380786Y514797D03*
Y517947D03*
X380699Y546576D03*
X386999Y61186D03*
X395080Y61360D03*
X386999Y64336D03*
X395080Y64510D03*
X395656Y516297D03*
X399837D03*
X387221Y531263D03*
Y534413D03*
X395656Y519447D03*
X399837D03*
X391559Y609125D03*
Y605975D03*
X386464Y640267D03*
Y637117D03*
X390482D03*
Y640267D03*
X411608Y514020D03*
Y510870D03*
X406150Y513960D03*
X411834Y548430D03*
Y545280D03*
X407834D03*
Y548430D03*
X415605Y615038D03*
Y618188D03*
X411473Y621563D03*
Y624713D03*
X407473D03*
Y621563D03*
X403922Y620857D03*
X423845Y550973D03*
Y554123D03*
X428039Y550949D03*
Y554099D03*
X428060Y559112D03*
Y562262D03*
X423829Y559032D03*
Y562182D03*
X432152Y559098D03*
Y562248D03*
X432351Y550933D03*
Y554083D03*
X417781Y689290D03*
Y686140D03*
X418440Y739081D03*
X430940D03*
X426440D03*
X421940Y727581D03*
Y730731D03*
X422440Y739081D03*
X430940Y730731D03*
Y727581D03*
X426440Y730731D03*
Y727581D03*
X418440Y742231D03*
X430940D03*
X426440D03*
X422440D03*
X446304Y71848D03*
Y74998D03*
X439749Y509637D03*
Y512787D03*
X443768Y518161D03*
X439762Y518106D03*
X447758Y518161D03*
X443845Y509635D03*
Y512785D03*
X445729Y534196D03*
Y531046D03*
X441651Y534276D03*
Y531126D03*
X443768Y521311D03*
X439762Y521256D03*
X447758Y521311D03*
X443028Y543127D03*
Y546277D03*
X446334Y546499D03*
X446536Y553518D03*
Y550368D03*
X436219Y559133D03*
Y562283D03*
X442207Y629045D03*
Y632195D03*
X443940Y739081D03*
X448440Y727581D03*
Y730731D03*
X439940Y739081D03*
X435440D03*
X448440D03*
X435440Y730731D03*
Y727581D03*
X439940Y730731D03*
Y727581D03*
X443940Y742231D03*
X439940D03*
X435440D03*
X448440D03*
X450682Y71690D03*
Y74840D03*
X452115Y191819D03*
Y188669D03*
X450937Y486264D03*
Y489414D03*
X460722Y532351D03*
X456722D03*
X450367Y546436D03*
Y543286D03*
X460722Y535501D03*
X456722D03*
X450790Y553519D03*
Y550369D03*
X461588Y550463D03*
Y553613D03*
X451940Y689081D03*
X461440D03*
X456440D03*
X451940Y692231D03*
X461440D03*
X456440D03*
X452940Y739081D03*
X457440Y727581D03*
Y730731D03*
X461940Y739081D03*
X457440D03*
X452940Y742231D03*
X461940D03*
X457440D03*
X470623Y154085D03*
Y157235D03*
X471221Y194784D03*
Y197934D03*
X465291Y537985D03*
Y534835D03*
X478411Y597114D03*
Y593964D03*
X474397D03*
Y597114D03*
X474884Y607476D03*
Y604326D03*
X473436Y626379D03*
Y629529D03*
X469444Y629940D03*
Y633090D03*
X465940Y689081D03*
X470440D03*
X474940D03*
X465940Y692231D03*
X470440D03*
X474940D03*
X470940Y739081D03*
X474940D03*
X466440Y727581D03*
Y730731D03*
X470430Y730748D03*
Y727598D03*
X474930Y730748D03*
Y727598D03*
X479430Y730748D03*
Y727598D03*
X466440Y739081D03*
X478940D03*
X470940Y742231D03*
X474940D03*
X466440D03*
X478940D03*
X488438Y103048D03*
Y106198D03*
X483538Y103048D03*
Y106198D03*
X492955Y106179D03*
Y103029D03*
X495276Y198703D03*
Y195553D03*
X491171Y195574D03*
Y198724D03*
X484280Y195416D03*
Y198566D03*
X485719Y276271D03*
Y279421D03*
X494238Y603450D03*
Y606600D03*
X487240Y739081D03*
X491540D03*
X482940D03*
X492440Y730731D03*
Y727581D03*
X487940Y730731D03*
Y727581D03*
X483440Y730731D03*
Y727581D03*
X487240Y742231D03*
X491540D03*
X482940D03*
X508955Y106179D03*
Y103029D03*
X496955Y106179D03*
Y103029D03*
X504955Y106179D03*
Y103029D03*
X500955Y106179D03*
Y103029D03*
X508300Y201875D03*
Y198725D03*
X504052Y202146D03*
Y205296D03*
X507638Y522050D03*
Y525200D03*
X502038Y525900D03*
Y522750D03*
X502238Y603450D03*
Y606600D03*
X498238Y603450D03*
Y606600D03*
X500140Y739081D03*
X504140D03*
X495840D03*
X504940Y727581D03*
Y730731D03*
X509670Y730633D03*
Y727483D03*
X508140Y739081D03*
X496940Y730731D03*
Y727581D03*
X500140Y742231D03*
X504140D03*
X495840D03*
X508140D03*
X520955Y106179D03*
Y103029D03*
X516955Y106179D03*
Y103029D03*
X512955Y106179D03*
Y103029D03*
X524955Y106179D03*
Y103029D03*
X516657Y200990D03*
X520500Y200925D03*
X524500D03*
X512200Y198625D03*
Y201775D03*
X512160Y211450D03*
Y214600D03*
X516657Y204140D03*
X520500Y204075D03*
X524500D03*
X521800Y214675D03*
Y211525D03*
X513500Y221468D03*
Y224618D03*
X519675Y238308D03*
Y241458D03*
X515675Y238308D03*
Y241458D03*
X524675D03*
Y238308D03*
X526440Y425081D03*
Y428231D03*
X519840Y430981D03*
Y434131D03*
X526440Y437731D03*
Y434581D03*
X525474Y512154D03*
Y515304D03*
X526638Y611200D03*
Y608050D03*
X518940Y726981D03*
Y730131D03*
X520940Y739081D03*
X523940Y727581D03*
Y730731D03*
X512140Y739081D03*
X514940Y727581D03*
Y730731D03*
X516940Y739081D03*
X525440D03*
X520940Y742231D03*
X512140D03*
X516940D03*
X525440D03*
X536955Y103029D03*
Y106179D03*
X532955D03*
Y103029D03*
X528955Y106179D03*
Y103029D03*
X532500Y200925D03*
X540500D03*
X528500D03*
X536657Y200990D03*
X532500Y204075D03*
X531929Y216238D03*
Y219388D03*
X535929Y216238D03*
Y219388D03*
X540500Y204075D03*
X528500D03*
X536657Y204140D03*
X530940Y425081D03*
Y428231D03*
X540940Y425081D03*
Y428231D03*
X535940Y425081D03*
Y428231D03*
X541440Y437731D03*
Y434581D03*
X536440Y437731D03*
Y434581D03*
X531440Y437731D03*
Y434581D03*
X529474Y512154D03*
Y515304D03*
X542438Y607850D03*
Y611000D03*
X534638Y607950D03*
Y611100D03*
X530738D03*
Y607950D03*
X536068Y629326D03*
Y632476D03*
X541440Y716168D03*
Y713018D03*
X531570Y716345D03*
Y713195D03*
X541940Y739081D03*
X532940Y727581D03*
Y730731D03*
X529940Y739081D03*
X534440D03*
X541940Y730731D03*
Y727581D03*
X528440Y730731D03*
Y727581D03*
X541940Y742231D03*
X529940D03*
X534440D03*
X547248Y103161D03*
Y100011D03*
X555938Y100048D03*
Y103198D03*
X551454D03*
Y100048D03*
X553909Y201089D03*
X549909D03*
X557909D03*
X544500Y200925D03*
X553909Y204239D03*
X549909D03*
X557909D03*
X544500Y204075D03*
X545940Y425081D03*
Y428231D03*
X549940Y425081D03*
Y428231D03*
X555140Y448752D03*
Y451902D03*
X551140D03*
Y448752D03*
X546938Y607850D03*
Y611000D03*
X543400Y632456D03*
Y629306D03*
X549940Y716168D03*
Y713018D03*
X546440Y739081D03*
X550940D03*
X555440D03*
X546440Y730731D03*
Y727581D03*
X550940Y730731D03*
Y727581D03*
X555440Y730731D03*
Y727581D03*
X546440Y742231D03*
X550940D03*
X555440D03*
X565938Y100048D03*
Y103198D03*
X561909Y201089D03*
Y204239D03*
X564354Y286277D03*
Y283127D03*
X559140Y448752D03*
Y451902D03*
X562812Y627509D03*
Y630659D03*
X565074Y716168D03*
Y713018D03*
X564440Y727581D03*
Y730731D03*
X568940Y739081D03*
X573440Y727581D03*
Y730731D03*
X559940Y739081D03*
X573440D03*
X568940Y730731D03*
Y727581D03*
X564440Y739081D03*
X559940Y730731D03*
Y727581D03*
X568940Y742231D03*
X559940D03*
X573440D03*
X564440D03*
X586842Y155799D03*
X586769Y166461D03*
Y163311D03*
X586842Y158949D03*
X587707Y226968D03*
Y223818D03*
X579707Y226968D03*
Y223818D03*
X583707Y226968D03*
Y223818D03*
X589107Y289518D03*
Y292668D03*
X588437Y564120D03*
Y560970D03*
X586369Y590017D03*
Y593167D03*
X578399Y589937D03*
Y593087D03*
X582399Y589937D03*
Y593087D03*
X582620Y625963D03*
Y622813D03*
X589800Y683909D03*
Y687059D03*
X583440Y739081D03*
X587940Y727581D03*
Y730731D03*
Y739081D03*
X583440Y730731D03*
Y727581D03*
Y742231D03*
X587940D03*
X590842Y155799D03*
X590769Y166461D03*
Y163311D03*
X590842Y158949D03*
X590598Y202307D03*
Y205457D03*
X591707Y226968D03*
Y223818D03*
X595707Y226968D03*
Y223818D03*
X593107Y289518D03*
Y292668D03*
X604338Y344760D03*
Y341610D03*
X604091Y352754D03*
Y349604D03*
X604493Y361140D03*
Y357990D03*
X596437Y564120D03*
Y560970D03*
X600437Y564120D03*
Y560970D03*
X604437Y564120D03*
Y560970D03*
X592437Y564120D03*
Y560970D03*
X596940Y727581D03*
Y730731D03*
X601440Y739081D03*
X605940D03*
X592440D03*
Y730731D03*
Y727581D03*
X601440Y730731D03*
Y727581D03*
X605940Y730731D03*
Y727581D03*
X596940Y739081D03*
X601440Y742231D03*
X605940D03*
X592440D03*
X596940D03*
X620366Y292625D03*
X611988Y407850D03*
X615928D03*
X611988Y411000D03*
X615928D03*
X614338Y418820D03*
Y415670D03*
X618368Y418830D03*
Y415680D03*
X612937Y564320D03*
Y561170D03*
X617437Y564320D03*
Y561170D03*
X608437Y564120D03*
Y560970D03*
X611249Y633125D03*
Y636275D03*
X619302Y633065D03*
Y636215D03*
X607292Y681400D03*
Y678250D03*
X617242Y682697D03*
Y679547D03*
X606972Y688804D03*
Y691954D03*
X613882Y691668D03*
Y694818D03*
X614172Y705076D03*
Y701926D03*
X610172Y705076D03*
Y701926D03*
X610440Y739081D03*
X614940D03*
X619440D03*
X614940Y730731D03*
Y727581D03*
X619440Y730731D03*
Y727581D03*
X610440Y730731D03*
Y727581D03*
Y742231D03*
X614940D03*
X619440D03*
X627369Y300555D03*
Y303705D03*
X621937Y564320D03*
Y561170D03*
X630137Y633742D03*
Y636892D03*
X634137Y633742D03*
Y636892D03*
X628440Y739081D03*
X633130Y738905D03*
X637130D03*
X623940Y739081D03*
X628440Y730731D03*
Y727581D03*
X623940Y730731D03*
Y727581D03*
X628440Y742231D03*
X633130Y742055D03*
X637130D03*
X623940Y742231D03*
X643957Y47525D03*
Y50675D03*
X639957Y47525D03*
Y50675D03*
X645236Y371027D03*
Y367877D03*
X641236Y371027D03*
Y367877D03*
X649236Y371027D03*
Y367877D03*
X651437Y575720D03*
Y572570D03*
X642737Y633842D03*
Y636992D03*
X646737Y633842D03*
Y636992D03*
X650970Y633740D03*
Y636890D03*
X638470Y633740D03*
Y636890D03*
X643500Y738925D03*
Y742075D03*
X655947Y47606D03*
Y50756D03*
X659947Y47606D03*
Y50756D03*
X653352Y285183D03*
Y288333D03*
X653938Y367910D03*
Y371060D03*
X668573Y517014D03*
X664024Y516991D03*
X659933Y517197D03*
X668573Y520164D03*
X664024Y520141D03*
X659933Y520347D03*
X655170Y633840D03*
Y636990D03*
X664870Y673830D03*
Y669424D03*
Y666274D03*
Y676980D03*
X659678Y684907D03*
Y688057D03*
X660660Y742510D03*
Y739360D03*
X654660Y742510D03*
Y739360D03*
X669987Y47536D03*
Y50686D03*
X675927Y47536D03*
Y50686D03*
X679927Y47536D03*
Y50686D03*
X672306Y527718D03*
Y524568D03*
X691161Y512755D03*
Y515905D03*
X686661Y512755D03*
Y515905D03*
X693966Y523712D03*
Y520562D03*
X707176Y43845D03*
X711676D03*
X707176Y46995D03*
X711676D03*
X709400Y743375D03*
Y740225D03*
X713400Y743375D03*
Y740225D03*
X731566Y452628D03*
Y455778D03*
Y445468D03*
Y448618D03*
X726829Y515757D03*
Y512607D03*
X722383Y515757D03*
Y512607D03*
X729400Y743375D03*
Y740225D03*
X721400Y743375D03*
Y740225D03*
X717400Y743375D03*
Y740225D03*
X725400Y743375D03*
Y740225D03*
G54D117*
X270135Y702797D03*
Y696891D03*
X318288Y521500D03*
Y527406D03*
X324182Y521508D03*
Y527414D03*
X330182Y521508D03*
Y527414D03*
X336182Y521508D03*
Y527414D03*
X342182Y521508D03*
Y527414D03*
X354182Y521508D03*
Y527414D03*
X348182Y521508D03*
Y527414D03*
X360182Y521508D03*
Y527414D03*
X447440Y703203D03*
Y709109D03*
X453940Y703203D03*
X460940D03*
X453940Y709109D03*
X460940D03*
X467440Y703203D03*
X473940D03*
X480440D03*
X467440Y709109D03*
X473940D03*
X480440D03*
X551129Y280528D03*
X545223D03*
X635408Y511230D03*
X641314D03*
G54D144*
X428628Y521153D03*
X427053D03*
X425478D03*
X423903D03*
X422329D03*
X420754D03*
X419179D03*
X417604D03*
Y541035D03*
X419179D03*
X420754D03*
X422329D03*
X423903D03*
X425478D03*
X427053D03*
X428628D03*
G54D180*
X652139Y382018D03*
X650564D03*
X648989D03*
X647414D03*
Y412752D03*
X648989D03*
X650564D03*
X652139D03*
X667887Y382018D03*
X666312D03*
X664737D03*
X663162D03*
X661588D03*
X660013D03*
X658438D03*
X656863D03*
X655288D03*
X653714D03*
Y412752D03*
X655288D03*
X656863D03*
X658438D03*
X660013D03*
X661588D03*
X663162D03*
X664737D03*
X666312D03*
X667887D03*
X669462Y382018D03*
Y412752D03*
G54D162*
X525802Y448680D03*
X524227D03*
X522653D03*
X521078D03*
X519503D03*
X517928D03*
X516353D03*
X514779D03*
X513204D03*
Y476632D03*
X514779D03*
X516353D03*
X517928D03*
X519503D03*
X521078D03*
X522653D03*
X524227D03*
X525802D03*
X533676Y448680D03*
X532101D03*
X530527D03*
X528952D03*
X527377D03*
Y476632D03*
X528952D03*
X530527D03*
X532101D03*
X533676D03*
G54D33*
X47292Y422630D03*
Y441446D03*
X72488Y422630D03*
Y441446D03*
X439566Y418705D03*
Y438705D03*
X464762Y418705D03*
Y438705D03*
G54D51*
X65740Y717159D03*
X67450Y727094D03*
X72170Y696299D03*
X70460Y707975D03*
X691990Y610622D03*
X684570Y615002D03*
G54D126*
X327348Y536761D03*
G54D208*
G01X76085Y513104D02*
X73687D01*
X72482Y511899D01*
X69339D01*
G01X118666Y505333D02*
Y510269D01*
X118124Y510811D01*
G01X243083Y257697D02*
Y257822D01*
X241708Y259197D01*
X241613D01*
G01X259455Y250223D02*
X259518Y250160D01*
Y252358D01*
G01X323907Y463789D02*
X324999D01*
X326334Y465124D01*
X329986D01*
G01X325520Y476935D02*
X329986D01*
G01X336088Y459022D02*
Y454511D01*
G01X325040Y480129D02*
Y480124D01*
X326260Y478904D01*
X329986D01*
G01X363844Y472998D02*
X368787D01*
G01X357742Y492880D02*
Y489350D01*
X355150Y486758D01*
G01X369500Y488024D02*
X369495Y488029D01*
X368222D01*
X366972Y486779D01*
X366146D01*
X366145Y486778D01*
X363844D01*
G01X369989Y476529D02*
X368669D01*
X367107Y474967D01*
X363844D01*
G01X373380Y539854D02*
X372917Y540317D01*
G01X373380Y536372D02*
Y539854D01*
G01X504480Y595770D02*
Y599167D01*
X505738Y600425D01*
G01X507630Y595770D02*
Y599756D01*
X506961Y600425D01*
X505738D01*
G01X506055Y595770D02*
Y590842D01*
G01D02*
X505738Y590525D01*
G01X648989Y378750D02*
Y382018D01*
G01X649998Y377741D02*
X648989Y378750D01*
G01X652139Y382018D02*
Y377125D01*
G01X655280Y378161D02*
X655288Y378169D01*
G01D02*
Y382018D01*
G01X658438D02*
Y378943D01*
X657546Y378051D01*
G54D163*
X523440Y462656D03*
G54D145*
X423116Y531094D03*
G54D136*
X413386Y377165D03*
G54D34*
X45220Y471985D03*
X45546Y488556D03*
X45330Y480233D03*
X56820Y471985D03*
X57146Y488556D03*
X56930Y480233D03*
X143823Y687539D03*
X155423D03*
X195809Y450491D03*
X184209D03*
X291237Y42886D03*
X279637D03*
X291237Y51290D03*
X279637D03*
X295064Y591707D03*
X306664D03*
X387657Y591843D03*
X399257D03*
G54D61*
X101399Y204167D03*
X98840D03*
Y218734D03*
X101399D03*
X106517Y204167D03*
X103958D03*
X106517Y218734D03*
X103958D03*
G54D70*
X128499Y522895D03*
X646732Y284699D03*
G54D25*
X36900Y12883D03*
X34341D03*
X31782D03*
Y20757D03*
X34341D03*
X36900D03*
G54D190*
X683386Y626150D03*
X678386D03*
X673386D03*
Y661386D03*
X678386D03*
X683386D03*
X698386Y626150D03*
X693386D03*
X688386D03*
Y661386D03*
X693386D03*
X698386D03*
X713386Y626150D03*
X708386D03*
X703386D03*
Y661386D03*
X708386D03*
X713386D03*
X728386Y626150D03*
X723386D03*
X718386D03*
Y661386D03*
X723386D03*
X728386D03*
G54D154*
X478370Y104470D03*
Y113070D03*
G54D52*
X76880Y143269D03*
X739968Y29361D03*
G54D16*
X10859Y109561D03*
X73740Y20708D03*
X703661D03*
G54D43*
X71970Y357848D03*
X105613Y147532D03*
X147590Y647878D03*
X487770Y513674D03*
X577880Y395242D03*
X693400Y758198D03*
X745580Y62870D03*
G54D172*
X583913Y69167D03*
X608571D03*
G54D118*
X290490Y473703D03*
X600696Y612943D03*
X610796Y611219D03*
G54D181*
X645840Y381668D03*
Y413102D03*
X671036Y381668D03*
Y413102D03*
G54D127*
X350411Y30188D03*
Y46920D03*
X358285Y30188D03*
X366159D03*
X358285Y46920D03*
X366159D03*
X374033Y30188D03*
X381907D03*
X374033Y46920D03*
X381907D03*
X389781Y30188D03*
X397655D03*
X389781Y46920D03*
X397655D03*
G54D109*
X210709Y541953D03*
G54D209*
G01X253960Y135933D02*
X252730Y137163D01*
X251441D01*
X249386Y139218D01*
Y140418D01*
X249925Y140957D01*
Y142157D01*
X249074Y143008D01*
X247874D01*
X247335Y142469D01*
X246135D01*
X245284Y143320D01*
Y144520D01*
X245823Y145059D01*
Y146259D01*
X244972Y147110D01*
X243772D01*
X243233Y146571D01*
X242033D01*
X241182Y147422D01*
Y148622D01*
X243459Y150899D01*
Y152101D01*
X242610Y152950D01*
X241408D01*
X239131Y150673D01*
X237931D01*
X235070Y153534D01*
Y163067D01*
X235919Y163916D01*
X237121D01*
X237970Y163067D01*
Y156368D01*
X238819Y155519D01*
X240021D01*
X240870Y156368D01*
Y157600D01*
X241719Y158449D01*
X243411D01*
X244260Y159298D01*
Y160500D01*
X243411Y161349D01*
X241719D01*
X240870Y162198D01*
Y164367D01*
X235070Y170167D01*
Y175141D01*
X234050Y176161D01*
Y189076D01*
X234899Y189925D01*
X236521D01*
X237370Y190774D01*
Y191976D01*
X236521Y192825D01*
X234899D01*
X234050Y193674D01*
Y194876D01*
X234899Y195725D01*
X236521D01*
X237370Y196574D01*
Y197776D01*
X236521Y198625D01*
X234899D01*
X233390Y200134D01*
Y202240D01*
X225670Y209960D01*
Y229695D01*
X224862Y230503D01*
G01X228220Y230668D02*
Y211445D01*
X240170Y199495D01*
Y194096D01*
X243142Y191124D01*
X245121D01*
X245970Y190275D01*
Y189073D01*
X245121Y188224D01*
X239039D01*
X238190Y187375D01*
Y186173D01*
X239039Y185324D01*
X245121D01*
X245970Y184475D01*
Y183273D01*
X245121Y182424D01*
X238621D01*
X237290Y181093D01*
Y179209D01*
X238621Y177878D01*
X245041D01*
X245890Y177029D01*
Y175827D01*
X245041Y174978D01*
X239550D01*
X238150Y173578D01*
Y171597D01*
X239550Y170197D01*
X244141D01*
X244990Y169348D01*
Y167207D01*
X247183Y165014D01*
Y163107D01*
G01X267073Y145007D02*
Y149683D01*
X265729Y151027D01*
X264529D01*
X261627Y148125D01*
X260427D01*
X250049Y158503D01*
Y159703D01*
X250900Y160554D01*
X252100D01*
X260427Y152227D01*
X261627D01*
X262478Y153078D01*
Y154278D01*
X247792Y168964D01*
Y170166D01*
X248641Y171015D01*
X249843D01*
X267491Y153367D01*
X268693Y153366D01*
X269543Y154216D01*
X269544Y155416D01*
X248860Y176100D01*
Y191516D01*
X243310Y197066D01*
Y200391D01*
X230690Y213011D01*
Y230591D01*
G01X232910Y231032D02*
Y214754D01*
X247150Y200514D01*
Y197195D01*
X251668Y192677D01*
Y185862D01*
X253083Y184447D01*
Y182257D01*
G01X241400Y233676D02*
Y218187D01*
X241410Y218177D01*
X241408D01*
X252721Y206864D01*
X259262D01*
X276586Y189540D01*
X277786Y189541D01*
X278636Y190391D01*
X278635Y191593D01*
X265086Y205142D01*
X265087Y206342D01*
X265937Y207192D01*
X267139Y207191D01*
X290230Y184100D01*
Y160605D01*
X293053Y157782D01*
Y154997D01*
G01X283593Y144477D02*
X283590D01*
Y156327D01*
X287073Y159810D01*
Y182957D01*
X286273Y183757D01*
X284973D01*
X284173Y182957D01*
Y161787D01*
X283373Y160987D01*
X282073D01*
X281273Y161787D01*
Y180817D01*
X279897Y182193D01*
Y183393D01*
X282702Y186198D01*
Y187398D01*
X281851Y188249D01*
X280651D01*
X277846Y185444D01*
X276646D01*
X259011Y203079D01*
X257809D01*
X256960Y202230D01*
Y201028D01*
X263071Y194917D01*
Y193785D01*
X262152Y192866D01*
X261020D01*
X253450Y200436D01*
Y202168D01*
X238600Y217018D01*
Y233676D01*
G01X255643Y192767D02*
X255547D01*
X250400Y197914D01*
Y201250D01*
X235800Y215850D01*
Y232664D01*
G01X244200Y233141D02*
Y219355D01*
X253422Y210133D01*
X268254D01*
X288837Y189550D01*
X290037D01*
X290888Y190401D01*
Y191601D01*
X283592Y198897D01*
Y200097D01*
X284443Y200948D01*
X285643D01*
X294990Y191601D01*
Y190401D01*
X292088Y187499D01*
Y186299D01*
X293319Y185068D01*
Y180607D01*
X294168Y179758D01*
X298270D01*
X299119Y178909D01*
Y163458D01*
X298270Y162609D01*
X297068D01*
X296219Y163458D01*
Y176009D01*
X295370Y176858D01*
X294168D01*
X293319Y176009D01*
Y162061D01*
X298257Y157123D01*
Y143401D01*
X295383Y140527D01*
G01X235820Y251569D02*
X236289D01*
X237394Y252674D01*
X237414D01*
X237494Y252754D01*
X237594D01*
G01X253960Y135933D02*
X255040Y134853D01*
Y133606D01*
X253890Y132456D01*
X252424D01*
X251760Y131792D01*
Y121284D01*
X252500Y120544D01*
X255371D01*
X256210Y121383D01*
Y122923D01*
X255270Y123863D01*
Y129578D01*
X258676Y132984D01*
X260238D01*
X262010Y131212D01*
Y130032D01*
X260290Y128313D01*
Y126482D01*
X261717Y125055D01*
X263220D01*
X265941Y127776D01*
X267122D01*
X271064Y123834D01*
Y114763D01*
G01X273426D02*
Y125634D01*
X264190Y134870D01*
Y140250D01*
X251673Y152767D01*
X250473D01*
X249622Y151916D01*
Y150716D01*
X261272Y139066D01*
Y137866D01*
X260421Y137015D01*
X259221D01*
X246490Y149746D01*
Y152886D01*
X248422Y154818D01*
Y156018D01*
X247180Y157260D01*
X247183Y157263D01*
Y163107D01*
G01X253083Y182257D02*
Y180201D01*
X251704Y178822D01*
Y177622D01*
X269056Y160270D01*
X270256D01*
X271107Y161121D01*
Y162321D01*
X255806Y177622D01*
Y178822D01*
X256657Y179673D01*
X257857D01*
X267781Y169749D01*
X268981D01*
X271911Y172679D01*
X273111D01*
X273962Y171828D01*
Y170628D01*
X271032Y167698D01*
Y166498D01*
X274646Y162884D01*
Y155701D01*
X273797Y154852D01*
X273189D01*
X272340Y154003D01*
Y152801D01*
X273189Y151952D01*
X274431D01*
X275280Y151103D01*
Y149901D01*
X274431Y149052D01*
X271269D01*
X270420Y148203D01*
Y147001D01*
X271269Y146152D01*
X274371D01*
X275220Y145303D01*
Y144101D01*
X274371Y143252D01*
X270839D01*
X269990Y142403D01*
Y137243D01*
X271033Y136200D01*
X272233D01*
X274507Y138474D01*
X275639D01*
X276558Y137555D01*
Y136423D01*
X274284Y134149D01*
Y132949D01*
X279229Y128004D01*
Y121231D01*
X280513Y119947D01*
Y114763D01*
G01X255643Y192767D02*
X256563Y191847D01*
X257963D01*
X268992Y180818D01*
Y179616D01*
X268143Y178767D01*
X266941D01*
X257502Y188206D01*
X256302D01*
X255451Y187355D01*
Y186155D01*
X267439Y174167D01*
X268399D01*
X273472Y179240D01*
Y180440D01*
X264189Y189723D01*
Y190923D01*
X265040Y191774D01*
X266240D01*
X277574Y180440D01*
Y179240D01*
X274672Y176338D01*
Y175138D01*
X278093Y171717D01*
Y159616D01*
X278942Y158767D01*
X279851D01*
X280700Y157918D01*
Y156716D01*
X279851Y155867D01*
X278942D01*
X278093Y155018D01*
Y153816D01*
X278942Y152967D01*
X279851D01*
X280700Y152118D01*
Y150916D01*
X279851Y150067D01*
X278942D01*
X278093Y149218D01*
Y147335D01*
X279600Y145828D01*
Y134419D01*
X282153Y131866D01*
Y122007D01*
X282875Y121285D01*
Y114763D01*
G01X307574Y149601D02*
X307096Y150079D01*
X306009D01*
X305160Y150928D01*
Y171964D01*
X305979Y172783D01*
Y172782D01*
X310081D01*
Y172785D01*
X311123Y173827D01*
Y183957D01*
X310153Y184927D01*
X308909D01*
X308060Y184078D01*
Y176844D01*
X307211Y175995D01*
Y175992D01*
X305998D01*
Y175982D01*
X305160Y176820D01*
Y189830D01*
X279111Y215879D01*
X255602D01*
X249810Y221671D01*
Y229679D01*
G01X247000Y228486D02*
Y220518D01*
X254537Y212981D01*
X269400D01*
X271089Y211292D01*
X272875D01*
X274564Y212981D01*
X277939D01*
X282019Y208901D01*
Y207701D01*
X281168Y206850D01*
X279968D01*
X277689Y209129D01*
X276487D01*
X275638Y208280D01*
Y207078D01*
X279968Y202748D01*
X281168D01*
X284070Y205650D01*
X285270D01*
X298293Y192627D01*
Y190387D01*
X299303Y189377D01*
X301543D01*
X302240Y188680D01*
Y186743D01*
X301391Y185894D01*
X297332D01*
X296483Y185045D01*
Y183843D01*
X297332Y182994D01*
X301391D01*
X302240Y182145D01*
Y133684D01*
X302930Y132994D01*
G01X252600Y228892D02*
Y222841D01*
X256494Y218947D01*
X280523D01*
X313953Y185517D01*
Y157517D01*
X313153Y156717D01*
X311853D01*
X311053Y157517D01*
Y168927D01*
X310253Y169727D01*
X308953D01*
X308153Y168927D01*
Y154087D01*
X309027Y153213D01*
X313144D01*
Y153206D01*
X313953Y152397D01*
Y148503D01*
X314802Y147654D01*
X316564D01*
X317413Y146805D01*
Y145603D01*
X316564Y144754D01*
X314802D01*
X313953Y143905D01*
Y141837D01*
X314893Y140897D01*
G01X328973Y142937D02*
Y148610D01*
X329450Y149087D01*
Y165830D01*
X330620Y167000D01*
Y168730D01*
X329450Y169900D01*
Y171630D01*
X330620Y172800D01*
Y174530D01*
X329450Y175700D01*
Y177430D01*
X330620Y178600D01*
Y180330D01*
X329450Y181500D01*
Y188251D01*
X317703Y199998D01*
X316503D01*
X314366Y197861D01*
X313166D01*
X312315Y198712D01*
Y199912D01*
X314452Y202049D01*
Y203249D01*
X313601Y204100D01*
X312401D01*
X310264Y201963D01*
X309064D01*
X308213Y202814D01*
Y204014D01*
X310350Y206151D01*
Y207351D01*
X309499Y208202D01*
X308299D01*
X306162Y206065D01*
X304962D01*
X304111Y206916D01*
Y208116D01*
X306248Y210253D01*
Y211453D01*
X305397Y212304D01*
X304197D01*
X302060Y210167D01*
X300860D01*
X300009Y211018D01*
Y212218D01*
X302146Y214355D01*
Y215555D01*
X300916Y216785D01*
X299108D01*
X297620Y215297D01*
X295849D01*
X293355Y217791D01*
Y218991D01*
X294001Y219637D01*
Y220837D01*
X293150Y221688D01*
X291950D01*
X291304Y221042D01*
X290104D01*
X289253Y221893D01*
Y223093D01*
X289899Y223739D01*
Y224939D01*
X289048Y225790D01*
X287848D01*
X287202Y225144D01*
X286002D01*
X285151Y225995D01*
Y228492D01*
X282201Y231442D01*
X268415D01*
X266750Y233107D01*
Y239528D01*
G01X276603Y92119D02*
X274607Y90123D01*
Y82480D01*
G01X279331D02*
Y93905D01*
X277962Y95274D01*
X276340D01*
X273973Y97641D01*
Y97645D01*
G01X267073Y145007D02*
Y136039D01*
X276413Y126699D01*
Y120557D01*
X275788Y119932D01*
Y114763D01*
G01X281200Y98369D02*
X284056Y95513D01*
Y82480D01*
G01X288780D02*
Y88030D01*
X288773Y88037D01*
Y90507D01*
X287423Y91857D01*
G01X278760Y101061D02*
Y97830D01*
X281693Y94897D01*
Y91997D01*
X281694Y91996D01*
Y82480D01*
G01X289720Y96094D02*
Y94519D01*
X291142Y93097D01*
Y82480D01*
G01X293053Y154997D02*
X295333Y152717D01*
Y145873D01*
X293247Y143787D01*
X291154D01*
X290354Y144587D01*
Y153737D01*
X289505Y154586D01*
X288303D01*
X287454Y153737D01*
Y139006D01*
X288773Y137687D01*
Y121127D01*
X289961Y119939D01*
Y114763D01*
G01X285237D02*
Y119661D01*
X285863Y120287D01*
Y134390D01*
X283593Y136660D01*
Y144477D01*
G01X293505Y82480D02*
Y94965D01*
G01X303220Y98397D02*
X305316Y96301D01*
Y82480D01*
G01X294686Y114763D02*
X294683D01*
Y127557D01*
X296330Y129204D01*
Y134786D01*
X297179Y135635D01*
X298381D01*
X299230Y134786D01*
Y130273D01*
X301000Y128503D01*
X304484D01*
X306970Y130989D01*
Y136759D01*
X308498Y138287D01*
X310137D01*
X311030Y139180D01*
Y140314D01*
X309925Y141419D01*
X306102D01*
X305253Y142268D01*
Y143470D01*
X306102Y144319D01*
X310103D01*
X310903Y145119D01*
Y148801D01*
X310103Y149601D01*
X307574D01*
G01X292324Y114763D02*
Y121456D01*
X291593Y122187D01*
Y136737D01*
X295383Y140527D01*
G01X314893Y140897D02*
X316843Y138947D01*
Y137776D01*
X313664Y134597D01*
X310640D01*
X309840Y133797D01*
Y131733D01*
X310640Y130933D01*
X312840D01*
X313640Y130133D01*
Y128833D01*
X312840Y128033D01*
X309869D01*
X308003Y126167D01*
X306709D01*
X305810Y125268D01*
Y123996D01*
X306709Y123097D01*
X309112D01*
X311221Y120988D01*
Y114763D01*
G01X314765Y82480D02*
Y89897D01*
X315075Y90207D01*
X315083D01*
G01X307678Y82480D02*
Y93165D01*
X310920Y96407D01*
X312223D01*
G01X310040Y82480D02*
Y90834D01*
X311553Y92347D01*
G01X328973Y142937D02*
Y141548D01*
X327500Y140075D01*
Y136864D01*
X328349Y136015D01*
X330221D01*
X331070Y135166D01*
Y133964D01*
X330221Y133115D01*
X328349D01*
X327500Y132266D01*
Y125956D01*
X326167Y124623D01*
X322562D01*
X320670Y122731D01*
Y114763D01*
G54D44*
X67640Y493618D03*
G54D62*
X102362Y247244D03*
Y349606D03*
X354331Y247244D03*
Y349606D03*
G54D146*
X431340Y599929D03*
X435080Y592055D03*
X438820Y599929D03*
X474860Y581398D03*
X471120Y589272D03*
X478600D03*
G54D35*
X51395Y500840D03*
X65440Y164548D03*
X59640D03*
X66055Y223944D03*
X60255D03*
X57195Y500840D03*
X85829Y535202D03*
X79182Y583713D03*
X73382D03*
X91629Y535202D03*
X91717Y587077D03*
X97517D03*
X103080Y535202D03*
X108880D03*
X130102Y738065D03*
X124302D03*
X145375Y305640D03*
X139575D03*
X165512Y50968D03*
X159712D03*
X208209Y476153D03*
X214009D03*
X220428Y583822D03*
X226228D03*
X238952Y583627D03*
X233152D03*
X238852Y589327D03*
X233052D03*
X256606Y387964D03*
X250806D03*
X265696Y446936D03*
X271496D03*
X275509Y668795D03*
X269709D03*
X324696Y363647D03*
X330496D03*
X324696Y369147D03*
X330496D03*
X324732Y374642D03*
X330532D03*
X332439Y380334D03*
X326639D03*
X342520Y303938D03*
X348320D03*
X340926Y317597D03*
X346726D03*
X409149Y71906D03*
X414949D03*
X409024Y558626D03*
X445663Y101680D03*
X448182Y262291D03*
X447975Y604522D03*
X457394Y187205D03*
X463194D03*
X453982Y262291D03*
X453775Y604522D03*
X473153Y617880D03*
X467353D03*
X495888Y655413D03*
X501688D03*
X535772Y253862D03*
X541572D03*
X714559Y563230D03*
X720359D03*
X725495Y593262D03*
X731295D03*
X757507Y564565D03*
X763307D03*
X757614Y570468D03*
X763414D03*
G54D71*
X132438Y699863D03*
X130470D03*
X128501D03*
Y717383D03*
X130470D03*
X132438D03*
X136375Y699863D03*
X134406D03*
Y717383D03*
X136375D03*
G54D164*
X519985Y526639D03*
X525085Y522183D03*
G54D191*
X697200Y140140D03*
X693854D03*
X695084Y212132D03*
X698430D03*
G54D155*
X482093Y127519D03*
Y129487D03*
Y131456D03*
Y133424D03*
Y135393D03*
Y137361D03*
Y139330D03*
Y141298D03*
Y143267D03*
Y145235D03*
Y147204D03*
Y149172D03*
Y151141D03*
Y153109D03*
Y155078D03*
Y157046D03*
Y159015D03*
Y160983D03*
Y162952D03*
Y164920D03*
Y166889D03*
Y168857D03*
Y170826D03*
Y172794D03*
Y174763D03*
Y176731D03*
X573117Y139330D03*
Y137361D03*
Y135393D03*
Y133424D03*
Y131456D03*
Y129487D03*
Y127519D03*
Y155078D03*
Y153109D03*
Y151141D03*
Y149172D03*
Y147204D03*
Y145235D03*
Y143267D03*
Y141298D03*
Y170826D03*
Y168857D03*
Y166889D03*
Y164920D03*
Y162952D03*
Y160983D03*
Y159015D03*
Y157046D03*
Y176731D03*
Y174763D03*
Y172794D03*
G54D80*
X164375Y262559D03*
Y280287D03*
Y274623D03*
Y268223D03*
Y285951D03*
Y292351D03*
Y310079D03*
Y298015D03*
Y303679D03*
Y327807D03*
Y321407D03*
Y315743D03*
Y333471D03*
X292323Y263375D03*
Y269039D03*
Y281103D03*
Y275439D03*
Y286767D03*
Y293167D03*
Y304495D03*
Y310895D03*
Y298831D03*
Y328623D03*
Y322223D03*
Y316559D03*
Y334287D03*
G54D53*
X86880Y143269D03*
X749968Y29361D03*
G54D137*
X412699Y466933D03*
X408369D03*
X412448Y471896D03*
Y476226D03*
G54D26*
X36024Y187233D03*
Y181225D03*
Y205257D03*
Y199249D03*
Y193241D03*
Y217272D03*
Y211264D03*
X41930Y178221D03*
Y202253D03*
Y196245D03*
Y190237D03*
Y220276D03*
Y214268D03*
Y208260D03*
G54D173*
X590999Y69167D03*
Y77041D03*
Y84915D03*
X615657Y69167D03*
Y77041D03*
Y84915D03*
G54D17*
X20859Y109561D03*
X83740Y20708D03*
X78740Y30708D03*
X507489Y360278D03*
X713661Y20708D03*
X708661Y30708D03*
G54D128*
X354348Y38554D03*
X393718D03*
X605796Y189845D03*
Y204845D03*
X611702Y185690D03*
Y178997D03*
Y200690D03*
Y193997D03*
G54D119*
X287709Y483619D03*
G54D182*
X642721Y384787D03*
Y409983D03*
X674155Y384787D03*
Y409983D03*
G54D90*
X173100Y33371D03*
G54D129*
X352079Y382282D03*
X347079D03*
Y408896D03*
X352079D03*
X362079Y382282D03*
X357079D03*
Y408896D03*
X362079D03*
G54D54*
X85951Y383568D03*
Y404368D03*
X100951Y383568D03*
X95951D03*
X90951D03*
Y404368D03*
X95951D03*
X100951D03*
X224269Y602633D03*
Y623433D03*
X239269Y602633D03*
X234269D03*
X229269D03*
Y623433D03*
X234269D03*
X239269D03*
X352079Y381319D03*
X347079D03*
Y409953D03*
X352079D03*
X362079Y381319D03*
X357079D03*
Y409953D03*
X362079D03*
G54D36*
X55256Y625732D03*
Y637332D03*
X116383Y576727D03*
Y588327D03*
X164948Y8617D03*
Y20217D03*
X181582Y11345D03*
Y22945D03*
X190011Y11535D03*
Y23135D03*
X199840Y11316D03*
Y22916D03*
X456988Y479623D03*
X465255Y479621D03*
X456988Y491223D03*
X465255Y491221D03*
X462344Y499662D03*
Y511262D03*
X718335Y581651D03*
Y593251D03*
X747439Y641672D03*
Y653272D03*
G54D27*
X47220Y28062D03*
X43480D03*
X39740D03*
Y37708D03*
X47220D03*
X424700Y661479D03*
X432180D03*
Y651833D03*
X428440D03*
X424700D03*
G54D18*
X25439Y303260D03*
Y356804D03*
G54D45*
X64089Y489779D03*
Y492338D03*
Y494898D03*
Y497457D03*
X80553D03*
G54D156*
X495125Y118424D03*
X493156D03*
X491188D03*
Y185826D03*
X493156D03*
X495125D03*
X510873Y118424D03*
X508904D03*
X506936D03*
X504967D03*
X502999D03*
X501030D03*
X499062D03*
X497093D03*
Y185826D03*
X499062D03*
X501030D03*
X502999D03*
X504967D03*
X506936D03*
X508904D03*
X510873D03*
X526621Y118424D03*
X524652D03*
X522684D03*
X520715D03*
X518747D03*
X516778D03*
X514810D03*
X512841D03*
Y185826D03*
X514810D03*
X516778D03*
X518747D03*
X520715D03*
X522684D03*
X524652D03*
X526621D03*
X542369Y118424D03*
X540400D03*
X538432D03*
X536463D03*
X534495D03*
X532526D03*
X530558D03*
X528589D03*
Y185826D03*
X530558D03*
X532526D03*
X534495D03*
X536463D03*
X538432D03*
X540400D03*
X542369D03*
X558117Y118424D03*
X556148D03*
X554180D03*
X552211D03*
X550243D03*
X548274D03*
X546306D03*
X544337D03*
Y185826D03*
X546306D03*
X548274D03*
X550243D03*
X552211D03*
X554180D03*
X556148D03*
X558117D03*
X564022Y118424D03*
X562054D03*
X560085D03*
Y185826D03*
X562054D03*
X564022D03*
G54D138*
X417659Y485373D03*
Y490373D03*
Y495373D03*
Y500373D03*
X441359Y485373D03*
Y500373D03*
Y495373D03*
Y490373D03*
G54D165*
X554780Y38803D03*
X617371D03*
X679963D03*
G54D174*
X590999Y92789D03*
X615657D03*
G54D81*
G01X225755Y507321D02*
X225677D01*
X223709Y505353D01*
G01X269850Y497872D02*
Y497812D01*
X271367Y496295D01*
X271429D01*
X163910Y507731D03*
X160760D03*
X157611D03*
X163910Y510881D03*
X160760D03*
X157611D03*
X163910Y514030D03*
X160760D03*
X157611D03*
X163910Y517180D03*
X160760D03*
X157611D03*
X163910Y520329D03*
X160760D03*
X157611D03*
X163910Y523479D03*
X160760D03*
X157611D03*
X163910Y526629D03*
X160760D03*
X157611D03*
X163910Y529778D03*
X160760D03*
X157611D03*
X163910Y532928D03*
X160760D03*
X157611D03*
X163910Y536077D03*
X160760D03*
X157611D03*
X163910Y539227D03*
X160760D03*
X157611D03*
X163910Y542377D03*
X160760D03*
X157611D03*
X163910Y545526D03*
X160760D03*
X157611D03*
X163910Y548676D03*
X160760D03*
X157611D03*
X163910Y551825D03*
X160760D03*
X157611D03*
X163910Y554975D03*
X160760D03*
X157611D03*
X179658Y507731D03*
X176508D03*
X179658Y510881D03*
X176508D03*
X179658Y514030D03*
X176508D03*
X179658Y517180D03*
X176508D03*
X179658Y520329D03*
X176508D03*
X179658Y523479D03*
X176508D03*
X179658Y526629D03*
X176508D03*
X179658Y529778D03*
X176508D03*
X179658Y532928D03*
X176508D03*
X179658Y536077D03*
X176508D03*
X179658Y539227D03*
X176508D03*
X179658Y542377D03*
X176508D03*
X179658Y545526D03*
X176508D03*
X179658Y548676D03*
X176508D03*
X179658Y551825D03*
X176508D03*
X179658Y554975D03*
X176508D03*
X182807Y507731D03*
Y510881D03*
Y514030D03*
Y517180D03*
Y520329D03*
Y523479D03*
Y526629D03*
Y529778D03*
Y532928D03*
Y536077D03*
Y539227D03*
Y542377D03*
Y545526D03*
Y548676D03*
Y551825D03*
Y554975D03*
X225755Y497872D03*
Y501022D03*
Y504171D03*
Y507321D03*
Y510471D03*
Y513620D03*
Y516770D03*
Y519919D03*
Y523069D03*
Y526219D03*
Y529368D03*
Y532518D03*
Y535667D03*
Y538817D03*
Y541967D03*
Y545116D03*
Y548266D03*
Y551415D03*
Y554565D03*
Y557715D03*
Y560864D03*
Y564014D03*
X228905Y497872D03*
Y501022D03*
X232054Y497872D03*
Y501022D03*
X235204Y497872D03*
Y501022D03*
X238354Y497872D03*
Y501022D03*
X241503Y497872D03*
Y501022D03*
X228905Y504171D03*
Y507321D03*
Y510471D03*
Y513620D03*
Y516770D03*
X232054Y504171D03*
Y507321D03*
Y510471D03*
Y513620D03*
Y516770D03*
X235204Y504171D03*
Y507321D03*
Y510471D03*
Y513620D03*
Y516770D03*
X238354Y504171D03*
Y507321D03*
Y510471D03*
Y513620D03*
Y516770D03*
X241503Y504171D03*
Y507321D03*
Y510471D03*
X228905Y519919D03*
Y523069D03*
Y526219D03*
Y529368D03*
Y532518D03*
X232054Y519919D03*
Y523069D03*
Y526219D03*
Y529368D03*
Y532518D03*
X235204Y519919D03*
Y523069D03*
Y526219D03*
Y529368D03*
Y532518D03*
X238354Y519919D03*
Y523069D03*
Y526219D03*
Y529368D03*
Y532518D03*
X241503Y519919D03*
Y523069D03*
Y526219D03*
Y529368D03*
Y532518D03*
X228905Y535667D03*
Y538817D03*
Y541967D03*
Y545116D03*
Y548266D03*
X232054Y535667D03*
Y538817D03*
Y541967D03*
Y545116D03*
Y548266D03*
X235204Y535667D03*
Y538817D03*
Y541967D03*
Y545116D03*
Y548266D03*
X238354Y535667D03*
Y538817D03*
Y541967D03*
Y545116D03*
Y548266D03*
X241503Y535667D03*
Y538817D03*
Y541967D03*
X228905Y551415D03*
Y554565D03*
Y557715D03*
Y560864D03*
Y564014D03*
X232054Y551415D03*
Y554565D03*
Y557715D03*
Y560864D03*
Y564014D03*
X235204Y551415D03*
Y554565D03*
Y557715D03*
Y560864D03*
Y564014D03*
X238354Y551415D03*
Y554565D03*
Y557715D03*
Y560864D03*
Y564014D03*
X241503Y551415D03*
Y554565D03*
Y557715D03*
Y560864D03*
Y564014D03*
X244653Y497872D03*
Y501022D03*
X247802Y497872D03*
Y501022D03*
X250952Y497872D03*
Y501022D03*
X254102Y497872D03*
Y501022D03*
X257251Y497872D03*
Y501022D03*
X244653Y504171D03*
Y507321D03*
Y510471D03*
X247802Y504171D03*
Y507321D03*
Y510471D03*
Y513620D03*
X250952Y504171D03*
Y507321D03*
Y510471D03*
Y513620D03*
X254102Y504171D03*
Y507321D03*
Y510471D03*
Y513620D03*
X257251Y504171D03*
Y507321D03*
Y510471D03*
Y513620D03*
X250952Y523069D03*
Y526219D03*
Y529368D03*
Y532518D03*
X254102Y523069D03*
Y526219D03*
Y529368D03*
Y532518D03*
X257251Y523069D03*
Y526219D03*
Y529368D03*
Y532518D03*
X247802Y548266D03*
X250952Y535667D03*
Y538817D03*
Y548266D03*
X254102Y535667D03*
Y538817D03*
Y548266D03*
X257251Y535667D03*
Y538817D03*
Y548266D03*
X244653Y551415D03*
Y554565D03*
Y557715D03*
Y560864D03*
Y564014D03*
X247802Y551415D03*
Y554565D03*
Y557715D03*
Y560864D03*
Y564014D03*
X250952Y551415D03*
Y554565D03*
Y557715D03*
Y560864D03*
Y564014D03*
X254102Y551415D03*
Y554565D03*
Y557715D03*
Y560864D03*
Y564014D03*
X257251Y551415D03*
Y554565D03*
Y557715D03*
Y560864D03*
Y564014D03*
X260401Y497872D03*
Y501022D03*
X263550Y497872D03*
Y501022D03*
X266700Y497872D03*
Y501022D03*
X269850Y497872D03*
Y501022D03*
X272999Y497872D03*
Y501022D03*
X260401Y504171D03*
Y507321D03*
Y510471D03*
Y513620D03*
X263550Y504171D03*
Y507321D03*
Y510471D03*
Y513620D03*
X266700Y504171D03*
Y507321D03*
Y510471D03*
Y513620D03*
X269850Y504171D03*
Y507321D03*
Y510471D03*
Y513620D03*
X272999Y504171D03*
Y507321D03*
Y510471D03*
X260401Y523069D03*
Y526219D03*
Y529368D03*
Y532518D03*
X263550Y523069D03*
Y526219D03*
Y529368D03*
Y532518D03*
X266700Y523069D03*
Y526219D03*
Y529368D03*
Y532518D03*
X260401Y535667D03*
Y538817D03*
Y548266D03*
X263550Y535667D03*
Y538817D03*
Y548266D03*
X266700Y535667D03*
Y538817D03*
Y548266D03*
X269850D03*
X260401Y551415D03*
Y554565D03*
Y557715D03*
Y560864D03*
Y564014D03*
X263550Y551415D03*
Y554565D03*
Y557715D03*
Y560864D03*
Y564014D03*
X266700Y551415D03*
Y554565D03*
Y557715D03*
Y560864D03*
Y564014D03*
X269850Y551415D03*
Y554565D03*
Y557715D03*
Y560864D03*
Y564014D03*
X272999Y551415D03*
Y554565D03*
Y557715D03*
Y560864D03*
Y564014D03*
X276149Y497872D03*
Y501022D03*
X279298Y497872D03*
Y501022D03*
X282448Y497872D03*
Y501022D03*
X285598Y497872D03*
Y501022D03*
X288747Y497872D03*
Y501022D03*
X276149Y504171D03*
Y507321D03*
Y510471D03*
X279298Y504171D03*
Y507321D03*
Y510471D03*
Y513620D03*
X282448Y504171D03*
Y507321D03*
Y510471D03*
Y513620D03*
X285598Y504171D03*
Y507321D03*
Y510471D03*
Y513620D03*
X288747Y504171D03*
Y507321D03*
Y510471D03*
Y513620D03*
X279298Y516770D03*
X282448D03*
X285598D03*
X288747D03*
X276149Y519919D03*
Y523069D03*
Y526219D03*
Y529368D03*
Y532518D03*
X279298Y519919D03*
Y523069D03*
Y526219D03*
Y529368D03*
Y532518D03*
X282448Y519919D03*
Y523069D03*
Y526219D03*
Y529368D03*
Y532518D03*
X285598Y519919D03*
Y523069D03*
Y526219D03*
Y529368D03*
Y532518D03*
X288747Y519919D03*
Y523069D03*
Y526219D03*
Y529368D03*
Y532518D03*
X276149Y535667D03*
Y538817D03*
Y541967D03*
X279298Y535667D03*
Y538817D03*
Y541967D03*
Y545116D03*
Y548266D03*
X282448Y535667D03*
Y538817D03*
Y541967D03*
Y545116D03*
Y548266D03*
X285598Y535667D03*
Y538817D03*
Y541967D03*
Y545116D03*
Y548266D03*
X288747Y535667D03*
Y538817D03*
Y541967D03*
Y545116D03*
Y548266D03*
X276149Y551415D03*
Y554565D03*
Y557715D03*
Y560864D03*
Y564014D03*
X279298Y551415D03*
Y554565D03*
Y557715D03*
Y560864D03*
Y564014D03*
X282448Y551415D03*
Y554565D03*
Y557715D03*
Y560864D03*
Y564014D03*
X285598Y551415D03*
Y554565D03*
Y557715D03*
Y560864D03*
Y564014D03*
X288747Y551415D03*
Y554565D03*
Y557715D03*
Y560864D03*
Y564014D03*
X291897Y497872D03*
Y501022D03*
Y504171D03*
Y507321D03*
Y510471D03*
Y513620D03*
Y516770D03*
Y519919D03*
Y523069D03*
Y526219D03*
Y529368D03*
Y532518D03*
Y535667D03*
Y538817D03*
Y541967D03*
Y545116D03*
Y548266D03*
Y551415D03*
Y554565D03*
Y557715D03*
Y560864D03*
Y564014D03*
G54D183*
X643071Y386361D03*
Y387936D03*
Y389511D03*
Y391086D03*
Y392661D03*
Y394235D03*
Y395810D03*
Y397385D03*
Y398960D03*
Y400535D03*
Y402109D03*
Y403684D03*
Y405259D03*
Y406834D03*
Y408409D03*
X673805Y391086D03*
Y389511D03*
Y387936D03*
Y386361D03*
Y406834D03*
Y405259D03*
Y403684D03*
Y402109D03*
Y400535D03*
Y398960D03*
Y397385D03*
Y395810D03*
Y394235D03*
Y392661D03*
Y408409D03*
G54D63*
X97150Y553052D03*
G54D72*
X143779Y37407D03*
Y38982D03*
Y40557D03*
Y42132D03*
Y43707D03*
X156085D03*
Y42132D03*
Y40557D03*
Y38982D03*
Y37407D03*
X413105Y524007D03*
Y538181D03*
X433127Y524007D03*
Y538181D03*
G54D147*
X449463Y101680D03*
G54D192*
X685246Y592423D03*
G54D184*
X658438Y397385D03*
G54D148*
X447355Y157140D03*
Y177140D03*
X461921Y157140D03*
Y177140D03*
G54D193*
X711575Y143555D03*
Y195355D03*
Y222361D03*
Y274161D03*
X733975Y143555D03*
Y195355D03*
Y222361D03*
Y274161D03*
G54D46*
X63237Y512883D03*
G54D19*
X23628Y321764D03*
Y338300D03*
X45282Y321764D03*
G54D166*
X546181Y81889D03*
G54D82*
X154307Y507507D03*
X154517Y513931D03*
X159196Y515612D03*
X154038Y511386D03*
X153967Y517186D03*
X159185Y531356D03*
X153731Y520734D03*
X159179Y521893D03*
X162335Y521906D03*
X159180Y528227D03*
X155400Y533436D03*
X154246Y527468D03*
X162335Y528206D03*
X159186Y534504D03*
X159185Y543953D03*
X155060Y545526D03*
X154945Y542383D03*
Y536083D03*
X162336Y550253D03*
X154945Y539233D03*
X159185Y547103D03*
X154900Y548682D03*
X162315Y553391D03*
X154900Y551832D03*
X159186Y553402D03*
X157611Y557468D03*
X154410Y557990D03*
X178818Y274540D03*
X178085Y518755D03*
X178094Y531365D03*
X168617Y525756D03*
X172371Y519783D03*
X174720Y531356D03*
X171606Y527511D03*
X178117Y528187D03*
X178082Y537654D03*
X178099Y550267D03*
X174105Y542290D03*
X167027Y539526D03*
Y536376D03*
X173217Y536556D03*
X181818Y274540D03*
X186417Y518526D03*
X186467Y514036D03*
X184920Y508626D03*
X181232Y515607D03*
X187417Y508756D03*
X189007Y514846D03*
X181232Y528205D03*
X187875Y534128D03*
X181232Y543953D03*
X184384Y537656D03*
X181232Y537654D03*
X184384Y543955D03*
X188927Y537836D03*
X190434Y546870D03*
X188383Y556895D03*
X184386Y553406D03*
X181491Y557436D03*
X208050Y528883D03*
X209886Y539962D03*
X201509Y539853D03*
X207309Y539953D03*
X199709Y551653D03*
X208109Y551053D03*
X202486Y551130D03*
X216184Y268587D03*
X227284Y502591D03*
X214626Y516492D03*
X227326Y505741D03*
X227329Y508894D03*
X223709Y505353D03*
X216564Y528902D03*
X214118Y528583D03*
X218751Y543835D03*
X233626Y502591D03*
X230476D03*
X243075D03*
X230476Y505741D03*
X236776Y508891D03*
Y518339D03*
X233626Y508891D03*
Y515190D03*
X230476D03*
X233626Y518339D03*
X236776Y512040D03*
X243075Y508891D03*
X230476D03*
X236776Y515190D03*
X230476Y518339D03*
Y512040D03*
X233626D03*
X239925Y518339D03*
X233626Y521489D03*
X236776Y534087D03*
X233626Y527788D03*
X230476Y534087D03*
X236776Y521489D03*
Y527788D03*
X233626Y524639D03*
X236776D03*
X230476D03*
X233626Y534087D03*
X239925Y527788D03*
Y524639D03*
X230476Y527788D03*
Y521489D03*
X239925Y534087D03*
Y521489D03*
X233626Y543536D03*
X239925Y540386D03*
Y543536D03*
X236776Y540386D03*
Y537236D03*
X230476D03*
Y543536D03*
Y540386D03*
X233626D03*
X236776Y543536D03*
X233626Y537236D03*
X239925D03*
X243075Y559284D03*
Y552984D03*
X235307Y566357D03*
X231209Y566282D03*
X252524Y502591D03*
X255673D03*
X249374D03*
X246224D03*
X255673Y512040D03*
X252524D03*
X255673Y508891D03*
Y505741D03*
X249374D03*
Y508891D03*
X252524Y505741D03*
Y508891D03*
X249374Y512040D03*
X246224D03*
X252524Y527789D03*
Y524639D03*
X255673Y534088D03*
X252524D03*
X249374D03*
X255673Y524639D03*
Y527789D03*
X249374D03*
Y524639D03*
X255673Y537237D03*
X249374D03*
X252524D03*
X255673Y540387D03*
X249374D03*
X252524D03*
Y549835D03*
X255673D03*
X249374D03*
X255673Y565580D03*
Y552984D03*
Y556133D03*
Y559282D03*
Y562431D03*
X249344Y552984D03*
Y556134D03*
X246224Y559284D03*
Y556134D03*
Y562434D03*
X252554Y559314D03*
X262904Y293850D03*
X268943Y291086D03*
X265122Y502591D03*
X274582D03*
X271402Y499441D03*
X271429Y496295D03*
X261972Y502591D03*
X268272Y505741D03*
Y508891D03*
Y512040D03*
X271422D03*
X265121Y508891D03*
X261972D03*
Y505741D03*
X265122Y512040D03*
X261972D03*
X265122Y505741D03*
X261972Y521489D03*
X268272Y534088D03*
X265122D03*
X261972D03*
X268272Y524639D03*
Y527789D03*
X265122D03*
Y524639D03*
X261972D03*
Y527789D03*
X268272Y521489D03*
X265122D03*
X268272Y540387D03*
X265122D03*
X261972D03*
X265122Y537237D03*
X268272D03*
X261972D03*
X268272Y549836D03*
X271421D03*
X265122D03*
X261972D03*
X274571Y552985D03*
X265122D03*
X268272Y559291D03*
X271422Y562434D03*
X271421Y556135D03*
X271422Y559291D03*
X261973Y552985D03*
X262009Y556153D03*
X261972Y562431D03*
X271422Y565583D03*
X271421Y552985D03*
X274572Y556142D03*
X284024Y499445D03*
X287173D03*
X277712Y502595D03*
X284024D03*
X290323D03*
Y534092D03*
X280874D03*
X287174D03*
X284024D03*
X277725D03*
Y527792D03*
Y521493D03*
X280874Y537241D03*
Y543541D03*
X284024D03*
X287174Y540391D03*
Y543541D03*
X290323Y540391D03*
Y543541D03*
X277725Y540391D03*
Y543541D03*
Y537241D03*
X290322Y549841D03*
X280872D03*
X287174Y559289D03*
X290323Y565589D03*
X284024Y565588D03*
X287174D03*
X290323Y559289D03*
Y562439D03*
Y556140D03*
X287174Y562438D03*
X280874D03*
X284024D03*
Y559289D03*
X277725Y552989D03*
X280874Y559289D03*
X277725Y556135D03*
Y559289D03*
X287174Y556139D03*
X280874Y552989D03*
X284024Y556139D03*
X287174Y552989D03*
X284024D03*
X293473Y534092D03*
Y540391D03*
Y565589D03*
Y562439D03*
Y559290D03*
X677206Y469943D03*
X681143D03*
X677206Y466006D03*
X681143D03*
X677206Y462069D03*
X681143D03*
X677206Y458132D03*
X681143D03*
X679175Y464038D03*
X674353Y463842D03*
X683112Y464038D03*
X677206Y485692D03*
X681143D03*
X677206Y481755D03*
X681143D03*
X677206Y477817D03*
X681143D03*
X677206Y473881D03*
X681143D03*
X683112Y483723D03*
X683113Y471941D03*
X677206Y493566D03*
X681143D03*
X677206Y489629D03*
X681143D03*
X683112Y487660D03*
X685080Y469943D03*
X689017D03*
X692955D03*
X696891D03*
X685080Y466006D03*
X689017D03*
X692955D03*
X696891D03*
X685080Y462069D03*
X689017D03*
X692955D03*
X696891D03*
X685080Y458132D03*
X689017D03*
X692955D03*
X696891D03*
X687049Y467975D03*
X698860D03*
X690986D03*
X685080Y485692D03*
X689017D03*
X692955D03*
X696891D03*
X685080Y481755D03*
X689017D03*
X692955D03*
X696891D03*
X685080Y477817D03*
X689017D03*
X692955D03*
X696891D03*
X685080Y473881D03*
X689017D03*
X692955D03*
X696891D03*
X698860Y471912D03*
X690986D03*
Y479786D03*
X687049Y483723D03*
X698860Y479786D03*
Y483723D03*
X687049Y479786D03*
X690986Y483723D03*
X687049Y471912D03*
X698683Y487517D03*
X685080Y493566D03*
X689017D03*
X692955D03*
X696891D03*
X685080Y489629D03*
X689017D03*
X692955D03*
X696891D03*
X690986Y487660D03*
X687049D03*
X692955Y502112D03*
X700829Y469943D03*
X704766D03*
X708703D03*
X712640D03*
X700829Y466006D03*
X704766D03*
X708703D03*
X712640D03*
X700829Y462069D03*
X704766D03*
X708703D03*
X712640D03*
X700829Y458132D03*
X704766D03*
X708703D03*
X712640D03*
X702797Y464038D03*
Y467975D03*
X700829Y485692D03*
X704766D03*
X708703D03*
X712640D03*
X700829Y481755D03*
X704766D03*
X708703D03*
X712640D03*
X700829Y477817D03*
X704766D03*
X708703D03*
X712640D03*
X700829Y473881D03*
X704766D03*
X708703D03*
X712640D03*
X706734Y471913D03*
Y483723D03*
X710671Y479786D03*
X706734Y475850D03*
X710671Y471913D03*
X702585Y483749D03*
X702797Y471912D03*
Y479786D03*
X706734D03*
X700829Y493566D03*
X704766D03*
X708703D03*
X712640D03*
X700829Y489629D03*
X704766D03*
X708703D03*
X712640D03*
G54D55*
X77499Y457491D03*
Y480521D03*
G54D139*
X413175Y525582D03*
Y527157D03*
Y528732D03*
Y530307D03*
Y531881D03*
Y533456D03*
Y535031D03*
Y536606D03*
X433057Y533456D03*
Y531881D03*
Y530307D03*
Y528732D03*
Y527157D03*
Y525582D03*
Y536606D03*
Y535031D03*
G54D73*
X148357Y34404D03*
X146782D03*
Y46710D03*
X148357D03*
X153082Y34404D03*
X151507D03*
X149932D03*
X153082Y46710D03*
X151507D03*
X149932D03*
X416029Y521083D03*
Y541105D03*
X430203Y521083D03*
Y541105D03*
G54D64*
X120635Y499230D03*
X330425Y556306D03*
X375349Y530269D03*
G54D91*
G01X161918Y254287D02*
X164036Y256405D01*
X164920D01*
G01X168120Y253205D02*
X171320D01*
G01X244653Y557715D02*
X244644D01*
X243075Y559284D01*
G01X391857Y713839D02*
X390578D01*
X389550Y712811D01*
Y711488D01*
X389350Y711288D01*
G01X403496Y713835D02*
X399341D01*
X399337Y713839D01*
G01X615928Y407850D02*
X618511D01*
X619014Y408353D01*
G01X637362Y285042D02*
X640112D01*
G01X687584Y237342D02*
Y233034D01*
G01Y246988D02*
Y251770D01*
X164920Y246805D03*
Y250005D03*
X168120Y246805D03*
X171320D03*
X168120Y250005D03*
X171320D03*
X174520Y246805D03*
X164920Y256405D03*
Y253205D03*
X171320D03*
X168120D03*
X164920Y340441D03*
Y343641D03*
X171320D03*
X168120D03*
X174520Y350041D03*
X171320D03*
X168120Y346841D03*
X171320D03*
X285378Y246805D03*
Y250005D03*
X282178Y246805D03*
X288578D03*
Y250005D03*
X285378Y253205D03*
X288578D03*
X285378Y343641D03*
X288578D03*
X282178Y350041D03*
X285378Y346841D03*
X288578Y350041D03*
X285378D03*
X288578Y346841D03*
X291778Y246805D03*
Y250005D03*
Y256405D03*
Y253205D03*
Y340441D03*
Y343641D03*
Y350041D03*
Y346841D03*
G54D157*
X495228Y540849D03*
Y542423D03*
Y543998D03*
Y545573D03*
Y547148D03*
Y548723D03*
Y550297D03*
Y551872D03*
Y553447D03*
Y555022D03*
Y556597D03*
Y558171D03*
Y559746D03*
Y561321D03*
Y562896D03*
Y564471D03*
Y566045D03*
Y567620D03*
Y569195D03*
Y570770D03*
Y572345D03*
Y573919D03*
Y575494D03*
Y577069D03*
Y578644D03*
Y580219D03*
Y581793D03*
Y583368D03*
Y584943D03*
Y586518D03*
Y588093D03*
Y589667D03*
X556252Y548723D03*
Y547148D03*
Y545573D03*
Y543998D03*
Y542423D03*
Y540849D03*
Y564471D03*
Y562896D03*
Y561321D03*
Y559746D03*
Y558171D03*
Y556597D03*
Y555022D03*
Y553447D03*
Y551872D03*
Y550297D03*
Y580219D03*
Y578644D03*
Y577069D03*
Y575494D03*
Y573919D03*
Y572345D03*
Y570770D03*
Y569195D03*
Y567620D03*
Y566045D03*
Y589667D03*
Y588093D03*
Y586518D03*
Y584943D03*
Y583368D03*
Y581793D03*
G54D175*
X584166Y276414D03*
X591774Y284989D03*
G54D37*
X51240Y807872D03*
X59114D03*
X63051D03*
X66988D03*
X70925D03*
X74862D03*
X78799D03*
X82736D03*
X86673D03*
X90610D03*
X94547D03*
X98484D03*
X102421D03*
X106358D03*
X110295D03*
X114232D03*
X118169D03*
X122106D03*
X126043D03*
X129980D03*
X133917D03*
X137854D03*
X141791D03*
X145728D03*
X149665D03*
X153602D03*
X157539D03*
X161476D03*
X165413D03*
X169350D03*
X173287D03*
X177224D03*
X181161D03*
X189035D03*
X192972D03*
X196909D03*
X200846D03*
X204783D03*
X208720D03*
X212658D03*
X216594D03*
X220532D03*
X224469D03*
X228406D03*
X232343D03*
X236280D03*
X240217D03*
X244154D03*
X248091D03*
X255965D03*
X259902D03*
X263839D03*
X267776D03*
X271713D03*
X275650D03*
X279587D03*
X283524D03*
X287461D03*
X291398D03*
X295335D03*
X299272D03*
X303209D03*
X311083D03*
X315020D03*
X318957D03*
X322894D03*
X326831D03*
X338642D03*
X342579D03*
X346516D03*
X350453D03*
X354390D03*
X358327D03*
X362264D03*
X366201D03*
X370138D03*
X374075D03*
X378012D03*
X409510D03*
X417384D03*
X421321D03*
X425258D03*
X429195D03*
X433132D03*
X437069D03*
X441006D03*
X444943D03*
X448880D03*
X452817D03*
X456754D03*
X460691D03*
X464628D03*
X468565D03*
X472502D03*
X476439D03*
X480376D03*
X484313D03*
X488250D03*
X492187D03*
X496124D03*
X500061D03*
X503998D03*
X507935D03*
X511872D03*
X515809D03*
X519746D03*
X523683D03*
X527620D03*
X531557D03*
X535494D03*
X539431D03*
X547305D03*
X551242D03*
X555179D03*
X559116D03*
X563053D03*
X566990D03*
X570928D03*
X574864D03*
X578802D03*
X582739D03*
X586676D03*
X590613D03*
X594550D03*
X598487D03*
X602424D03*
X606361D03*
X614235D03*
X618172D03*
X622109D03*
X626046D03*
X629983D03*
X633920D03*
X637857D03*
X641794D03*
X645731D03*
X649668D03*
X653605D03*
X657542D03*
X661479D03*
X669353D03*
X673290D03*
X677227D03*
X681164D03*
X685101D03*
X696912D03*
X700849D03*
X704786D03*
X708723D03*
X712660D03*
X716597D03*
X720534D03*
X724471D03*
X728408D03*
X732345D03*
X736282D03*
G54D28*
X40749Y150808D03*
Y249194D03*
G54D56*
X80553Y492338D03*
G54D185*
X662460Y149432D03*
Y145496D03*
X662673Y164035D03*
Y160099D03*
X662294Y228238D03*
Y224302D03*
X662908Y242841D03*
Y238905D03*
X673484Y149432D03*
Y145496D03*
X673697Y164035D03*
Y160099D03*
X673318Y228238D03*
Y224302D03*
X673932Y242841D03*
Y238905D03*
G54D47*
X69339Y515836D03*
Y513867D03*
Y511899D03*
Y509930D03*
X57135D03*
Y511899D03*
Y513867D03*
Y515836D03*
X119039Y402421D03*
X131245D03*
X119039Y404389D03*
Y406358D03*
X131245D03*
Y404389D03*
X119039Y410295D03*
X131245D03*
X119039Y408327D03*
X131245D03*
X636349Y300643D03*
Y308517D03*
Y302611D03*
Y304580D03*
Y306549D03*
X648555Y308517D03*
Y300643D03*
Y306549D03*
Y304580D03*
Y302611D03*
G54D83*
X157550Y595169D03*
Y597138D03*
Y599106D03*
Y601075D03*
Y603043D03*
Y605012D03*
Y606980D03*
Y608949D03*
Y610917D03*
Y612886D03*
Y614854D03*
Y616823D03*
Y618791D03*
Y620760D03*
Y622728D03*
Y624697D03*
X193376Y597138D03*
Y595169D03*
Y612886D03*
Y610917D03*
Y608949D03*
Y606980D03*
Y605012D03*
Y603043D03*
Y601075D03*
Y599106D03*
Y624697D03*
Y622728D03*
Y620760D03*
Y618791D03*
Y616823D03*
Y614854D03*
X616024Y587981D03*
Y589950D03*
Y591918D03*
Y593887D03*
Y595855D03*
Y597824D03*
Y599792D03*
Y601761D03*
Y603729D03*
Y605698D03*
Y607666D03*
Y609635D03*
Y611603D03*
Y613572D03*
Y615540D03*
Y617509D03*
X651850Y595855D03*
Y593887D03*
Y591918D03*
Y589950D03*
Y587981D03*
Y611603D03*
Y609635D03*
Y607666D03*
Y605698D03*
Y603729D03*
Y601761D03*
Y599792D03*
Y597824D03*
Y617509D03*
Y615540D03*
Y613572D03*
G54D92*
X177720Y246805D03*
Y350041D03*
X278978Y246805D03*
Y350041D03*
G54D158*
X507489Y281538D03*
G54D74*
X149932Y40557D03*
G54D29*
X43898Y168544D03*
Y231457D03*
G54D194*
X712975Y155655D03*
Y165455D03*
Y173455D03*
Y183255D03*
Y234461D03*
Y244261D03*
Y252261D03*
Y262061D03*
X723275Y165455D03*
Y173455D03*
Y183255D03*
Y244261D03*
Y252261D03*
Y262061D03*
G54D167*
X556181Y81889D03*
G54D149*
X436202Y492873D03*
G54D65*
X115150Y605559D03*
X110520Y627269D03*
X113270Y635559D03*
X111120Y657269D03*
X133410Y607269D03*
X143110Y612533D03*
X137230Y623734D03*
X150360Y622884D03*
X668320Y585031D03*
X666470Y593397D03*
X657270Y603848D03*
X667930Y599681D03*
X675130Y591687D03*
G54D38*
X55177Y805904D03*
X185098D03*
X252028D03*
X307146D03*
X413447D03*
X543368D03*
X610298D03*
X665416D03*
G54D176*
X595427Y501238D03*
Y516986D03*
X622199Y501238D03*
Y516986D03*
X632769Y527813D03*
Y543561D03*
X659541Y527813D03*
Y543561D03*
G54D57*
X74621Y493618D03*
G54D66*
X136024Y145866D03*
X430906D03*
G54D39*
X59920Y170026D03*
X65696Y170071D03*
X59920Y175826D03*
X65696Y175871D03*
X59821Y193765D03*
Y199565D03*
X65821D03*
Y193765D03*
X60242Y212743D03*
Y218543D03*
X66242D03*
Y212743D03*
X71880Y195309D03*
Y201109D03*
X77368Y295057D03*
Y289257D03*
X116165Y562839D03*
Y568639D03*
X124628Y726984D03*
Y732784D03*
X141699Y25494D03*
Y31294D03*
X151101Y455287D03*
Y449487D03*
X292893Y72444D03*
Y66644D03*
X298293Y72444D03*
Y66644D03*
X303693Y72444D03*
Y66644D03*
X367531Y641507D03*
Y635707D03*
X416288Y512677D03*
Y506877D03*
X421788Y512677D03*
Y506877D03*
X438258Y548889D03*
Y543089D03*
X454641Y518021D03*
Y523821D03*
X456991Y553628D03*
X542248Y97186D03*
Y102986D03*
X547340Y473756D03*
Y479556D03*
X560938Y106523D03*
Y100723D03*
X562340Y475256D03*
Y481056D03*
X585805Y201406D03*
Y207206D03*
X718231Y568773D03*
Y574573D03*
G54D48*
X66190Y506781D03*
X64221D03*
X62253D03*
X60284D03*
Y518985D03*
X62253D03*
X64221D03*
X66190D03*
X116698Y493127D03*
Y505333D03*
X124572Y493127D03*
X122604D03*
X120635D03*
X118666D03*
X124572Y505333D03*
X118666D03*
X120635D03*
X122604D03*
X334362Y550203D03*
X326488D03*
X332394D03*
X330425D03*
X328456D03*
X326488Y562409D03*
X334362D03*
X328456D03*
X330425D03*
X332394D03*
X379286Y524166D03*
X371412D03*
X377318D03*
X375349D03*
X373380D03*
X371412Y536372D03*
X379286D03*
X373380D03*
X375349D03*
X377318D03*
X458200Y81713D03*
X450326D03*
Y93919D03*
X458200D03*
X456232Y81713D03*
X454263D03*
X452294D03*
Y93919D03*
X454263D03*
X456232D03*
G54D84*
X162668Y592020D03*
X160699D03*
Y627846D03*
X162668D03*
X178416Y592020D03*
X176447D03*
X174479D03*
X172510D03*
X170542D03*
X168573D03*
X166605D03*
X164636D03*
Y627846D03*
X166605D03*
X168573D03*
X170542D03*
X172510D03*
X174479D03*
X176447D03*
X178416D03*
X190227Y592020D03*
X188258D03*
X186290D03*
X184321D03*
X182353D03*
X180384D03*
Y627846D03*
X182353D03*
X184321D03*
X186290D03*
X188258D03*
X190227D03*
X621142Y584832D03*
X619173D03*
Y620658D03*
X621142D03*
X636890Y584832D03*
X634921D03*
X632953D03*
X630984D03*
X629016D03*
X627047D03*
X625079D03*
X623110D03*
Y620658D03*
X625079D03*
X627047D03*
X629016D03*
X630984D03*
X632953D03*
X634921D03*
X636890D03*
X648701Y584832D03*
X646732D03*
X644764D03*
X642795D03*
X640827D03*
X638858D03*
Y620658D03*
X640827D03*
X642795D03*
X644764D03*
X646732D03*
X648701D03*
G54D177*
X605796Y165160D03*
X609733Y215672D03*
G54D75*
X151969Y98622D03*
G54D168*
X557207Y235893D03*
Y270863D03*
X572955Y235893D03*
X571380D03*
X569805D03*
X568231D03*
X566656D03*
X565081D03*
X563506D03*
X561931D03*
X560357D03*
X558782D03*
Y270863D03*
X560357D03*
X561931D03*
X563506D03*
X565081D03*
X566656D03*
X568231D03*
X569805D03*
X571380D03*
X572955D03*
X585553Y235893D03*
X583979D03*
X582404D03*
X580829D03*
X579254D03*
X577679D03*
X576105D03*
X574530D03*
Y270863D03*
X576105D03*
X577679D03*
X579254D03*
X580829D03*
X582404D03*
X583979D03*
X585553D03*
G54D159*
X509464Y452420D03*
Y453995D03*
Y455569D03*
Y457144D03*
Y458719D03*
Y460294D03*
Y461869D03*
Y463443D03*
Y465018D03*
Y466593D03*
Y468168D03*
Y469743D03*
Y471317D03*
Y472892D03*
X537416Y453995D03*
Y452420D03*
Y469743D03*
Y468168D03*
Y466593D03*
Y465018D03*
Y463443D03*
Y461869D03*
Y460294D03*
Y458719D03*
Y457144D03*
Y455569D03*
Y472892D03*
Y471317D03*
G54D195*
X732284Y109187D03*
Y126509D03*
G54D93*
G01X163518Y243987D02*
Y245403D01*
X164920Y246805D01*
G01X166122Y295025D02*
X164375Y293278D01*
Y292351D01*
G01X168321Y293358D02*
X167638Y292675D01*
X166066D01*
X165742Y292351D01*
X164375D01*
G01X164920Y249877D02*
Y246805D01*
G01X182636Y251569D02*
X181129D01*
X180541Y252157D01*
X178248D01*
G01D02*
X177583Y252822D01*
Y254867D01*
G01X171668Y256287D02*
X173164Y257783D01*
X173177D01*
G01X171668Y256287D02*
X173088Y254867D01*
X173561D01*
G01X175812Y265293D02*
X173750Y267355D01*
X172914D01*
G01X175812Y268049D02*
Y265293D01*
G01X172982Y260548D02*
X170937D01*
X170272Y259883D01*
G01D02*
Y257683D01*
X171668Y256287D01*
G01X172914Y267355D02*
X170646D01*
X170617Y267326D01*
G01X177312Y273113D02*
Y271531D01*
X175812Y270031D01*
Y268049D01*
G01X175118Y274287D02*
X176292Y273113D01*
X177312D01*
G01X170617Y267326D02*
X170607Y267316D01*
X168338D01*
G01X175812Y283689D02*
Y280933D01*
G01X175318Y278687D02*
Y279687D01*
X175812Y280181D01*
Y280933D01*
G01X172982Y278276D02*
X171095Y280163D01*
Y280287D01*
G01X170272Y277611D02*
X170503Y277842D01*
X172548D01*
X172982Y278276D01*
G01X170510Y275522D02*
X170330Y275342D01*
X168647D01*
X168359Y275630D01*
X168321D01*
G01X175830Y296573D02*
X175812D01*
G01D02*
Y299329D01*
G01X172914Y285083D02*
X172918D01*
X174312Y283689D01*
X175812D01*
G01X175162Y293934D02*
X177312Y291784D01*
Y291509D01*
G01X175659Y286984D02*
X175756Y287081D01*
Y287197D01*
X177312Y288753D01*
G01X176037Y309845D02*
Y311988D01*
X175812Y312213D01*
G01Y314969D02*
Y312213D01*
G01X172982Y313732D02*
X174219Y314969D01*
X175812D01*
G01X177312Y307149D02*
X177774D01*
X180254Y309629D01*
Y310663D01*
G01X177312Y304393D02*
Y307149D01*
G01X172914Y302811D02*
X172745Y302642D01*
X168610D01*
X168480Y302772D01*
X168338D01*
G01X168321Y328814D02*
X173058D01*
X173177Y328695D01*
G01D02*
X174019Y327853D01*
X175812D01*
G01X180342Y316469D02*
X177312Y319499D01*
Y320033D01*
G01X172914Y320539D02*
X169500D01*
X169461Y320500D01*
X168338D01*
G01X182335Y339149D02*
Y339474D01*
G01X171320Y343641D02*
X171545Y343866D01*
G01X175812Y330609D02*
Y331006D01*
X177359Y332553D01*
G01X172982Y331460D02*
X173833Y330609D01*
X175812D01*
G01X177359Y332553D02*
Y332391D01*
X178812Y330938D01*
Y330609D01*
G01X172982Y335482D02*
X173809D01*
X174876Y336549D01*
G01X170272Y336147D02*
X170937Y335482D01*
X172982D01*
G01X174876Y336549D02*
X175812Y337485D01*
Y338429D01*
G01X174757Y346866D02*
X171345D01*
X171320Y346841D01*
G01X179515Y346623D02*
X178327Y347811D01*
X177029D01*
G01X186260Y248663D02*
Y251445D01*
X186136Y251569D01*
G01X195311Y254867D02*
X195506Y255062D01*
X198076D01*
G01X193300Y252980D02*
X193424D01*
X195311Y254867D01*
G01X196163Y263697D02*
X194663Y265197D01*
X194395D01*
X193735Y265857D01*
G01X191099Y262197D02*
Y265197D01*
G01Y268197D02*
Y265197D01*
G01X193735Y265857D02*
X193075Y265197D01*
X191099D01*
G01X188504Y254826D02*
Y252705D01*
X188442Y252643D01*
G01X191289Y254867D02*
X191248Y254826D01*
X188504D01*
G01X186136Y251569D02*
X185774Y251931D01*
Y254311D01*
G01X188442Y252643D02*
X187368Y251569D01*
X186136D01*
G01X183279Y257697D02*
Y257711D01*
X184707Y259139D01*
X184829D01*
G01X183279Y257697D02*
Y254572D01*
X183018Y254311D01*
G01D02*
X182636Y253929D01*
Y251569D01*
G01X186312Y275869D02*
Y278720D01*
X185991Y279041D01*
G01X186312Y273113D02*
Y275869D01*
G01X192312Y273113D02*
X191678Y272479D01*
X189950D01*
X189522Y272907D01*
X189518D01*
X189312Y273113D01*
G01X184812Y283689D02*
Y280933D01*
G01X196163Y272697D02*
X195747Y273113D01*
X195592D01*
X194955Y273750D01*
X192949D01*
X192312Y273113D01*
G01X194164Y280933D02*
X196812D01*
G01X194164D02*
X190918Y277687D01*
G01X194164Y280933D02*
X193812D01*
G01X185991Y279041D02*
Y279754D01*
X184812Y280933D01*
G01X183698Y285693D02*
X184812Y284579D01*
Y283689D01*
G01X195312Y291509D02*
X193557Y293264D01*
Y294428D01*
G01X195312Y288753D02*
Y291509D01*
G01X198312Y288753D02*
X195312D01*
G01X196812Y296573D02*
X193812D01*
G01X193557Y294428D02*
Y296318D01*
X193812Y296573D01*
G01X187812Y286352D02*
Y283689D01*
G01X184812Y292979D02*
X186282Y291509D01*
X186312D01*
G01Y288753D02*
X186304Y288761D01*
Y291501D01*
X186312Y291509D01*
G01X184812Y296573D02*
Y299329D01*
G01X186254Y295023D02*
X184812Y296465D01*
Y296573D01*
G01X193812Y299329D02*
X196812D01*
G01X194771Y302176D02*
X194190Y301595D01*
Y299707D01*
X193812Y299329D01*
G01X195312Y307149D02*
X195282D01*
X193812Y308619D01*
G01X195312Y304393D02*
Y307149D01*
G01X190812Y312213D02*
X193812D01*
G01X190812Y314969D02*
Y312213D01*
G01X193812Y308619D02*
X193089Y309342D01*
Y311490D01*
X193812Y312213D01*
G01X184754Y302843D02*
X186304Y304393D01*
X186312D01*
G01Y307149D02*
Y304393D01*
G01X197975Y324149D02*
X195219D01*
G01D02*
Y321149D01*
G01X186312Y322789D02*
X186296Y322805D01*
Y326366D01*
G01X186312Y320033D02*
Y322789D01*
G01X186296Y326366D02*
X186229D01*
X184812Y327783D01*
Y327853D01*
G01X195219Y333149D02*
X197975D01*
G01X185195Y332852D02*
X186196D01*
X187399Y331649D01*
G01X190155D02*
X187399D01*
G01X184367Y337792D02*
X183472D01*
X182335Y338929D01*
Y339149D01*
G01X187829Y346640D02*
Y347172D01*
X189496Y348839D01*
G01X190500Y394605D02*
X187094D01*
X186653Y394164D01*
X183419D01*
G01X180430Y392969D02*
Y392974D01*
X181260Y393804D01*
X183059D01*
X183419Y394164D01*
G01X180440Y398056D02*
Y398047D01*
X181168Y397319D01*
X183419D01*
Y397314D01*
G01D02*
X186406D01*
X186556Y397164D01*
X190500D01*
G01X198685Y240785D02*
X196685Y242785D01*
Y244914D01*
X198031Y246260D01*
X198964D01*
G01X203988Y248663D02*
Y251445D01*
X203864Y251569D01*
G01X211935Y244085D02*
X211028Y244992D01*
Y246260D01*
G01X203983Y265197D02*
X206739D01*
G01X203864Y251569D02*
X204772Y252477D01*
X206144D01*
G01X203502Y254311D02*
X204017Y254826D01*
X206232D01*
G01X206144Y252477D02*
X206232Y252565D01*
Y254826D01*
G01X198076Y255062D02*
X198827Y254311D01*
X200746D01*
G01X198919Y263697D02*
X196163D01*
G01X201667Y274542D02*
X200602D01*
X199447Y275697D01*
X198919D01*
G01X196163D02*
X198919D01*
G01Y272697D02*
X196258D01*
X196212Y272744D01*
X196210D01*
X196163Y272697D01*
G01X199509Y278094D02*
X199812Y278397D01*
Y280933D01*
G01X196812Y283689D02*
Y280933D01*
G01D02*
X199812D01*
G01X204724Y279523D02*
X201968Y276767D01*
X201574D01*
G01D02*
X201667Y276674D01*
Y274542D01*
G01X203983Y274197D02*
Y275632D01*
X205118Y276767D01*
G01X209449Y281098D02*
X207874Y279523D01*
G01X206739Y274197D02*
X203983D01*
G01X207874Y276767D02*
Y275332D01*
X207524Y274981D01*
X206739Y274197D01*
G01X207874Y279523D02*
Y276767D01*
G01Y282673D02*
X206299Y281098D01*
G01X204724Y282673D02*
X204503D01*
X203149Y281319D01*
Y281098D01*
G01X201412Y294265D02*
X199812Y295865D01*
Y296573D01*
G01D02*
X196812D01*
G01X201068Y288753D02*
X198312D01*
G01X209449Y287398D02*
X207874Y285823D01*
G01X203149Y287398D02*
X204724Y285823D01*
G01X212599Y287398D02*
X211024Y285823D01*
G01X207874Y288973D02*
X207591D01*
X206299Y290265D01*
Y290548D01*
G01X204724Y288973D02*
X203149Y290548D01*
G01X206299Y293698D02*
X207874Y295273D01*
G01X196812Y299329D02*
X199812D01*
G01D02*
Y300037D01*
X201412Y301637D01*
G01D02*
X201476Y301573D01*
X204724D01*
G01D02*
Y301894D01*
X204299Y302319D01*
Y304298D01*
X204724Y304723D01*
G01Y298423D02*
Y301573D01*
G01X206299Y312598D02*
X204724Y314173D01*
G01X201412Y309905D02*
Y310613D01*
X199812Y312213D01*
G01Y314969D02*
Y312213D01*
G01X207874Y314173D02*
X206299Y312598D01*
G01X196812Y312213D02*
X197012Y312413D01*
X199612D01*
X199812Y312213D01*
G01X201068Y307149D02*
Y304393D01*
G01X198312Y307149D02*
X198282D01*
X196812Y308619D01*
G01X198312Y304393D02*
Y307149D01*
G01X211024Y307873D02*
X211042D01*
X212610Y306305D01*
G01X207874Y307873D02*
Y307842D01*
X210993D01*
X211024Y307873D01*
G01X204724D02*
X205193Y308342D01*
X207405D01*
X207874Y307873D01*
G01X196812Y308619D02*
X197254D01*
X198880Y310245D01*
G01X201068Y307149D02*
X204000D01*
X204724Y307873D01*
G01X201068Y307149D02*
X198312D01*
G01Y304393D02*
X201068D01*
G01X207874Y301573D02*
X206299Y303148D01*
G01X204724Y311023D02*
X204720D01*
X203166Y312577D01*
G01X205795Y328649D02*
X203039D01*
G01X207310Y330149D02*
Y330110D01*
X205849Y328649D01*
X205795D01*
G01X213615Y333149D02*
X210859D01*
G01X200905Y333776D02*
X200937Y333744D01*
X200342Y333149D01*
X197975D01*
G01X201489Y336207D02*
X201597D01*
X201878Y336487D01*
X203039Y337649D01*
G01X205795D02*
X203039D01*
G01X201489Y339107D02*
X202997Y340615D01*
X204269D01*
X205080Y341425D01*
X205142Y341487D01*
X205438Y341784D01*
G01X221592Y251569D02*
X221716Y251445D01*
Y248663D01*
G01X217135Y244085D02*
X216692Y244528D01*
Y246260D01*
G01X228756D02*
X228290D01*
X227517Y245487D01*
Y244187D01*
G01X222379Y265197D02*
Y265189D01*
X223929Y263639D01*
G01X227443Y263697D02*
Y263821D01*
X226067Y265197D01*
X225973D01*
G01X230767Y254867D02*
X226745D01*
G01X227443Y275697D02*
X226826D01*
X224357Y273228D01*
G01X227443Y272697D02*
X224888D01*
X224357Y273228D01*
G01X225199Y284248D02*
X223624Y282673D01*
G01X217324Y285823D02*
X220474D01*
G01X223624Y295273D02*
Y295212D01*
X225160Y293676D01*
G01X226774Y298423D02*
X223624Y295273D01*
G01X226774Y292123D02*
X226713D01*
X225160Y293676D01*
G01X220474Y292123D02*
X217324D01*
G01X225199Y290548D02*
X223624Y288973D01*
G01X226774Y292123D02*
X225199Y290548D01*
G01X215749Y293698D02*
X217324Y295273D01*
G01X215749Y287398D02*
X217324Y288973D01*
G01X229924Y314173D02*
X226774Y311023D01*
G01Y304723D02*
X225199Y306298D01*
G01D02*
X223624Y307873D01*
G01X220474Y304723D02*
X222049Y306298D01*
G01X214174Y307873D02*
Y307869D01*
X212610Y306305D01*
G01X218899Y299998D02*
X217324Y298423D01*
G01Y301573D02*
X218899Y303148D01*
G01X225199Y315748D02*
X226774Y317323D01*
G01D02*
X226499Y317598D01*
Y321149D01*
G01Y324149D02*
X226484D01*
G01D02*
X226300D01*
X225143Y322992D01*
X224585D01*
G01X226499Y321149D02*
X226428D01*
X224585Y322992D01*
G01X215010Y342047D02*
X214971Y342086D01*
Y346623D01*
G01X221435Y331649D02*
X218679D01*
G01X226499Y333149D02*
X224221Y330871D01*
X222338D01*
X221560Y331649D01*
X221435D01*
G01X229255Y330149D02*
X229103D01*
X227710Y331542D01*
Y331938D01*
X226499Y333149D01*
G01X233413Y250206D02*
Y252281D01*
X233904Y252772D01*
G01X233532Y255062D02*
X234150D01*
X236205Y257117D01*
X239047D01*
X239569Y257639D01*
G01X236202Y254471D02*
Y254311D01*
G01X233904Y252772D02*
X234503D01*
X236202Y254471D01*
G01X233793Y257697D02*
X233727D01*
X230897Y254867D01*
X230767D01*
G01X230199Y263697D02*
X227443D01*
G01X238958Y254311D02*
X238182Y255087D01*
X236818D01*
X236202Y254471D01*
G01X235263Y265197D02*
X235167D01*
X233793Y266571D01*
Y266697D01*
G01X238019Y265197D02*
X235263D01*
G01X245839Y263697D02*
X243083D01*
G01D02*
Y263881D01*
X241767Y265197D01*
X241613D01*
G01X227443Y266697D02*
Y269697D01*
G01X235263Y274197D02*
Y271197D01*
G01Y268197D02*
Y268227D01*
X233793Y269697D01*
G01D02*
X235263Y271167D01*
Y271197D01*
G01X233074Y279523D02*
X234649Y281098D01*
G01D02*
X236224Y279523D01*
G01X242524D02*
X244099Y281098D01*
G01X239374Y279523D02*
Y279622D01*
X237865Y281131D01*
G01D02*
X237832D01*
X236224Y279523D01*
G01X239374D02*
X242524D01*
G01X239569Y269639D02*
X238019Y271189D01*
Y271197D01*
G01D02*
Y274197D01*
G01X230199Y272697D02*
X231749Y271147D01*
Y271218D01*
X232118Y271587D01*
G01X230199Y269697D02*
X230307D01*
X232118Y271508D01*
Y271587D01*
G01X243083Y272697D02*
Y272667D01*
X241613Y271197D01*
G01X243083Y269697D02*
Y269727D01*
X241613Y271197D01*
G01X237760Y293692D02*
X237805D01*
X239374Y292123D01*
G01X242524Y295273D02*
X244099Y296848D01*
G01X242524Y288973D02*
X240949Y290548D01*
G01X237799Y287398D02*
X239374Y285823D01*
G01X244099Y287398D02*
X242524Y285823D01*
G01X229924Y298423D02*
X231499Y296848D01*
G01X229924Y288973D02*
Y289057D01*
X231450Y290583D01*
G01X233074Y292123D02*
X232990D01*
X231450Y290583D01*
G01X242524Y288973D02*
X242578D01*
X244110Y290505D01*
G01X242524Y288973D02*
X240949Y287398D01*
G01X242524Y288973D02*
X244099Y287398D01*
G01X236224Y295273D02*
Y295228D01*
X237760Y293692D01*
G01X239374Y292123D02*
X240949Y290548D01*
G01X233074Y311023D02*
X236224Y314173D01*
G01X237799Y312598D02*
X239374Y314173D01*
G01X242524Y311023D02*
X245674Y314173D01*
G01X233074Y307873D02*
X236224Y311023D01*
G01X229924Y307873D02*
Y307640D01*
X230947Y306617D01*
X231818D01*
X233074Y307873D01*
G01X236224Y311023D02*
X237799Y312598D01*
G01X236224Y314173D02*
Y317323D01*
G01D02*
X235830Y317717D01*
Y320079D01*
G01X241258Y319123D02*
X240302Y320079D01*
X239374D01*
G01X241258Y319123D02*
X242524Y317857D01*
Y317323D01*
G01X241258Y319123D02*
X239458Y317323D01*
X239374D01*
G01X229255Y327149D02*
Y330149D01*
G01Y321149D02*
X228934Y320828D01*
Y318313D01*
X229924Y317323D01*
G01D02*
Y314173D01*
G01X242139Y321149D02*
Y320004D01*
X241258Y319123D01*
G01X237075Y325649D02*
Y322649D01*
G01D02*
X237984D01*
X239374Y321259D01*
Y320079D01*
G01X237075Y322649D02*
X237057D01*
X235830Y321422D01*
Y320079D01*
G01X233074D02*
Y320235D01*
X231567Y321742D01*
G01X234319Y322649D02*
X232474D01*
X231567Y321742D01*
G01X234319Y325649D02*
Y322649D01*
G01X232782Y327096D02*
X234229Y325649D01*
X234319D01*
G01X233074Y317323D02*
Y320079D01*
G01X234319Y328649D02*
Y328633D01*
X232782Y327096D01*
G01X229255Y324149D02*
Y324179D01*
X230725Y325649D01*
G01X237075Y328649D02*
Y328619D01*
X238545Y327149D01*
G01X242139Y324149D02*
X241879D01*
X240511Y325517D01*
G01X242139Y330149D02*
X241563D01*
X240374Y328960D01*
G01X242139Y327149D02*
Y327195D01*
X240374Y328960D01*
G01X242139Y327149D02*
Y327145D01*
X240511Y325517D01*
G01X243659Y341979D02*
Y344024D01*
X242994Y344689D01*
G01D02*
X242509Y344204D01*
X240692D01*
G01X235468Y342535D02*
X235106Y342897D01*
Y345277D01*
G01X234319Y331649D02*
X233515Y330845D01*
X231529D01*
X230725Y331649D01*
G01X244895Y333149D02*
X242139D01*
G01D02*
X242109D01*
X239932Y330972D01*
X237752D01*
X237075Y331649D01*
G01D02*
X234319D01*
G01X230725D02*
X229647Y332727D01*
Y332757D01*
X229255Y333149D01*
G01X240692Y344204D02*
X239679D01*
X238606Y345277D01*
G01X234982Y348183D02*
Y349210D01*
X233606Y350586D01*
G01X235106Y345277D02*
Y345493D01*
X235199Y345586D01*
Y347660D01*
X234982Y347877D01*
Y348183D01*
G01X242680Y348839D02*
Y348873D01*
X242406Y349147D01*
Y353216D01*
X241848Y353774D01*
G01X241503Y529366D02*
X239925Y527788D01*
G01X241503Y529368D02*
Y529366D01*
G01Y526217D02*
X239925Y524639D01*
G01X241503Y526219D02*
Y526217D01*
G01X241494Y526219D02*
X239925Y527788D01*
G01X241503Y526219D02*
X241494D01*
G01X250903Y265197D02*
Y265417D01*
X250188Y266132D01*
X248274D01*
X245839Y263697D01*
G01Y272697D02*
Y269697D01*
G01X244099Y281098D02*
X245674Y279523D01*
G01X250399Y281098D02*
X251974Y279523D01*
G01X245674D02*
X248824D01*
G01X247249Y296848D02*
X248824Y295273D01*
G01X255630Y292453D02*
Y292235D01*
X253943Y290548D01*
X253549D01*
G01X258386Y292453D02*
X255630D01*
G01X245674Y292123D02*
Y292069D01*
X244110Y290505D01*
G01X244099Y287398D02*
X245674Y285823D01*
G01X258386Y308093D02*
X258455D01*
X259977Y309615D01*
X260045D01*
G01X255630Y305337D02*
X255498D01*
X254016Y306819D01*
X254007D01*
G01X252715Y322649D02*
Y321972D01*
X251580Y320837D01*
Y320079D01*
G01D02*
Y319036D01*
X251974Y318642D01*
Y317323D01*
G01X244895Y324149D02*
Y327149D01*
G01Y321149D02*
Y324149D01*
G01Y327149D02*
Y330149D01*
G01X257779Y324149D02*
X257773D01*
X256276Y322652D01*
G01X255124Y320079D02*
Y321500D01*
X256276Y322652D01*
G01D02*
X257779Y321149D01*
G01X260535Y330149D02*
X257779D01*
G01X250466Y344381D02*
Y342047D01*
G01X244895Y330149D02*
X245258Y330512D01*
X247025D01*
G01X250952Y513618D02*
X249374Y512040D01*
G01X250952Y513620D02*
Y513618D01*
G01X247802D02*
X246224Y512040D01*
G01X247802Y513620D02*
Y513618D01*
G01X250943Y548266D02*
X249374Y549835D01*
G01X250952Y548266D02*
X250943D01*
G01X247805D02*
X249374Y549835D01*
G01X247802Y548266D02*
X247805D01*
G01X266543Y265197D02*
X265073Y266667D01*
Y266697D01*
G01X263029Y265139D02*
X261587Y263697D01*
X261479D01*
G01X271886Y284633D02*
Y281877D01*
G01X270386Y276813D02*
X270394D01*
X271944Y278363D01*
G01X273386Y274057D02*
X273416D01*
X274886Y272587D01*
G01X270386Y274057D02*
X270416D01*
X271886Y272587D01*
G01X264386Y276813D02*
X264394D01*
X265944Y278363D01*
G01X264386Y276813D02*
X263270Y275697D01*
X261479D01*
G01X267386Y274057D02*
X267416D01*
X268886Y272587D01*
G01X264386Y274057D02*
X267386D01*
G01X265886Y268993D02*
X268886D01*
G01X265886D02*
X265073Y268180D01*
Y266697D01*
G01X268886Y268993D02*
X268894D01*
X270444Y270543D01*
G01D02*
X271886Y269101D01*
Y268993D01*
G01X274886Y272587D02*
X276356Y274057D01*
X276386D01*
G01X264386Y296047D02*
X262916Y297517D01*
G01D02*
X262886D01*
G01Y300273D02*
Y297517D01*
G01X271886D02*
X271300Y296931D01*
G01D02*
Y293367D01*
G01D02*
X270386Y292453D01*
G01X271886Y297517D02*
Y300273D01*
G01X270386Y289697D02*
X271218Y290529D01*
G01D02*
Y291621D01*
G01D02*
X270386Y292453D01*
G01Y308093D02*
X270394D01*
X271944Y309643D01*
G01X271886Y315913D02*
Y313157D01*
G01X270386Y305337D02*
Y308093D01*
G01X271811Y303313D02*
X271886Y303238D01*
G01D02*
Y300273D01*
G01X271944Y309643D02*
X273018Y310717D01*
Y312157D01*
X272018Y313157D01*
X271886D01*
G01X262944Y309643D02*
X261394Y308093D01*
X261386D01*
G01Y305337D02*
Y308093D01*
G01Y311687D02*
X262856Y313157D01*
X262886D01*
G01Y315913D02*
Y313157D01*
G01X264386Y323733D02*
X263332Y322679D01*
X262035D01*
G01D02*
X260535Y321179D01*
Y321149D01*
G01X261387Y341979D02*
X262495D01*
X263576Y340898D01*
G01X260722Y344689D02*
Y344679D01*
X261582Y343819D01*
Y342174D01*
X261387Y341979D01*
G01X263576Y340898D02*
X263003D01*
X262295Y340190D01*
X261576D01*
X260535Y339149D01*
G01X263550Y513612D02*
X265122Y512040D01*
G01X263550Y513620D02*
Y513612D01*
G01X260401Y513611D02*
X261972Y512040D01*
G01X260401Y513620D02*
Y513611D01*
G01X260402Y548266D02*
X261972Y549836D01*
G01X260401Y548266D02*
X260402D01*
G01X263552D02*
X265122Y549836D01*
G01X263542Y548266D02*
X261972Y549836D01*
G01X263550Y548266D02*
X263542D01*
G01X263552D02*
X263550D01*
G01X288578Y246805D02*
Y245583D01*
X290154Y244007D01*
G01X281941Y249980D02*
X282098D01*
X283660Y251542D01*
G01X278978Y246805D02*
Y244905D01*
X278354Y244281D01*
G01X283660Y251542D02*
X285197Y250005D01*
X285378D01*
G01X282178Y246805D02*
Y244005D01*
G01X290154Y244007D02*
X291778Y245631D01*
Y246805D01*
G01X288578Y250005D02*
X285378Y246805D01*
G01X283716Y265386D02*
X283521Y265581D01*
Y268151D01*
G01X285603Y263375D02*
X283716Y265262D01*
Y265386D01*
G01X288577Y258618D02*
Y260411D01*
X288954Y260788D01*
G01X288577Y258618D02*
X290791D01*
X291778Y259605D01*
G01X287014Y256311D02*
Y257842D01*
X286492Y258364D01*
G01X291778Y253205D02*
X288578D01*
G01D02*
Y255012D01*
X289254Y255688D01*
G01X284272Y255849D02*
X286552D01*
X287014Y256311D01*
G01X281954Y255588D02*
Y257349D01*
X280886Y258417D01*
G01X281954Y255588D02*
Y252993D01*
X281941Y252980D01*
G01X283660Y251542D02*
X285323Y253205D01*
X285378D01*
G01X288954Y260788D02*
X286515D01*
X286426Y260699D01*
G01X289254Y255688D02*
X289971Y256405D01*
X291778D01*
G01X279386Y274057D02*
X279356D01*
X277886Y272587D01*
G01X279386Y276813D02*
Y274057D01*
G01X284272Y273577D02*
X281876D01*
X280886Y272587D01*
G01X284272Y273577D02*
Y270821D01*
G01X286010Y276042D02*
X286596Y276628D01*
Y278471D01*
G01X290366Y278263D02*
X290158Y278471D01*
X286596D01*
G01X283716Y283114D02*
Y281991D01*
G01D02*
X282867Y281142D01*
G01D02*
Y280097D01*
G01D02*
X283716Y279248D01*
G01D02*
Y279092D01*
G01X283784Y294035D02*
X280968D01*
G01D02*
X279386Y292453D01*
G01X280886Y297517D02*
X282707Y299338D01*
G01X279386Y289697D02*
Y292453D01*
G01X288360Y294074D02*
X288917Y293517D01*
X290700D01*
X291050Y293167D01*
X292323D01*
G01X283521Y285879D02*
Y284698D01*
G01D02*
X283716Y284503D01*
G01D02*
Y283114D01*
G01X283521Y285879D02*
Y287798D01*
G01D02*
X284272Y288549D01*
G01X285890Y311357D02*
X286596Y312063D01*
Y313719D01*
G01X279386Y305337D02*
Y308093D01*
G01X280886Y313157D02*
X280856D01*
X279386Y311687D01*
G01X282707Y299338D02*
Y299833D01*
G01D02*
X283716Y300842D01*
G01X280886Y315913D02*
Y313157D01*
G01X289927Y305871D02*
X290218Y305580D01*
X291450D01*
X292323Y304707D01*
Y304495D01*
G01X294781Y309788D02*
X294228Y309235D01*
X290204D01*
X289920Y309519D01*
G01X279386Y311687D02*
Y310919D01*
X279875Y310430D01*
Y308582D01*
X279386Y308093D01*
G01X283521Y321335D02*
X283112Y321744D01*
X281461D01*
G01D02*
X280694Y320977D01*
X279386D01*
G01X283716Y314548D02*
X284337Y313927D01*
X286596D01*
G01D02*
Y313719D01*
G01X290366D02*
X286596D01*
G01X287014Y327123D02*
X288360Y328469D01*
Y329530D01*
G01X279386Y323733D02*
X280067Y324414D01*
Y325703D01*
X280776Y326412D01*
G01D02*
X283784Y329420D01*
Y329491D01*
G01X276149Y504171D02*
Y504104D01*
X277658Y502595D01*
X277712D01*
G01X285598Y501022D02*
Y501020D01*
X287173Y499445D01*
G01X276151Y519919D02*
X277725Y521493D01*
G01X276149Y519919D02*
X276151D01*
G01X276149Y523069D02*
X277725Y521493D01*
G01X291778Y250005D02*
Y246805D01*
G01X294510Y280709D02*
X294116Y281103D01*
X292323D01*
G01Y275439D02*
X295307D01*
G01X297782Y291966D02*
X295731Y294017D01*
X293173D01*
X292323Y293167D01*
G01Y286767D02*
X295010D01*
G01X419038Y242611D02*
X417919D01*
X416805Y243725D01*
X412330D01*
G01X422178Y266891D02*
X418658D01*
X417146Y265379D01*
X412330D01*
G01X405688Y253581D02*
X405698Y253571D01*
X410618D01*
X410628Y253561D01*
X412330D01*
Y253569D01*
G01X418597Y273538D02*
Y272720D01*
X417161Y271284D01*
X412330D01*
G01X418698Y279631D02*
Y278481D01*
X417407Y277190D01*
X412330D01*
G01X418998Y289871D02*
X418278D01*
X417408Y289001D01*
X412330D01*
G01X418718Y301181D02*
Y301172D01*
X418358Y300812D01*
X412330D01*
G01X428208Y262109D02*
Y263101D01*
X429278Y264171D01*
Y264421D01*
X429918Y265061D01*
X430168D01*
X430486Y265379D01*
X434882D01*
G01Y253569D02*
X427768D01*
G01X426948Y281051D02*
X427590D01*
X429634Y283095D01*
X434882D01*
G01X422918Y289501D02*
X428608D01*
X429108Y289001D01*
X434882D01*
G01X442148Y279361D02*
X439977Y277190D01*
X434882D01*
G01Y271284D02*
X442165D01*
G01X434882Y294906D02*
X441076D01*
G01X434882Y300812D02*
X441361D01*
G01X491413Y214434D02*
X491855Y214876D01*
X498701D01*
G01X492700Y223800D02*
X493581Y224681D01*
X498778D01*
G01X488142Y223746D02*
X492646D01*
X492700Y223800D01*
G01X558845Y158697D02*
X561542Y156000D01*
X567278D01*
X568200Y155078D01*
X573117D01*
X175572Y249980D03*
X178812Y257697D03*
X169684Y255495D03*
X168121Y257802D03*
X170272Y259883D03*
X172982Y260548D03*
X173177Y257783D03*
X177312Y260229D03*
X175812Y265293D03*
X178812D03*
X171095Y262559D03*
X168095Y262759D03*
X166332Y265399D03*
X170102Y265191D03*
X172982Y264570D03*
X175572Y252980D03*
X177583Y254867D03*
X178248Y252157D03*
X173561Y254867D03*
X177312Y273113D03*
Y275869D03*
X175812Y268049D03*
X178812D03*
X166778Y269599D03*
X169684Y269723D03*
X168338Y267316D03*
X172426Y270085D03*
X172914Y267355D03*
X172426Y272841D03*
X173177Y275511D03*
X169684Y273223D03*
X168321Y275630D03*
X166771Y273247D03*
X172982Y278276D03*
X170272Y277611D03*
X166122Y277297D03*
X168095Y280487D03*
X171095Y280287D03*
X178812Y280933D03*
X175812D03*
X177312Y288753D03*
X172914Y285083D03*
X168338Y285044D03*
X166332Y283127D03*
X178812Y283689D03*
X175812D03*
X172982Y282298D03*
X170102Y282919D03*
X172426Y287813D03*
X169684Y287451D03*
X166778Y287327D03*
X166771Y290975D03*
X172426Y290569D03*
X173177Y293239D03*
X168321Y293358D03*
X169684Y290951D03*
X177312Y291509D03*
X170272Y295339D03*
X166122Y295025D03*
X172982Y296004D03*
X175812Y296573D03*
X178812D03*
X168095Y298215D03*
X171095Y298015D03*
X172982Y300026D03*
X175812Y299329D03*
X178812D03*
X177312Y304393D03*
Y307149D03*
X168338Y302772D03*
X170102Y300647D03*
X166332Y300855D03*
X172914Y302811D03*
X166771Y308703D03*
X172426Y308297D03*
Y305541D03*
X173177Y310967D03*
X168321Y311086D03*
X169684Y308679D03*
Y305179D03*
X166778Y305055D03*
X178812Y312213D03*
X175812D03*
X170272Y313067D03*
X166122Y312753D03*
X178812Y314969D03*
X175812D03*
X172982Y313732D03*
X177312Y320033D03*
Y322789D03*
X175812Y327853D03*
X178812D03*
X172914Y320539D03*
X172982Y317754D03*
X168338Y320500D03*
X170102Y318375D03*
X166332Y318583D03*
X168095Y315943D03*
X171095Y315743D03*
X166771Y326431D03*
X172426Y323269D03*
X169684Y322907D03*
X166778Y322783D03*
X169684Y326407D03*
X168321Y328814D03*
X173177Y328695D03*
X172426Y326025D03*
X175812Y338429D03*
Y330609D03*
X178812D03*
X166122Y330481D03*
X170272Y330795D03*
X172982Y331460D03*
X171095Y333471D03*
X168095Y333671D03*
X170272Y336147D03*
X168121Y338228D03*
X172982Y335482D03*
X172914Y338267D03*
X172426Y340997D03*
X169684Y340535D03*
X179554Y342047D03*
X176768Y341979D03*
X179579Y336149D03*
Y339149D03*
X174757Y343866D03*
X177433Y344689D03*
X179515Y346623D03*
X174757Y346866D03*
X193100Y249980D03*
X180229Y250206D03*
X188543Y250223D03*
X182612Y248656D03*
X186260Y248663D03*
X190460Y248217D03*
X182636Y251569D03*
X186136D03*
X190668Y251987D03*
X180312Y260229D03*
X181812Y265293D03*
X193300Y252980D03*
X195311Y254867D03*
X191289D03*
X183279Y260697D03*
Y257697D03*
X191099Y259197D03*
Y265197D03*
Y262197D03*
X188343Y259197D03*
Y265197D03*
Y262197D03*
X180348Y255062D03*
X183018Y254311D03*
X185774D03*
X188504Y254826D03*
X189312Y273113D03*
Y275869D03*
X186312D03*
X183312D03*
X186312Y273113D03*
X183312D03*
X192312Y275869D03*
Y273113D03*
X187812Y268049D03*
X184812D03*
X180312Y275869D03*
Y273113D03*
X181812Y268049D03*
Y280933D03*
X184812D03*
X187812D03*
X190812D03*
X193812D03*
X191099Y268197D03*
X195312Y291509D03*
Y288753D03*
X180312D03*
Y291509D03*
X183312Y288753D03*
X186312D03*
X183312Y291509D03*
X186312D03*
X189312D03*
Y288753D03*
X192312D03*
Y291509D03*
X181812Y283689D03*
X184812D03*
X187812D03*
X190812D03*
X193812D03*
X181812Y296573D03*
X190812D03*
X187812D03*
X184812D03*
X193812D03*
X181812Y299329D03*
X190812D03*
X187812D03*
X184812D03*
X193812D03*
X195312Y304393D03*
Y307149D03*
X180312D03*
Y304393D03*
X189312D03*
Y307149D03*
X186312D03*
X183312D03*
X186312Y304393D03*
X183312D03*
X192312Y307149D03*
Y304393D03*
X181812Y312213D03*
X184812D03*
X187812D03*
X190812D03*
X193812D03*
X181812Y314969D03*
X184812D03*
X187812D03*
X190812D03*
X193812D03*
X183312Y320033D03*
X186312D03*
X189312D03*
X181812Y327853D03*
X183312Y322789D03*
X186312D03*
X189312D03*
X184812Y327853D03*
X187812D03*
X190812D03*
X192312Y320033D03*
Y322789D03*
X180312Y320033D03*
Y322789D03*
X195219Y321149D03*
Y324149D03*
Y327149D03*
X190475Y341979D03*
X187710Y341784D03*
X187399Y334649D03*
Y331649D03*
X190155Y334649D03*
Y331649D03*
Y337649D03*
X187399D03*
X182335Y333149D03*
Y336149D03*
Y339149D03*
X189810Y344689D03*
X194497Y341979D03*
X192486Y343866D03*
X182284Y342535D03*
X185040D03*
X195219Y330149D03*
Y333149D03*
Y336149D03*
Y339149D03*
X195118Y344859D03*
X189496Y348839D03*
X192686Y346866D03*
X185446Y348190D03*
X181922Y345277D03*
X185422D03*
X187829Y346640D03*
X181798Y348183D03*
X195326Y348629D03*
X210828Y249980D03*
X197957Y250206D03*
X206271Y250223D03*
X196290Y248007D03*
X200340Y248656D03*
X208188Y248217D03*
X203988Y248663D03*
X200364Y251569D03*
X208396Y251987D03*
X203864Y251569D03*
X211028Y252980D03*
X196163Y263697D03*
Y257697D03*
Y260697D03*
X198919Y263697D03*
Y257697D03*
Y260697D03*
X206739Y262197D03*
Y265197D03*
Y259197D03*
X203983Y262197D03*
Y265197D03*
Y259197D03*
X195976Y252157D03*
X200746Y254311D03*
X203502D03*
X198076Y255062D03*
X209017Y254867D03*
X206232Y254826D03*
X196812Y280933D03*
X199812D03*
X205118Y276767D03*
X201574D03*
X207874D03*
X196163Y275697D03*
Y272697D03*
Y269697D03*
X198919Y275697D03*
Y272697D03*
Y269697D03*
X206739Y268197D03*
Y271197D03*
Y274197D03*
X203983Y268197D03*
Y271197D03*
Y274197D03*
X196163Y266697D03*
X198919D03*
X198312Y288753D03*
Y291509D03*
X201068Y288753D03*
Y291509D03*
X201412Y294265D03*
Y285997D03*
X196812Y283689D03*
X199812D03*
X196812Y296573D03*
X199812D03*
X196812Y299329D03*
X199812D03*
X201412Y301637D03*
X201068Y304393D03*
Y307149D03*
X201412Y309905D03*
X198312Y307149D03*
Y304393D03*
X196812Y312213D03*
X199812D03*
X196812Y314969D03*
X199812D03*
X210859Y321149D03*
Y327149D03*
Y324149D03*
X207874Y320079D03*
X204724D03*
X201968D03*
X205795Y322649D03*
X203039D03*
Y325649D03*
X205795D03*
Y328649D03*
X203039D03*
X197975Y321149D03*
Y324149D03*
Y327149D03*
X201868Y317323D03*
X197282Y342047D03*
X205438Y341784D03*
X208203Y341979D03*
X210859Y336149D03*
Y333149D03*
Y330149D03*
Y339149D03*
X203039Y337649D03*
X205795D03*
Y331649D03*
Y334649D03*
X203039Y331649D03*
Y334649D03*
X197975Y330149D03*
Y333149D03*
Y336149D03*
Y339149D03*
X200012Y342535D03*
X207538Y344689D03*
X202768Y342535D03*
X210214Y343866D03*
X203174Y348190D03*
X197243Y346623D03*
X199650Y345277D03*
X199526Y348183D03*
X207224Y348839D03*
X205557Y346640D03*
X203150Y345277D03*
X210414Y346866D03*
X223999Y250223D03*
X215685Y250206D03*
X214018Y248007D03*
X218068Y248656D03*
X221716Y248663D03*
X225916Y248217D03*
X221592Y251569D03*
X218092D03*
X222379Y259197D03*
X219623D03*
Y265197D03*
Y262197D03*
X222379Y265197D03*
Y262197D03*
X214559Y260697D03*
Y257697D03*
Y263697D03*
X211803Y260697D03*
Y257697D03*
Y263697D03*
X213704Y252157D03*
X213039Y254867D03*
X223960Y254826D03*
X215804Y255062D03*
X221230Y254311D03*
X218474D03*
X226124Y251987D03*
X226745Y254867D03*
X220868Y276767D03*
X211803Y275697D03*
X214559D03*
X217324Y276767D03*
X223624D03*
X219623Y274197D03*
X222379D03*
Y271197D03*
X219623D03*
Y268197D03*
X222379D03*
X214559Y269697D03*
Y272697D03*
X211803Y269697D03*
Y272697D03*
X214559Y266697D03*
X211803D03*
X217324Y320079D03*
X223624D03*
X220080D03*
X218679Y328649D03*
X221435D03*
Y325649D03*
X218679D03*
Y322649D03*
X221435D03*
X213615Y321149D03*
Y327149D03*
Y324149D03*
X226499Y321149D03*
Y324149D03*
Y327149D03*
X223166Y341784D03*
X215010Y342047D03*
X212225Y341979D03*
X218679Y334649D03*
Y331649D03*
X221435Y334649D03*
Y331649D03*
Y337649D03*
X218679D03*
X213615Y336149D03*
Y333149D03*
Y330149D03*
Y339149D03*
X212846Y344859D03*
X217740Y342535D03*
X220496D03*
X225931Y341979D03*
X226499Y330149D03*
Y333149D03*
Y336149D03*
Y339149D03*
X225266Y344689D03*
X220902Y348190D03*
X213054Y348629D03*
X217254Y348183D03*
X224952Y348839D03*
X217378Y345277D03*
X220878D03*
X223285Y346640D03*
X214971Y346623D03*
X233413Y250206D03*
X241727Y250223D03*
X228556Y249980D03*
X235796Y248656D03*
X239444Y248663D03*
X231746Y248007D03*
X239320Y251569D03*
X235820D03*
X243083Y260697D03*
Y257697D03*
Y263697D03*
X230199D03*
Y257697D03*
Y260697D03*
X238019Y262197D03*
Y265197D03*
X235263Y262197D03*
Y265197D03*
Y259197D03*
X238019D03*
X231432Y252157D03*
X233532Y255062D03*
X230767Y254867D03*
X238958Y254311D03*
X236202D03*
X241688Y254826D03*
X228756Y252980D03*
X227443Y263697D03*
Y257697D03*
Y260697D03*
X236618Y276767D03*
X230199Y275697D03*
X243083D03*
X233074Y276767D03*
X239374D03*
X243083Y269697D03*
Y272697D03*
X230199D03*
Y269697D03*
X238019Y268197D03*
X235263D03*
Y271197D03*
X238019D03*
Y274197D03*
X235263D03*
X243083Y266697D03*
X230199D03*
X227443Y275697D03*
Y272697D03*
Y269697D03*
Y266697D03*
X242139Y321149D03*
Y327149D03*
Y324149D03*
X233074Y320079D03*
X239374D03*
X235830D03*
X237075Y322649D03*
X234319D03*
Y325649D03*
X237075D03*
Y328649D03*
X234319D03*
X229255Y321149D03*
Y324149D03*
Y327149D03*
X229953Y341979D03*
X232738Y342020D03*
X240894Y341784D03*
X242139Y336149D03*
Y333149D03*
Y330149D03*
Y339149D03*
X234319Y337649D03*
X237075D03*
Y331649D03*
Y334649D03*
X234319Y331649D03*
Y334649D03*
X229255Y330149D03*
Y333149D03*
Y336149D03*
Y339149D03*
X227942Y343866D03*
X242994Y344689D03*
X230574Y344859D03*
X235468Y342535D03*
X238224D03*
X228142Y346866D03*
X238630Y348190D03*
X242680Y348839D03*
X230782Y348629D03*
X234982Y348183D03*
X232699Y346623D03*
X235106Y345277D03*
X238606D03*
X241013Y346640D03*
X251141Y250206D03*
X253524Y248656D03*
X249474Y248007D03*
X246284Y249980D03*
X243644Y248217D03*
X257172Y248663D03*
X253548Y251569D03*
X243852Y251987D03*
X253659Y259197D03*
X250903D03*
Y265197D03*
Y262197D03*
X253659Y265197D03*
Y262197D03*
X249160Y252157D03*
X251260Y255062D03*
X248495Y254867D03*
X253930Y254311D03*
X246484Y252980D03*
X245839Y260697D03*
Y257697D03*
Y263697D03*
X244473Y254867D03*
X257048Y251569D03*
X258723Y263697D03*
Y257697D03*
Y260697D03*
X256686Y254311D03*
X254830Y279523D03*
X254730Y276767D03*
X251974D03*
X248824D03*
X250903Y274197D03*
X253659D03*
Y271197D03*
X250903D03*
Y268197D03*
X253659D03*
X245839Y275697D03*
Y269697D03*
Y272697D03*
Y266697D03*
X256886Y281877D03*
X258723Y275697D03*
Y272697D03*
Y269697D03*
Y266697D03*
X255286Y295209D03*
Y286941D03*
X256886Y284633D03*
Y297517D03*
X258386Y292453D03*
Y289697D03*
X255630Y292453D03*
Y289697D03*
X255286Y302581D03*
Y310849D03*
X256886Y300273D03*
X258386Y305337D03*
Y308093D03*
X255630Y305337D03*
Y308093D03*
X256886Y313157D03*
X248824Y320079D03*
X251580D03*
X249959Y328649D03*
Y325649D03*
Y322649D03*
X252715Y328649D03*
Y325649D03*
Y322649D03*
X244895Y321149D03*
Y327149D03*
Y324149D03*
X256886Y315913D03*
X257779Y321149D03*
Y324149D03*
Y327149D03*
X255124Y320079D03*
X243659Y341979D03*
X247681D03*
X250466Y342047D03*
X249959Y334649D03*
Y331649D03*
Y337649D03*
X252715Y334649D03*
Y331649D03*
Y337649D03*
X244895Y336149D03*
Y333149D03*
Y330149D03*
Y339149D03*
X245670Y343866D03*
X248302Y344859D03*
X253196Y342535D03*
X257779Y330149D03*
Y333149D03*
Y336149D03*
Y339149D03*
X258622Y341784D03*
X255952Y342535D03*
X245870Y346866D03*
X248510Y348629D03*
X252710Y348183D03*
X250427Y346623D03*
X252834Y345277D03*
X256358Y348190D03*
X258741Y346640D03*
X256334Y345277D03*
X268869Y250206D03*
X271252Y248656D03*
X267202Y248007D03*
X259455Y250223D03*
X264012Y249980D03*
X261372Y248217D03*
X271276Y251569D03*
X261580Y251987D03*
X274363Y257697D03*
X266543Y259197D03*
Y265197D03*
Y262197D03*
X269299Y259197D03*
X274363Y260697D03*
Y263697D03*
X269299Y265197D03*
Y262197D03*
X271658Y254311D03*
X266223Y254867D03*
X268988Y255062D03*
X266888Y252157D03*
X274414Y254311D03*
X261479Y257697D03*
Y260697D03*
Y263697D03*
X259416Y254799D03*
X262201Y254867D03*
X264212Y252980D03*
X271886Y268993D03*
X268886D03*
X265886D03*
X264386Y274057D03*
Y276813D03*
X267386Y274057D03*
X270386D03*
X273386D03*
X267386Y276813D03*
X270386D03*
X273386D03*
X262886Y281877D03*
X259886D03*
X265886D03*
X268886D03*
X271886D03*
X261479Y275697D03*
Y269697D03*
Y272697D03*
Y266697D03*
X262886Y284633D03*
X259886D03*
X261386Y289697D03*
Y292453D03*
X262886Y297517D03*
X264386Y292453D03*
Y289697D03*
X259886Y297517D03*
X265886Y284633D03*
X268886D03*
X271886D03*
X268886Y297517D03*
X265886D03*
X270386Y292453D03*
Y289697D03*
X267386D03*
Y292453D03*
X271886Y297517D03*
X273386Y292453D03*
Y289697D03*
X262886Y300273D03*
X259886D03*
X261386Y308093D03*
Y305337D03*
X264386D03*
Y308093D03*
X268886Y300273D03*
X265886D03*
X271886D03*
X267386Y308093D03*
Y305337D03*
X270386D03*
Y308093D03*
X273386Y305337D03*
Y308093D03*
X262886Y313157D03*
X259886D03*
X265886D03*
X268886D03*
X271886D03*
X262886Y315913D03*
X259886D03*
X265886D03*
X268886D03*
X271886D03*
X264386Y320977D03*
Y323733D03*
X270386Y320977D03*
X267386D03*
X273386D03*
X270386Y323733D03*
X273386D03*
X267386D03*
X271886Y328797D03*
X265599Y328649D03*
X268886Y328797D03*
X260535Y321149D03*
Y324149D03*
Y327149D03*
X273419Y339149D03*
Y336149D03*
X265599Y331649D03*
X268355D03*
Y334649D03*
X265599D03*
X268355Y337649D03*
X265599D03*
X260535Y330149D03*
Y333149D03*
Y336149D03*
Y339149D03*
X261387Y341979D03*
X265409D03*
X268194Y342047D03*
X263398Y343866D03*
X260722Y344689D03*
X273680Y342535D03*
X270924D03*
X266030Y344859D03*
X263598Y346866D03*
X260408Y348839D03*
X270438Y348183D03*
X274086Y348190D03*
X274062Y345277D03*
X270562D03*
X268155Y346623D03*
X266238Y348629D03*
X281941Y249980D03*
X277183Y250223D03*
X274900Y248663D03*
X274776Y251569D03*
X280886Y258417D03*
X283784Y258579D03*
X283716Y261364D03*
Y265386D03*
X284272Y255849D03*
X277886Y266237D03*
X280886D03*
X277119Y257697D03*
Y260697D03*
X279930Y254867D03*
X281941Y252980D03*
X279265Y252157D03*
X277144Y254799D03*
X287014Y256311D03*
X288577Y258618D03*
X286426Y260699D03*
X288603Y263175D03*
X285603Y263375D03*
X286426Y266051D03*
X283521Y268151D03*
X284272Y270821D03*
X277886Y268993D03*
X280886D03*
X274886D03*
X279386Y274057D03*
X276386D03*
X279386Y276813D03*
X276386D03*
X283716Y279092D03*
X283784Y276307D03*
X284272Y273577D03*
X274886Y281877D03*
X280886D03*
X277886D03*
X289927Y270415D03*
X288377Y268032D03*
X287014Y270439D03*
X288603Y280903D03*
X290366Y278263D03*
X289920Y274063D03*
X286596Y278471D03*
X288360Y276346D03*
X287014Y273939D03*
X285603Y281103D03*
X283716Y283114D03*
X283521Y285879D03*
X284272Y288549D03*
X280886Y284633D03*
X277886D03*
Y297517D03*
X280886D03*
X279386Y289697D03*
Y292453D03*
X274886Y284633D03*
Y297517D03*
X276386Y292453D03*
Y289697D03*
X283784Y294035D03*
X283716Y296820D03*
X284272Y291305D03*
X286426Y283779D03*
X289927Y288143D03*
X287014Y288167D03*
X288377Y285760D03*
X290366Y295991D03*
X289920Y291791D03*
X286596Y296199D03*
X288360Y294074D03*
X287014Y291667D03*
X277886Y300273D03*
X280886D03*
X279386Y308093D03*
Y305337D03*
X274886Y300273D03*
X276386Y305337D03*
Y308093D03*
X283716Y300842D03*
X283521Y303607D03*
X284272Y306277D03*
X283784Y311763D03*
X284272Y309033D03*
X280886Y313157D03*
X277886D03*
X274886D03*
X286426Y301507D03*
X285603Y298831D03*
X288603Y298631D03*
X289927Y305871D03*
X287014Y305895D03*
X288377Y303488D03*
X289920Y309519D03*
X287014Y309395D03*
X288360Y311802D03*
X280886Y315913D03*
X277886D03*
X274886D03*
X283716Y318570D03*
Y314548D03*
X283521Y321335D03*
X284272Y324005D03*
X279386Y320977D03*
X276386D03*
X279386Y323733D03*
X276386D03*
X284272Y326761D03*
X277886Y328797D03*
X280886D03*
X274886D03*
X286426Y319235D03*
X285603Y316559D03*
X288603Y316359D03*
X290366Y313719D03*
X286596Y313927D03*
X288377Y321216D03*
X289927Y323599D03*
X287014Y323623D03*
Y327123D03*
X289920Y327247D03*
X283784Y329491D03*
X283716Y332276D03*
Y336298D03*
X283521Y339063D03*
X277886Y331553D03*
X280886D03*
X274886D03*
X279386Y336617D03*
X276386D03*
X277886Y339149D03*
X283137Y341979D03*
X279115D03*
X276350Y341784D03*
X281126Y343866D03*
X278450Y344689D03*
X288360Y329530D03*
X286596Y331655D03*
X290366Y331447D03*
X288603Y334087D03*
X285603Y334287D03*
X288577Y339044D03*
X286426Y336963D03*
X287014Y341351D03*
X281126Y346866D03*
X276469Y346640D03*
X290576Y266365D03*
Y284093D03*
Y301821D03*
Y319549D03*
G54D186*
X665457Y209073D03*
X682779D03*
G54D187*
X658936Y359552D03*
X673897D03*
G54D49*
X70066Y560821D03*
X70220Y552972D03*
X70066Y576821D03*
Y568821D03*
X84989Y542702D03*
X77546Y560821D03*
X77700Y552972D03*
X77546Y576821D03*
Y568821D03*
X97605Y435943D03*
X90125D03*
X97605Y426943D03*
X90125D03*
X97627Y444943D03*
X90147D03*
X102240Y542702D03*
X92469D03*
X109720D03*
X240130Y418256D03*
X232650D03*
X240195Y434135D03*
X232715D03*
X240195Y426135D03*
X232715D03*
X250678Y608063D03*
X258158D03*
X250703Y623716D03*
X258183D03*
X250678Y615871D03*
X258158D03*
X313297Y546404D03*
X320777D03*
X321848Y571803D03*
X335123Y10530D03*
X327643D03*
X335123Y26530D03*
X327643D03*
X335123Y18530D03*
X327643D03*
X329328Y571803D03*
X351910Y331176D03*
X344430D03*
X343632Y613013D03*
X351112D03*
X343632Y605013D03*
X351112D03*
X343632Y621013D03*
X351112D03*
X417881Y412830D03*
X410401D03*
X417881Y420830D03*
X410401D03*
X417881Y436830D03*
X410401D03*
X417881Y428830D03*
X410401D03*
X417881Y444830D03*
X410401D03*
X410551Y452830D03*
X403071D03*
X410551Y460574D03*
X403071D03*
X409942Y631847D03*
X417422D03*
X463867Y587570D03*
X456387D03*
X555998Y222533D03*
X563478D03*
X617872Y526967D03*
X610392D03*
X638602Y317360D03*
X638592Y324998D03*
X646082Y317360D03*
X646072Y324998D03*
X669690Y193115D03*
X666118Y304444D03*
X658638D03*
X677170Y193115D03*
X695683Y562356D03*
X695668Y578380D03*
Y570380D03*
Y586380D03*
X710585Y543908D03*
X703105D03*
X703163Y562356D03*
X703148Y578380D03*
Y570380D03*
Y586380D03*
X757490Y105176D03*
X750010D03*
X758937Y577664D03*
X758928Y585787D03*
X766417Y577664D03*
X766408Y585787D03*
G54D94*
X164920Y259605D03*
Y337241D03*
X291778Y259605D03*
Y337241D03*
G54D76*
X143617Y453259D03*
Y450700D03*
Y448141D03*
Y445582D03*
X258863Y632992D03*
Y635551D03*
Y638110D03*
Y640669D03*
G54D85*
X163195Y653433D03*
X179731D03*
X629669Y559245D03*
X646205D03*
G54D196*
X723275Y155655D03*
Y234461D03*
G54D178*
X605796Y174845D03*
G54D67*
X125142Y406358D03*
X642452Y304580D03*
G54D169*
X553895Y239205D03*
Y240780D03*
Y242354D03*
Y243929D03*
Y245504D03*
Y247079D03*
Y248654D03*
Y250228D03*
Y251803D03*
Y253378D03*
Y254953D03*
Y256528D03*
Y258102D03*
Y259677D03*
Y261252D03*
Y262827D03*
Y264402D03*
Y265976D03*
Y267551D03*
X588865Y250228D03*
Y248654D03*
Y247079D03*
Y245504D03*
Y243929D03*
Y242354D03*
Y240780D03*
Y239205D03*
Y265976D03*
Y264402D03*
Y262827D03*
Y261252D03*
Y259677D03*
Y258102D03*
Y256528D03*
Y254953D03*
Y253378D03*
Y251803D03*
Y267551D03*
G54D58*
X84103Y507111D03*
X158165Y25472D03*
X179544Y419427D03*
X274972Y11822D03*
X380699Y544526D03*
X406150Y511910D03*
X446334Y544449D03*
G54D59*
X88150Y575352D03*
X97150D03*
X106150D03*
G54D197*
X727607Y564179D03*
Y582179D03*
Y573179D03*
G54D86*
X164993Y705542D03*
Y700542D03*
Y695542D03*
Y710542D03*
G54D179*
X609300Y534523D03*
X618946D03*
X609300Y542003D03*
Y538263D03*
X618946Y542003D03*
X682880Y547065D03*
Y539585D03*
X692526D03*
Y543325D03*
Y547065D03*
G54D188*
X688977Y105315D03*
Y719488D03*
G54D95*
X180546Y432984D03*
X275974Y25379D03*
X310327Y609214D03*
X402920Y609350D03*
G54D77*
X149540Y703042D03*
G54D68*
X136097Y449421D03*
G54D69*
X120072Y477093D03*
Y484573D03*
X132152Y497692D03*
Y505172D03*
X223314Y62441D03*
Y54961D03*
X231314Y62441D03*
Y54961D03*
X239314Y62441D03*
Y54961D03*
X247314Y62441D03*
Y54961D03*
X252243Y640444D03*
Y632964D03*
X374786Y508277D03*
Y515757D03*
X387362Y548675D03*
Y541195D03*
X424904Y598298D03*
Y590818D03*
X443704Y110425D03*
X435937Y110553D03*
X443704Y117905D03*
X435937Y118033D03*
X459174Y110350D03*
X451401Y110425D03*
X459174Y117830D03*
X451401Y117905D03*
X554740Y473916D03*
Y481396D03*
X571175Y199691D03*
Y207171D03*
X579175Y199691D03*
Y207171D03*
G54D78*
X160111Y58771D03*
X311329Y622771D03*
X403922Y622907D03*
X620366Y294675D03*
G54D189*
X683806Y158536D03*
Y168182D03*
X683844Y237342D03*
Y246988D03*
X691286Y158536D03*
X687546D03*
Y168182D03*
X691286D03*
X691324Y237342D03*
X687584D03*
Y246988D03*
X691324D03*
G54D87*
X176939Y29820D03*
X174380D03*
X171820D03*
X169261D03*
Y46284D03*
G54D96*
X177593Y438791D03*
X179562D03*
Y427177D03*
X177593D03*
X181530Y438791D03*
X183499D03*
Y427177D03*
X181530D03*
X273021Y31186D03*
Y19572D03*
X274990Y31186D03*
X276958D03*
X278927D03*
Y19572D03*
X276958D03*
X274990D03*
X313280Y603407D03*
X311311D03*
X309343D03*
X307374D03*
Y615021D03*
X309343D03*
X311311D03*
X313280D03*
X399967Y603543D03*
Y615157D03*
X405873Y603543D03*
X403904D03*
X401936D03*
Y615157D03*
X403904D03*
X405873D03*
G54D198*
X749907Y573179D03*
G54D199*
G01X490760Y154771D02*
Y154778D01*
X490460Y155078D01*
X482093D01*
G01X533483Y177449D02*
X536419Y180385D01*
Y185782D01*
X536463Y185826D01*
G54D79*
X163583Y82480D03*
X161221D03*
X158859D03*
X162402Y114763D03*
X160040D03*
X180119Y82480D03*
X177757D03*
X175394D03*
X173032D03*
X170670D03*
X168308D03*
X165946D03*
X178938Y114763D03*
X176576D03*
X174213D03*
X171851D03*
X169489D03*
X167127D03*
X164765D03*
X194292Y82480D03*
X191930D03*
X189568D03*
X187205D03*
X184843D03*
X182481D03*
X195473Y114763D03*
X193111D03*
X190749D03*
X188387D03*
X186024D03*
X183662D03*
X181300D03*
X210827Y82480D03*
X208465D03*
X206103D03*
X203741D03*
X201379D03*
X199016D03*
X196654D03*
X209646Y114763D03*
X207284D03*
X204922D03*
X202560D03*
X200198D03*
X197835D03*
X227363Y82480D03*
X225001D03*
X222639D03*
X220276D03*
X217914D03*
X215552D03*
X213190D03*
X226182Y114763D03*
X223820D03*
X221457D03*
X219095D03*
X216733D03*
X214371D03*
X212009D03*
X241536Y82480D03*
X239174D03*
X236812D03*
X234450D03*
X232087D03*
X229725D03*
X242717Y114763D03*
X240355D03*
X237993D03*
X235631D03*
X233268D03*
X230906D03*
X228544D03*
X258072Y82480D03*
X255709D03*
X253347D03*
X259253Y114763D03*
X256891D03*
X254528D03*
X274607Y82480D03*
X272245D03*
X269883D03*
X267520D03*
X265158D03*
X262796D03*
X260434D03*
X273426Y114763D03*
X271064D03*
X268702D03*
X266339D03*
X263977D03*
X261615D03*
X288780Y82480D03*
X286418D03*
X284056D03*
X281694D03*
X279331D03*
X276969D03*
X289961Y114763D03*
X287599D03*
X285237D03*
X282875D03*
X280513D03*
X278150D03*
X275788D03*
X305316Y82480D03*
X302953D03*
X300591D03*
X298229D03*
X295867D03*
X293505D03*
X291142D03*
X306497Y114763D03*
X304135D03*
X301772D03*
X299410D03*
X297048D03*
X294686D03*
X292324D03*
X321851Y82480D03*
X319489D03*
X317127D03*
X314765D03*
X312402D03*
X310040D03*
X307678D03*
X320670Y114763D03*
X318308D03*
X315946D03*
X313583D03*
X311221D03*
X308859D03*
X336024Y82480D03*
X333662D03*
X331300D03*
X328938D03*
X326576D03*
X324213D03*
X337205Y114763D03*
X334843D03*
X332481D03*
X330119D03*
X327757D03*
X325394D03*
X323032D03*
X352560Y82480D03*
X350198D03*
X347835D03*
X345473D03*
X343111D03*
X340749D03*
X338387D03*
X353741Y114763D03*
X351379D03*
X349016D03*
X346654D03*
X344292D03*
X341930D03*
X339568D03*
X369095Y82480D03*
X366733D03*
X364371D03*
X362009D03*
X359646D03*
X357284D03*
X354922D03*
X367914Y114763D03*
X365552D03*
X363190D03*
X360827D03*
X358465D03*
X356103D03*
X383268Y82480D03*
X380906D03*
X378544D03*
X376182D03*
X373820D03*
X371457D03*
X384450Y114763D03*
X382087D03*
X379725D03*
X377363D03*
X375001D03*
X372639D03*
X370276D03*
X399804Y82480D03*
X397442D03*
X395079D03*
X392717D03*
X390355D03*
X387993D03*
X385631D03*
X400985Y114763D03*
X398623D03*
X396261D03*
X393898D03*
X391536D03*
X389174D03*
X386812D03*
X406891Y82480D03*
X404528D03*
X402166D03*
X408072Y114763D03*
X405709D03*
X403347D03*
G54D97*
X174739Y430031D03*
Y432000D03*
Y433968D03*
Y435937D03*
X186353D03*
Y433968D03*
Y432000D03*
Y430031D03*
X270167Y22426D03*
Y24395D03*
Y26363D03*
Y28332D03*
X281781D03*
Y26363D03*
Y24395D03*
Y22426D03*
X304520Y606261D03*
Y608230D03*
Y610198D03*
Y612167D03*
X316134D03*
Y610198D03*
Y608230D03*
Y606261D03*
X397113Y606397D03*
Y608366D03*
Y610334D03*
Y612303D03*
X408727D03*
Y610334D03*
Y608366D03*
Y606397D03*
G54D88*
X174380Y46284D03*
G54D89*
X173100Y40352D03*
G54D98*
X173892Y482546D03*
X181470Y485105D03*
Y482546D03*
X173892Y487664D03*
X181470D03*
X506279Y209758D03*
Y214876D03*
X498701Y209758D03*
Y212317D03*
Y214876D03*
X506356Y219563D03*
Y224681D03*
X498778Y219563D03*
Y222122D03*
Y224681D03*
G54D99*
X175463Y609933D03*
X633937Y602745D03*
M02*
